FILE_TYPE = EXPANDEDNETLIST;
{ Packager-XL run on 24-Aug-2023 AT 15:36:33 CONSTRAINTS_VIEW_GENERATED}
NET_NAME
'ADC128_A0'
 '@S9S_MB_2U_LIB.S9S_MB_2U(SCH_1):ADC128_A0':
 C_SIGNAL='@s9s_mb_2u_lib.s9s_mb_2u(sch_1):adc128_a0';
NODE_NAME     U269 7
 '@S9S_MB_2U_LIB.S9S_MB_2U(SCH_1):PAGE239_I103@PURE_QUANTA.ADC128D818CIMTXNOPB(CHIPS)':
 'A0': CDS_PINID='A0';
NODE_NAME     R3670 1
 '@S9S_MB_2U_LIB.S9S_MB_2U(SCH_1):PAGE239_I227@PURE_QUANTA.Q_RES(CHIPS)':
 'A': CDS_PINID='A';
NODE_NAME     R3669 2
 '@S9S_MB_2U_LIB.S9S_MB_2U(SCH_1):PAGE239_I228@PURE_QUANTA.Q_RES(CHIPS)':
 'B': CDS_PINID='B';
NET_NAME
'ADC128_A1'
 '@S9S_MB_2U_LIB.S9S_MB_2U(SCH_1):ADC128_A1':
 C_SIGNAL='@s9s_mb_2u_lib.s9s_mb_2u(sch_1):adc128_a1';
NODE_NAME     U269 8
 '@S9S_MB_2U_LIB.S9S_MB_2U(SCH_1):PAGE239_I103@PURE_QUANTA.ADC128D818CIMTXNOPB(CHIPS)':
 'A1': CDS_PINID='A1';
NODE_NAME     R3668 1
 '@S9S_MB_2U_LIB.S9S_MB_2U(SCH_1):PAGE239_I223@PURE_QUANTA.Q_RES(CHIPS)':
 'A': CDS_PINID='A';
NODE_NAME     R3667 2
 '@S9S_MB_2U_LIB.S9S_MB_2U(SCH_1):PAGE239_I224@PURE_QUANTA.Q_RES(CHIPS)':
 'B': CDS_PINID='B';
NET_NAME
'ADC128_VREF'
 '@S9S_MB_2U_LIB.S9S_MB_2U(SCH_1):ADC128_VREF':
 C_SIGNAL='@s9s_mb_2u_lib.s9s_mb_2u(sch_1):adc128_vref';
NODE_NAME     U269 1
 '@S9S_MB_2U_LIB.S9S_MB_2U(SCH_1):PAGE239_I103@PURE_QUANTA.ADC128D818CIMTXNOPB(CHIPS)':
 'VREF': CDS_PINID='VREF';
NODE_NAME     R3689 2
 '@S9S_MB_2U_LIB.S9S_MB_2U(SCH_1):PAGE239_I129@PURE_QUANTA.Q_RES(CHIPS)':
 'B': CDS_PINID='B';
NODE_NAME     R3690 1
 '@S9S_MB_2U_LIB.S9S_MB_2U(SCH_1):PAGE239_I131@PURE_QUANTA.Q_RES(CHIPS)':
 'A': CDS_PINID='A';
NET_NAME
'AGND_HSC'
 '@S9S_MB_2U_LIB.S9S_MB_2U(SCH_1):AGND_HSC':
 C_SIGNAL='@s9s_mb_2u_lib.s9s_mb_2u(sch_1):agnd_hsc',
 CDS_GLOBAL_NET='TRUE';
NODE_NAME     PC2183 2
 '@S9S_MB_2U_LIB.S9S_MB_2U(SCH_1):PAGE301_I2@PURE_QUANTA.Q_CAP(CHIPS)':
 'B': CDS_PINID='B';
NODE_NAME     PR3915 2
 '@S9S_MB_2U_LIB.S9S_MB_2U(SCH_1):PAGE301_I12@PURE_QUANTA.Q_RES(CHIPS)':
 'B': CDS_PINID='B';
NODE_NAME     PR1101 2
 '@S9S_MB_2U_LIB.S9S_MB_2U(SCH_1):PAGE301_I13@PURE_QUANTA.Q_RES(CHIPS)':
 'B': CDS_PINID='B';
NODE_NAME     PC2347 2
 '@S9S_MB_2U_LIB.S9S_MB_2U(SCH_1):PAGE301_I29@PURE_QUANTA.Q_CAP(CHIPS)':
 'B': CDS_PINID='B';
NODE_NAME     PC2181 2
 '@S9S_MB_2U_LIB.S9S_MB_2U(SCH_1):PAGE301_I4@PURE_QUANTA.Q_CAP(CHIPS)':
 'B': CDS_PINID='B';
NODE_NAME     PC1525 2
 '@S9S_MB_2U_LIB.S9S_MB_2U(SCH_1):PAGE301_I20@PURE_QUANTA.Q_CAP(CHIPS)':
 'B': CDS_PINID='B';
NODE_NAME     PC2349 2
 '@S9S_MB_2U_LIB.S9S_MB_2U(SCH_1):PAGE325_I11@PURE_QUANTA.Q_CAP(CHIPS)':
 'B': CDS_PINID='B';
NODE_NAME     PR3987 2
 '@S9S_MB_2U_LIB.S9S_MB_2U(SCH_1):PAGE325_I12@PURE_QUANTA.Q_RES(CHIPS)':
 'B': CDS_PINID='B';
NODE_NAME     PR3991 2
 '@S9S_MB_2U_LIB.S9S_MB_2U(SCH_1):PAGE325_I13@PURE_QUANTA.Q_RES(CHIPS)':
 'B': CDS_PINID='B';
NODE_NAME     PR3990 2
 '@S9S_MB_2U_LIB.S9S_MB_2U(SCH_1):PAGE325_I34@PURE_QUANTA.Q_RES(CHIPS)':
 'B': CDS_PINID='B';
NODE_NAME     PC2348 2
 '@S9S_MB_2U_LIB.S9S_MB_2U(SCH_1):PAGE301_I11@PURE_QUANTA.Q_CAP(CHIPS)':
 'B': CDS_PINID='B';
NODE_NAME     PR3918 2
 '@S9S_MB_2U_LIB.S9S_MB_2U(SCH_1):PAGE301_I34@PURE_QUANTA.Q_RES(CHIPS)':
 'B': CDS_PINID='B';
NODE_NAME     PU297 20
 '@S9S_MB_2U_LIB.S9S_MB_2U(SCH_1):PAGE325_I17@PURE_QUANTA.MP5991GLUZ(CHIPS)':
 'GND': CDS_PINID='GND';
NODE_NAME     PR3912 1
 '@S9S_MB_2U_LIB.S9S_MB_2U(SCH_1):PAGE301_I15@PURE_QUANTA.Q_RES(CHIPS)':
 'A': CDS_PINID='A';
NODE_NAME     PU289 18
 '@S9S_MB_2U_LIB.S9S_MB_2U(SCH_1):PAGE303_I56@PURE_QUANTA.MP5990GMA1111Z(CHIPS)':
 'GND1': CDS_PINID='GND1';
NODE_NAME     PU289 44
 '@S9S_MB_2U_LIB.S9S_MB_2U(SCH_1):PAGE303_I56@PURE_QUANTA.MP5990GMA1111Z(CHIPS)':
 'GND2': CDS_PINID='GND2';
NODE_NAME     PR3932 2
 '@S9S_MB_2U_LIB.S9S_MB_2U(SCH_1):PAGE303_I59@PURE_QUANTA.Q_RES(CHIPS)':
 'B': CDS_PINID='B';
NODE_NAME     PC2223 2
 '@S9S_MB_2U_LIB.S9S_MB_2U(SCH_1):PAGE325_I4@PURE_QUANTA.Q_CAP(CHIPS)':
 'B': CDS_PINID='B';
NODE_NAME     PR3986 2
 '@S9S_MB_2U_LIB.S9S_MB_2U(SCH_1):PAGE325_I30@PURE_QUANTA.Q_RES(CHIPS)':
 'B': CDS_PINID='B';
NODE_NAME     PU296 20
 '@S9S_MB_2U_LIB.S9S_MB_2U(SCH_1):PAGE325_I35@PURE_QUANTA.MP5991GLUZ(CHIPS)':
 'GND': CDS_PINID='GND';
NODE_NAME     PC2190 2
 '@S9S_MB_2U_LIB.S9S_MB_2U(SCH_1):PAGE303_I75@PURE_QUANTA.Q_CAP(CHIPS)':
 'B': CDS_PINID='B';
NODE_NAME     PR3914 2
 '@S9S_MB_2U_LIB.S9S_MB_2U(SCH_1):PAGE301_I30@PURE_QUANTA.Q_RES(CHIPS)':
 'B': CDS_PINID='B';
NODE_NAME     PU287 20
 '@S9S_MB_2U_LIB.S9S_MB_2U(SCH_1):PAGE301_I35@PURE_QUANTA.MP5991GLUZ(CHIPS)':
 'GND': CDS_PINID='GND';
NODE_NAME     PC2227 2
 '@S9S_MB_2U_LIB.S9S_MB_2U(SCH_1):PAGE325_I38@PURE_QUANTA.Q_CAP(CHIPS)':
 'B': CDS_PINID='B';
NODE_NAME     PU288 20
 '@S9S_MB_2U_LIB.S9S_MB_2U(SCH_1):PAGE301_I14@PURE_QUANTA.MP5991GLUZ(CHIPS)':
 'GND': CDS_PINID='GND';
NODE_NAME     PR1134 1
 '@S9S_MB_2U_LIB.S9S_MB_2U(SCH_1):PAGE301_I32@PURE_QUANTA.Q_RES(CHIPS)':
 'A': CDS_PINID='A';
NODE_NAME     PR3927 2
 '@S9S_MB_2U_LIB.S9S_MB_2U(SCH_1):PAGE303_I40@PURE_QUANTA.Q_RES(CHIPS)':
 'B': CDS_PINID='B';
NODE_NAME     PC2189 2
 '@S9S_MB_2U_LIB.S9S_MB_2U(SCH_1):PAGE303_I45@PURE_QUANTA.Q_CAP(CHIPS)':
 'B': CDS_PINID='B';
NODE_NAME     R1117 2
 '@S9S_MB_2U_LIB.S9S_MB_2U(SCH_1):PAGE303_I61@PURE_QUANTA.Q_RES(CHIPS)':
 'B': CDS_PINID='B';
NODE_NAME     PC2191 2
 '@S9S_MB_2U_LIB.S9S_MB_2U(SCH_1):PAGE303_I69@PURE_QUANTA.Q_CAP(CHIPS)':
 'B': CDS_PINID='B';
NODE_NAME     PC2192 2
 '@S9S_MB_2U_LIB.S9S_MB_2U(SCH_1):PAGE303_I77@PURE_QUANTA.Q_CAP(CHIPS)':
 'B': CDS_PINID='B';
NODE_NAME     PC3272 2
 '@S9S_MB_2U_LIB.S9S_MB_2U(SCH_1):PAGE325_I19@PURE_QUANTA.Q_CAP(CHIPS)':
 'B': CDS_PINID='B';
NODE_NAME     PC2224 2
 '@S9S_MB_2U_LIB.S9S_MB_2U(SCH_1):PAGE325_I23@PURE_QUANTA.Q_CAP(CHIPS)':
 'B': CDS_PINID='B';
NODE_NAME     PC2350 2
 '@S9S_MB_2U_LIB.S9S_MB_2U(SCH_1):PAGE325_I29@PURE_QUANTA.Q_CAP(CHIPS)':
 'B': CDS_PINID='B';
NODE_NAME     PR3982 1
 '@S9S_MB_2U_LIB.S9S_MB_2U(SCH_1):PAGE325_I32@PURE_QUANTA.Q_RES(CHIPS)':
 'A': CDS_PINID='A';
NODE_NAME     PC2186 2
 '@S9S_MB_2U_LIB.S9S_MB_2U(SCH_1):PAGE303_I14@PURE_QUANTA.Q_CAP(CHIPS)':
 'B': CDS_PINID='B';
NODE_NAME     PC2187 2
 '@S9S_MB_2U_LIB.S9S_MB_2U(SCH_1):PAGE303_I23@PURE_QUANTA.Q_CAP(CHIPS)':
 'B': CDS_PINID='B';
NODE_NAME     C2179 2
 '@S9S_MB_2U_LIB.S9S_MB_2U(SCH_1):PAGE303_I29@PURE_QUANTA.Q_CAP(CHIPS)':
 'B': CDS_PINID='B';
NODE_NAME     PR3930 1
 '@S9S_MB_2U_LIB.S9S_MB_2U(SCH_1):PAGE303_I32@PURE_QUANTA.Q_RES(CHIPS)':
 'A': CDS_PINID='A';
NODE_NAME     PC2103 2
 '@S9S_MB_2U_LIB.S9S_MB_2U(SCH_1):PAGE303_I35@PURE_QUANTA.Q_CAP(CHIPS)':
 'B': CDS_PINID='B';
NODE_NAME     PR3002 2
 '@S9S_MB_2U_LIB.S9S_MB_2U(SCH_1):PAGE303_I54@PURE_QUANTA.Q_RES(CHIPS)':
 'B': CDS_PINID='B';
NODE_NAME     PR1131 2
 '@S9S_MB_2U_LIB.S9S_MB_2U(SCH_1):PAGE303_I58@PURE_QUANTA.Q_RES(CHIPS)':
 'B': CDS_PINID='B';
NODE_NAME     PR3935 2
 '@S9S_MB_2U_LIB.S9S_MB_2U(SCH_1):PAGE303_I79@PURE_QUANTA.Q_RES(CHIPS)':
 'B': CDS_PINID='B';
NODE_NAME     PR3937 2
 '@S9S_MB_2U_LIB.S9S_MB_2U(SCH_1):PAGE303_I84@PURE_QUANTA.Q_RES(CHIPS)':
 'B': CDS_PINID='B';
NODE_NAME     PC2193 2
 '@S9S_MB_2U_LIB.S9S_MB_2U(SCH_1):PAGE303_I89@PURE_QUANTA.Q_CAP(CHIPS)':
 'B': CDS_PINID='B';
NODE_NAME     PR1133 2
 '@S9S_MB_2U_LIB.S9S_MB_2U(SCH_1):PAGE303_I91@PURE_QUANTA.Q_RES(CHIPS)':
 'B': CDS_PINID='B';
NODE_NAME     PC2182 2
 '@S9S_MB_2U_LIB.S9S_MB_2U(SCH_1):PAGE301_I23@PURE_QUANTA.Q_CAP(CHIPS)':
 'B': CDS_PINID='B';
NODE_NAME     PC2185 2
 '@S9S_MB_2U_LIB.S9S_MB_2U(SCH_1):PAGE301_I37@PURE_QUANTA.Q_CAP(CHIPS)':
 'B': CDS_PINID='B';
NODE_NAME     PC2184 2
 '@S9S_MB_2U_LIB.S9S_MB_2U(SCH_1):PAGE301_I47@PURE_QUANTA.Q_CAP(CHIPS)':
 'B': CDS_PINID='B';
NODE_NAME     PC2225 2
 '@S9S_MB_2U_LIB.S9S_MB_2U(SCH_1):PAGE325_I2@PURE_QUANTA.Q_CAP(CHIPS)':
 'B': CDS_PINID='B';
NODE_NAME     PR3984 1
 '@S9S_MB_2U_LIB.S9S_MB_2U(SCH_1):PAGE325_I14@PURE_QUANTA.Q_RES(CHIPS)':
 'A': CDS_PINID='A';
NODE_NAME     PC2226 2
 '@S9S_MB_2U_LIB.S9S_MB_2U(SCH_1):PAGE325_I48@PURE_QUANTA.Q_CAP(CHIPS)':
 'B': CDS_PINID='B';
NET_NAME
'A_HSC_HIGH'
 '@S9S_MB_2U_LIB.S9S_MB_2U(SCH_1):A_HSC_HIGH':
 C_SIGNAL='@s9s_mb_2u_lib.s9s_mb_2u(sch_1):a_hsc_high';
NODE_NAME     R4670 1
 '@S9S_MB_2U_LIB.S9S_MB_2U(SCH_1):PAGE326_I24@PURE_QUANTA.Q_RES(CHIPS)':
 'A': CDS_PINID='A';
NODE_NAME     R4669 2
 '@S9S_MB_2U_LIB.S9S_MB_2U(SCH_1):PAGE326_I25@PURE_QUANTA.Q_RES(CHIPS)':
 'B': CDS_PINID='B';
NODE_NAME     U369 4
 '@S9S_MB_2U_LIB.S9S_MB_2U(SCH_1):PAGE326_I30@PURE_QUANTA.TPS3700DDCR(CHIPS)':
 'INB-': CDS_PINID='\inb-\';
NET_NAME
'A_HSC_INAP'
 '@S9S_MB_2U_LIB.S9S_MB_2U(SCH_1):A_HSC_INAP':
 C_SIGNAL='@s9s_mb_2u_lib.s9s_mb_2u(sch_1):a_hsc_inap';
NODE_NAME     R2238 1
 '@S9S_MB_2U_LIB.S9S_MB_2U(SCH_1):PAGE326_I2@PURE_QUANTA.Q_RES(CHIPS)':
 'A': CDS_PINID='A';
NODE_NAME     U205 3
 '@S9S_MB_2U_LIB.S9S_MB_2U(SCH_1):PAGE326_I5@PURE_QUANTA.TPS3700DDCR(CHIPS)':
 'INA+': CDS_PINID='\ina+\';
NODE_NAME     R2236 2
 '@S9S_MB_2U_LIB.S9S_MB_2U(SCH_1):PAGE326_I7@PURE_QUANTA.Q_RES(CHIPS)':
 'B': CDS_PINID='B';
NET_NAME
'A_HSC_LOW'
 '@S9S_MB_2U_LIB.S9S_MB_2U(SCH_1):A_HSC_LOW':
 C_SIGNAL='@s9s_mb_2u_lib.s9s_mb_2u(sch_1):a_hsc_low';
NODE_NAME     R4668 1
 '@S9S_MB_2U_LIB.S9S_MB_2U(SCH_1):PAGE326_I13@PURE_QUANTA.Q_RES(CHIPS)':
 'A': CDS_PINID='A';
NODE_NAME     R4667 2
 '@S9S_MB_2U_LIB.S9S_MB_2U(SCH_1):PAGE326_I14@PURE_QUANTA.Q_RES(CHIPS)':
 'B': CDS_PINID='B';
NODE_NAME     U369 3
 '@S9S_MB_2U_LIB.S9S_MB_2U(SCH_1):PAGE326_I30@PURE_QUANTA.TPS3700DDCR(CHIPS)':
 'INA+': CDS_PINID='\ina+\';
NET_NAME
'A_HSC_LOW_DRAIN'
 '@S9S_MB_2U_LIB.S9S_MB_2U(SCH_1):A_HSC_LOW_DRAIN':
 C_SIGNAL='@s9s_mb_2u_lib.s9s_mb_2u(sch_1):a_hsc_low_drain';
NODE_NAME     U329 D
 '@S9S_MB_2U_LIB.S9S_MB_2U(SCH_1):PAGE326_I46@PURE_QUANTA.MOSFET_NCH_GDS_ESD_PROTECTED(CHIPS)':
 'D': CDS_PINID='D';
NODE_NAME     R4652 1
 '@S9S_MB_2U_LIB.S9S_MB_2U(SCH_1):PAGE326_I48@PURE_QUANTA.Q_RES(CHIPS)':
 'A': CDS_PINID='A';
NET_NAME
'A_HSC_LOW_GATE'
 '@S9S_MB_2U_LIB.S9S_MB_2U(SCH_1):A_HSC_LOW_GATE':
 C_SIGNAL='@s9s_mb_2u_lib.s9s_mb_2u(sch_1):a_hsc_low_gate';
NODE_NAME     U369 1
 '@S9S_MB_2U_LIB.S9S_MB_2U(SCH_1):PAGE326_I30@PURE_QUANTA.TPS3700DDCR(CHIPS)':
 'OUTA': CDS_PINID='OUTA';
NODE_NAME     R4673 1
 '@S9S_MB_2U_LIB.S9S_MB_2U(SCH_1):PAGE326_I44@PURE_QUANTA.Q_RES(CHIPS)':
 'A': CDS_PINID='A';
NODE_NAME     U329 G
 '@S9S_MB_2U_LIB.S9S_MB_2U(SCH_1):PAGE326_I46@PURE_QUANTA.MOSFET_NCH_GDS_ESD_PROTECTED(CHIPS)':
 'G': CDS_PINID='G';
NODE_NAME     R4672 2
 '@S9S_MB_2U_LIB.S9S_MB_2U(SCH_1):PAGE326_I53@PURE_QUANTA.Q_RES(CHIPS)':
 'B': CDS_PINID='B';
NODE_NAME     R4794 2
 '@S9S_MB_2U_LIB.S9S_MB_2U(SCH_1):PAGE326_I72@PURE_QUANTA.Q_RES(CHIPS)':
 'B': CDS_PINID='B';
NODE_NAME     R4797 2
 '@S9S_MB_2U_LIB.S9S_MB_2U(SCH_1):PAGE326_I80@PURE_QUANTA.Q_RES(CHIPS)':
 'B': CDS_PINID='B';
NET_NAME
'A_P12V_STBY_ADR_TRIGGER'
 '@S9S_MB_2U_LIB.S9S_MB_2U(SCH_1):A_P12V_STBY_ADR_TRIGGER':
 C_SIGNAL='@s9s_mb_2u_lib.s9s_mb_2u(sch_1):a_p12v_stby_adr_trigger';
NODE_NAME     R2219 2
 '@S9S_MB_2U_LIB.S9S_MB_2U(SCH_1):PAGE326_I100@PURE_QUANTA.Q_RES(CHIPS)':
 'B': CDS_PINID='B';
NODE_NAME     R2227 1
 '@S9S_MB_2U_LIB.S9S_MB_2U(SCH_1):PAGE326_I101@PURE_QUANTA.Q_RES(CHIPS)':
 'A': CDS_PINID='A';
NODE_NAME     U206 3
 '@S9S_MB_2U_LIB.S9S_MB_2U(SCH_1):PAGE326_I102@PURE_QUANTA.LT6700CS61TRPBF(CHIPS)':
 'INA+': CDS_PINID='\ina+\';
NET_NAME
'A_P12V_STBY_FPH_GATE'
 '@S9S_MB_2U_LIB.S9S_MB_2U(SCH_1):A_P12V_STBY_FPH_GATE':
 C_SIGNAL='@s9s_mb_2u_lib.s9s_mb_2u(sch_1):a_p12v_stby_fph_gate';
NODE_NAME     U325 G
 '@S9S_MB_2U_LIB.S9S_MB_2U(SCH_1):PAGE326_I38@PURE_QUANTA.MOSFET_N(CHIPS)':
 'GATE': CDS_PINID='GATE';
NODE_NAME     R2230 2
 '@S9S_MB_2U_LIB.S9S_MB_2U(SCH_1):PAGE326_I39@PURE_QUANTA.Q_RES(CHIPS)':
 'B': CDS_PINID='B';
NODE_NAME     U206 6
 '@S9S_MB_2U_LIB.S9S_MB_2U(SCH_1):PAGE326_I102@PURE_QUANTA.LT6700CS61TRPBF(CHIPS)':
 'OUTB': CDS_PINID='OUTB';
NET_NAME
'A_P12V_STBY_FP_TRIGGER'
 '@S9S_MB_2U_LIB.S9S_MB_2U(SCH_1):A_P12V_STBY_FP_TRIGGER':
 C_SIGNAL='@s9s_mb_2u_lib.s9s_mb_2u(sch_1):a_p12v_stby_fp_trigger';
NODE_NAME     R2222 1
 '@S9S_MB_2U_LIB.S9S_MB_2U(SCH_1):PAGE326_I17@PURE_QUANTA.Q_RES(CHIPS)':
 'A': CDS_PINID='A';
NODE_NAME     R2221 2
 '@S9S_MB_2U_LIB.S9S_MB_2U(SCH_1):PAGE326_I20@PURE_QUANTA.Q_RES(CHIPS)':
 'B': CDS_PINID='B';
NODE_NAME     U206 4
 '@S9S_MB_2U_LIB.S9S_MB_2U(SCH_1):PAGE326_I102@PURE_QUANTA.LT6700CS61TRPBF(CHIPS)':
 'INB-': CDS_PINID='\inb-\';
NET_NAME
'BIC_MONITER'
 '@S9S_MB_2U_LIB.S9S_MB_2U(SCH_1):BIC_MONITER':
 C_SIGNAL='@s9s_mb_2u_lib.s9s_mb_2u(sch_1):bic_moniter';
NODE_NAME     Q67 2
 '@S9S_MB_2U_LIB.S9S_MB_2U(SCH_1):PAGE145_I33@PURE_QUANTA.MOSFET_NCH_DUAL(CHIPS)':
 'G1': CDS_PINID='G1';
NODE_NAME     R2831 1
 '@S9S_MB_2U_LIB.S9S_MB_2U(SCH_1):PAGE145_I56@PURE_QUANTA.Q_RES(CHIPS)':
 'A': CDS_PINID='A';
NODE_NAME     R2830 2
 '@S9S_MB_2U_LIB.S9S_MB_2U(SCH_1):PAGE145_I68@PURE_QUANTA.Q_RES(CHIPS)':
 'B': CDS_PINID='B';
NODE_NAME     J109 A3
 '@S9S_MB_2U_LIB.S9S_MB_2U(SCH_1):PAGE319_I53@PURE_QUANTA.CONN112_10137002101LF(CHIPS)':
 'A3': CDS_PINID='A3';
NET_NAME
'BIC_MONITER_ISO'
 '@S9S_MB_2U_LIB.S9S_MB_2U(SCH_1):BIC_MONITER_ISO':
 C_SIGNAL='@s9s_mb_2u_lib.s9s_mb_2u(sch_1):bic_moniter_iso';
NODE_NAME     Q67 3
 '@S9S_MB_2U_LIB.S9S_MB_2U(SCH_1):PAGE145_I82@PURE_QUANTA.MOSFET_NCH_DUAL(CHIPS)':
 'D2': CDS_PINID='D2';
NODE_NAME     R2920 2
 '@S9S_MB_2U_LIB.S9S_MB_2U(SCH_1):PAGE145_I84@PURE_QUANTA.Q_RES(CHIPS)':
 'B': CDS_PINID='B';
NODE_NAME     C1773 1
 '@S9S_MB_2U_LIB.S9S_MB_2U(SCH_1):PAGE145_I114@PURE_QUANTA.Q_CAP(CHIPS)':
 'A': CDS_PINID='A';
NODE_NAME     R2846 1
 '@S9S_MB_2U_LIB.S9S_MB_2U(SCH_1):PAGE314_I134@PURE_QUANTA.Q_RES(CHIPS)':
 'A': CDS_PINID='A';
NET_NAME
'BIC_MONITER_ISO_R'
 '@S9S_MB_2U_LIB.S9S_MB_2U(SCH_1):BIC_MONITER_ISO_R':
 C_SIGNAL='@s9s_mb_2u_lib.s9s_mb_2u(sch_1):bic_moniter_iso_r';
NODE_NAME     R2846 2
 '@S9S_MB_2U_LIB.S9S_MB_2U(SCH_1):PAGE314_I134@PURE_QUANTA.Q_RES(CHIPS)':
 'B': CDS_PINID='B';
NODE_NAME     U249 C3
 '@S9S_MB_2U_LIB.S9S_MB_2U(SCH_1):PAGE314_I188@PURE_QUANTA.LCMXO3LF9400C5BG484C(CHIPS)':
 'PT10C': CDS_PINID='PT10C';
NET_NAME
'BIC_MONITER_N'
 '@S9S_MB_2U_LIB.S9S_MB_2U(SCH_1):BIC_MONITER_N':
 C_SIGNAL='@s9s_mb_2u_lib.s9s_mb_2u(sch_1):bic_moniter_n';
NODE_NAME     R2835 2
 '@S9S_MB_2U_LIB.S9S_MB_2U(SCH_1):PAGE145_I14@PURE_QUANTA.Q_RES(CHIPS)':
 'B': CDS_PINID='B';
NODE_NAME     Q67 6
 '@S9S_MB_2U_LIB.S9S_MB_2U(SCH_1):PAGE145_I33@PURE_QUANTA.MOSFET_NCH_DUAL(CHIPS)':
 'D1': CDS_PINID='D1';
NODE_NAME     Q67 5
 '@S9S_MB_2U_LIB.S9S_MB_2U(SCH_1):PAGE145_I82@PURE_QUANTA.MOSFET_NCH_DUAL(CHIPS)':
 'G2': CDS_PINID='G2';
NET_NAME
'BMC_MONITER'
 '@S9S_MB_2U_LIB.S9S_MB_2U(SCH_1):BMC_MONITER':
 C_SIGNAL='@s9s_mb_2u_lib.s9s_mb_2u(sch_1):bmc_moniter';
NODE_NAME     R2845 1
 '@S9S_MB_2U_LIB.S9S_MB_2U(SCH_1):PAGE314_I136@PURE_QUANTA.Q_RES(CHIPS)':
 'A': CDS_PINID='A';
NODE_NAME     U249 C4
 '@S9S_MB_2U_LIB.S9S_MB_2U(SCH_1):PAGE314_I188@PURE_QUANTA.LCMXO3LF9400C5BG484C(CHIPS)':
 'PT10D': CDS_PINID='PT10D';
NET_NAME
'BMC_MONITER_BUF'
 '@S9S_MB_2U_LIB.S9S_MB_2U(SCH_1):BMC_MONITER_BUF':
 C_SIGNAL='@s9s_mb_2u_lib.s9s_mb_2u(sch_1):bmc_moniter_buf';
NODE_NAME     J109 A1
 '@S9S_MB_2U_LIB.S9S_MB_2U(SCH_1):PAGE319_I53@PURE_QUANTA.CONN112_10137002101LF(CHIPS)':
 'A1': CDS_PINID='A1';
NODE_NAME     R2917 2
 '@S9S_MB_2U_LIB.S9S_MB_2U(SCH_1):PAGE140_I206@PURE_QUANTA.Q_RES(CHIPS)':
 'B': CDS_PINID='B';
NET_NAME
'BMC_MONITER_BUF_R'
 '@S9S_MB_2U_LIB.S9S_MB_2U(SCH_1):BMC_MONITER_BUF_R':
 C_SIGNAL='@s9s_mb_2u_lib.s9s_mb_2u(sch_1):bmc_moniter_buf_r';
NODE_NAME     U195 6
 '@S9S_MB_2U_LIB.S9S_MB_2U(SCH_1):PAGE140_I65@PURE_QUANTA.74LVC2G17GW(CHIPS)':
 'B0': CDS_PINID='B0';
NODE_NAME     R2820 2
 '@S9S_MB_2U_LIB.S9S_MB_2U(SCH_1):PAGE140_I78@PURE_QUANTA.Q_RES(CHIPS)':
 'B': CDS_PINID='B';
NODE_NAME     R2926 1
 '@S9S_MB_2U_LIB.S9S_MB_2U(SCH_1):PAGE140_I121@PURE_QUANTA.Q_RES(CHIPS)':
 'A': CDS_PINID='A';
NODE_NAME     R2917 1
 '@S9S_MB_2U_LIB.S9S_MB_2U(SCH_1):PAGE140_I206@PURE_QUANTA.Q_RES(CHIPS)':
 'A': CDS_PINID='A';
NET_NAME
'BMC_MONITER_R'
 '@S9S_MB_2U_LIB.S9S_MB_2U(SCH_1):BMC_MONITER_R':
 C_SIGNAL='@s9s_mb_2u_lib.s9s_mb_2u(sch_1):bmc_moniter_r';
NODE_NAME     U195 1
 '@S9S_MB_2U_LIB.S9S_MB_2U(SCH_1):PAGE140_I65@PURE_QUANTA.74LVC2G17GW(CHIPS)':
 'A0': CDS_PINID='A0';
NODE_NAME     R2815 2
 '@S9S_MB_2U_LIB.S9S_MB_2U(SCH_1):PAGE140_I68@PURE_QUANTA.Q_RES(CHIPS)':
 'B': CDS_PINID='B';
NODE_NAME     R2915 1
 '@S9S_MB_2U_LIB.S9S_MB_2U(SCH_1):PAGE140_I92@PURE_QUANTA.Q_RES(CHIPS)':
 'A': CDS_PINID='A';
NODE_NAME     R2845 2
 '@S9S_MB_2U_LIB.S9S_MB_2U(SCH_1):PAGE314_I136@PURE_QUANTA.Q_RES(CHIPS)':
 'B': CDS_PINID='B';
NET_NAME
'CK440Q_OE_1'
 '@S9S_MB_2U_LIB.S9S_MB_2U(SCH_1):CK440Q_OE_1':
 C_SIGNAL='@s9s_mb_2u_lib.s9s_mb_2u(sch_1):ck440q_oe_1';
NODE_NAME     U13 A30
 '@S9S_MB_2U_LIB.S9S_MB_2U(SCH_1):PAGE197_I180@PURE_QUANTA.9SQ440NQQI8(CHIPS)':
 'OE1#': CDS_PINID='\oe1#\';
NODE_NAME     R3638 2
 '@S9S_MB_2U_LIB.S9S_MB_2U(SCH_1):PAGE197_I378@PURE_QUANTA.Q_RES(CHIPS)':
 'B': CDS_PINID='B';
NET_NAME
'CK440Q_OE_2'
 '@S9S_MB_2U_LIB.S9S_MB_2U(SCH_1):CK440Q_OE_2':
 C_SIGNAL='@s9s_mb_2u_lib.s9s_mb_2u(sch_1):ck440q_oe_2';
NODE_NAME     U13 A29
 '@S9S_MB_2U_LIB.S9S_MB_2U(SCH_1):PAGE197_I180@PURE_QUANTA.9SQ440NQQI8(CHIPS)':
 'OE2#': CDS_PINID='\oe2#\';
NODE_NAME     R3639 2
 '@S9S_MB_2U_LIB.S9S_MB_2U(SCH_1):PAGE197_I379@PURE_QUANTA.Q_RES(CHIPS)':
 'B': CDS_PINID='B';
NET_NAME
'CK440Q_OE_3'
 '@S9S_MB_2U_LIB.S9S_MB_2U(SCH_1):CK440Q_OE_3':
 C_SIGNAL='@s9s_mb_2u_lib.s9s_mb_2u(sch_1):ck440q_oe_3';
NODE_NAME     U13 A26
 '@S9S_MB_2U_LIB.S9S_MB_2U(SCH_1):PAGE197_I180@PURE_QUANTA.9SQ440NQQI8(CHIPS)':
 'OE3#': CDS_PINID='\oe3#\';
NODE_NAME     R3640 2
 '@S9S_MB_2U_LIB.S9S_MB_2U(SCH_1):PAGE197_I380@PURE_QUANTA.Q_RES(CHIPS)':
 'B': CDS_PINID='B';
NET_NAME
'CK440Q_OE_4'
 '@S9S_MB_2U_LIB.S9S_MB_2U(SCH_1):CK440Q_OE_4':
 C_SIGNAL='@s9s_mb_2u_lib.s9s_mb_2u(sch_1):ck440q_oe_4';
NODE_NAME     U13 B19
 '@S9S_MB_2U_LIB.S9S_MB_2U(SCH_1):PAGE197_I180@PURE_QUANTA.9SQ440NQQI8(CHIPS)':
 'OE4#': CDS_PINID='\oe4#\';
NODE_NAME     R3641 2
 '@S9S_MB_2U_LIB.S9S_MB_2U(SCH_1):PAGE197_I381@PURE_QUANTA.Q_RES(CHIPS)':
 'B': CDS_PINID='B';
NET_NAME
'CK440Q_OE_5'
 '@S9S_MB_2U_LIB.S9S_MB_2U(SCH_1):CK440Q_OE_5':
 C_SIGNAL='@s9s_mb_2u_lib.s9s_mb_2u(sch_1):ck440q_oe_5';
NODE_NAME     U13 B15
 '@S9S_MB_2U_LIB.S9S_MB_2U(SCH_1):PAGE197_I180@PURE_QUANTA.9SQ440NQQI8(CHIPS)':
 'OE5#': CDS_PINID='\oe5#\';
NODE_NAME     R3642 2
 '@S9S_MB_2U_LIB.S9S_MB_2U(SCH_1):PAGE197_I382@PURE_QUANTA.Q_RES(CHIPS)':
 'B': CDS_PINID='B';
NET_NAME
'CK440Q_OE_6'
 '@S9S_MB_2U_LIB.S9S_MB_2U(SCH_1):CK440Q_OE_6':
 C_SIGNAL='@s9s_mb_2u_lib.s9s_mb_2u(sch_1):ck440q_oe_6';
NODE_NAME     U13 B14
 '@S9S_MB_2U_LIB.S9S_MB_2U(SCH_1):PAGE197_I180@PURE_QUANTA.9SQ440NQQI8(CHIPS)':
 'OE6#': CDS_PINID='\oe6#\';
NODE_NAME     R3643 2
 '@S9S_MB_2U_LIB.S9S_MB_2U(SCH_1):PAGE197_I383@PURE_QUANTA.Q_RES(CHIPS)':
 'B': CDS_PINID='B';
NET_NAME
'CLK_100M_BMC_P3E_DN'
 '@S9S_MB_2U_LIB.S9S_MB_2U(SCH_1):CLK_100M_BMC_P3E_DN':
 C_SIGNAL='@s9s_mb_2u_lib.s9s_mb_2u(sch_1):clk_100m_bmc_p3e_dn';
NODE_NAME     U4 B11
 '@S9S_MB_2U_LIB.S9S_MB_2U(SCH_1):PAGE171_I78@PURE_QUANTA.EMMITSBURG_REV0P9(CHIPS)':
 'CLKOUT_SRC_N_6': CDS_PINID='CLKOUT_SRC_N_6';
NODE_NAME     R4536 1
 '@S9S_MB_2U_LIB.S9S_MB_2U(SCH_1):PAGE227_I92@PURE_QUANTA.Q_RES(CHIPS)':
 'A': CDS_PINID='A';
NET_NAME
'CLK_100M_BMC_P3E_DN_R'
 '@S9S_MB_2U_LIB.S9S_MB_2U(SCH_1):CLK_100M_BMC_P3E_DN_R':
 C_SIGNAL='@s9s_mb_2u_lib.s9s_mb_2u(sch_1):clk_100m_bmc_p3e_dn_r';
NODE_NAME     R4536 2
 '@S9S_MB_2U_LIB.S9S_MB_2U(SCH_1):PAGE227_I92@PURE_QUANTA.Q_RES(CHIPS)':
 'B': CDS_PINID='B';
NODE_NAME     J41 A15
 '@S9S_MB_2U_LIB.S9S_MB_2U(SCH_1):PAGE227_I173@PURE_QUANTA.SCONN168_ME1016810202011(CHIPS)':
 'REFCLKP1': CDS_PINID='REFCLKP1';
NET_NAME
'CLK_100M_BMC_P3E_DP'
 '@S9S_MB_2U_LIB.S9S_MB_2U(SCH_1):CLK_100M_BMC_P3E_DP':
 C_SIGNAL='@s9s_mb_2u_lib.s9s_mb_2u(sch_1):clk_100m_bmc_p3e_dp';
NODE_NAME     U4 D11
 '@S9S_MB_2U_LIB.S9S_MB_2U(SCH_1):PAGE171_I78@PURE_QUANTA.EMMITSBURG_REV0P9(CHIPS)':
 'CLKOUT_SRC_P_6': CDS_PINID='CLKOUT_SRC_P_6';
NODE_NAME     R4535 1
 '@S9S_MB_2U_LIB.S9S_MB_2U(SCH_1):PAGE227_I91@PURE_QUANTA.Q_RES(CHIPS)':
 'A': CDS_PINID='A';
NET_NAME
'CLK_100M_BMC_P3E_DP_R'
 '@S9S_MB_2U_LIB.S9S_MB_2U(SCH_1):CLK_100M_BMC_P3E_DP_R':
 C_SIGNAL='@s9s_mb_2u_lib.s9s_mb_2u(sch_1):clk_100m_bmc_p3e_dp_r';
NODE_NAME     R4535 2
 '@S9S_MB_2U_LIB.S9S_MB_2U(SCH_1):PAGE227_I91@PURE_QUANTA.Q_RES(CHIPS)':
 'B': CDS_PINID='B';
NODE_NAME     J41 A14
 '@S9S_MB_2U_LIB.S9S_MB_2U(SCH_1):PAGE227_I173@PURE_QUANTA.SCONN168_ME1016810202011(CHIPS)':
 'REFCLKN1': CDS_PINID='REFCLKN1';
NET_NAME
'CLK_100M_BMC_RC_DN'
 '@S9S_MB_2U_LIB.S9S_MB_2U(SCH_1):CLK_100M_BMC_RC_DN':
 C_SIGNAL='@s9s_mb_2u_lib.s9s_mb_2u(sch_1):clk_100m_bmc_rc_dn';
NODE_NAME     R3336 2
 '@S9S_MB_2U_LIB.S9S_MB_2U(SCH_1):PAGE201_I74@PURE_QUANTA.Q_RES(CHIPS)':
 'B': CDS_PINID='B';
NODE_NAME     J41 A69
 '@S9S_MB_2U_LIB.S9S_MB_2U(SCH_1):PAGE227_I173@PURE_QUANTA.SCONN168_ME1016810202011(CHIPS)':
 'USB_DATP': CDS_PINID='USB_DATP';
NET_NAME
'CLK_100M_BMC_RC_DN_R'
 '@S9S_MB_2U_LIB.S9S_MB_2U(SCH_1):CLK_100M_BMC_RC_DN_R':
 C_SIGNAL='@s9s_mb_2u_lib.s9s_mb_2u(sch_1):clk_100m_bmc_rc_dn_r';
NODE_NAME     R3336 1
 '@S9S_MB_2U_LIB.S9S_MB_2U(SCH_1):PAGE201_I74@PURE_QUANTA.Q_RES(CHIPS)':
 'A': CDS_PINID='A';
NODE_NAME     U247 14
 '@S9S_MB_2U_LIB.S9S_MB_2U(SCH_1):PAGE201_I167@PURE_QUANTA.9FGL0251DKILFT(CHIPS)':
 'DIF0#': CDS_PINID='\dif0#\';
NET_NAME
'CLK_100M_BMC_RC_DP'
 '@S9S_MB_2U_LIB.S9S_MB_2U(SCH_1):CLK_100M_BMC_RC_DP':
 C_SIGNAL='@s9s_mb_2u_lib.s9s_mb_2u(sch_1):clk_100m_bmc_rc_dp';
NODE_NAME     R3335 2
 '@S9S_MB_2U_LIB.S9S_MB_2U(SCH_1):PAGE201_I69@PURE_QUANTA.Q_RES(CHIPS)':
 'B': CDS_PINID='B';
NODE_NAME     J41 A68
 '@S9S_MB_2U_LIB.S9S_MB_2U(SCH_1):PAGE227_I173@PURE_QUANTA.SCONN168_ME1016810202011(CHIPS)':
 'USB_DATN': CDS_PINID='USB_DATN';
NET_NAME
'CLK_100M_BMC_RC_DP_R'
 '@S9S_MB_2U_LIB.S9S_MB_2U(SCH_1):CLK_100M_BMC_RC_DP_R':
 C_SIGNAL='@s9s_mb_2u_lib.s9s_mb_2u(sch_1):clk_100m_bmc_rc_dp_r';
NODE_NAME     R3335 1
 '@S9S_MB_2U_LIB.S9S_MB_2U(SCH_1):PAGE201_I69@PURE_QUANTA.Q_RES(CHIPS)':
 'A': CDS_PINID='A';
NODE_NAME     U247 13
 '@S9S_MB_2U_LIB.S9S_MB_2U(SCH_1):PAGE201_I167@PURE_QUANTA.9FGL0251DKILFT(CHIPS)':
 'DIF0': CDS_PINID='DIF0';
NET_NAME
'CLK_100M_CK440_PCH_EXTCLK_DN'
 '@S9S_MB_2U_LIB.S9S_MB_2U(SCH_1):CLK_100M_CK440_PCH_EXTCLK_DN':
 C_SIGNAL='@s9s_mb_2u_lib.s9s_mb_2u(sch_1):clk_100m_ck440_pch_extclk_dn';
NODE_NAME     U4 D21
 '@S9S_MB_2U_LIB.S9S_MB_2U(SCH_1):PAGE171_I78@PURE_QUANTA.EMMITSBURG_REV0P9(CHIPS)':
 'REFCLK_INJ_S_N': CDS_PINID='REFCLK_INJ_S_N';
NODE_NAME     R554 2
 '@S9S_MB_2U_LIB.S9S_MB_2U(SCH_1):PAGE198_I57@PURE_QUANTA.Q_RES(CHIPS)':
 'B': CDS_PINID='B';
NET_NAME
'CLK_100M_CK440_PCH_EXTCLK_DP'
 '@S9S_MB_2U_LIB.S9S_MB_2U(SCH_1):CLK_100M_CK440_PCH_EXTCLK_DP':
 C_SIGNAL='@s9s_mb_2u_lib.s9s_mb_2u(sch_1):clk_100m_ck440_pch_extclk_dp';
NODE_NAME     U4 B21
 '@S9S_MB_2U_LIB.S9S_MB_2U(SCH_1):PAGE171_I78@PURE_QUANTA.EMMITSBURG_REV0P9(CHIPS)':
 'REFCLK_INJ_S_P': CDS_PINID='REFCLK_INJ_S_P';
NODE_NAME     R553 2
 '@S9S_MB_2U_LIB.S9S_MB_2U(SCH_1):PAGE198_I58@PURE_QUANTA.Q_RES(CHIPS)':
 'B': CDS_PINID='B';
NET_NAME
'CLK_100M_CK440_PCH_EXTCLK_R_DN'
 '@S9S_MB_2U_LIB.S9S_MB_2U(SCH_1):CLK_100M_CK440_PCH_EXTCLK_R_DN':
 C_SIGNAL='@s9s_mb_2u_lib.s9s_mb_2u(sch_1):clk_100m_ck440_pch_extclk_r_dn';
NODE_NAME     U13 A47
 '@S9S_MB_2U_LIB.S9S_MB_2U(SCH_1):PAGE197_I180@PURE_QUANTA.9SQ440NQQI8(CHIPS)':
 'MXCK2#': CDS_PINID='\mxck2#\';
NODE_NAME     R554 1
 '@S9S_MB_2U_LIB.S9S_MB_2U(SCH_1):PAGE198_I57@PURE_QUANTA.Q_RES(CHIPS)':
 'A': CDS_PINID='A';
NET_NAME
'CLK_100M_CK440_PCH_EXTCLK_R_DP'
 '@S9S_MB_2U_LIB.S9S_MB_2U(SCH_1):CLK_100M_CK440_PCH_EXTCLK_R_DP':
 C_SIGNAL='@s9s_mb_2u_lib.s9s_mb_2u(sch_1):clk_100m_ck440_pch_extclk_r_dp';
NODE_NAME     U13 A48
 '@S9S_MB_2U_LIB.S9S_MB_2U(SCH_1):PAGE197_I180@PURE_QUANTA.9SQ440NQQI8(CHIPS)':
 'MXCK2': CDS_PINID='MXCK2';
NODE_NAME     R553 1
 '@S9S_MB_2U_LIB.S9S_MB_2U(SCH_1):PAGE198_I58@PURE_QUANTA.Q_RES(CHIPS)':
 'A': CDS_PINID='A';
NET_NAME
'CLK_100M_DB2000_CPU0_BCLK0_DN'
 '@S9S_MB_2U_LIB.S9S_MB_2U(SCH_1):CLK_100M_DB2000_CPU0_BCLK0_DN':
 C_SIGNAL='@s9s_mb_2u_lib.s9s_mb_2u(sch_1):clk_100m_db2000_cpu0_bclk0_dn';
NODE_NAME     U2 AT30
 '@S9S_MB_2U_LIB.S9S_MB_2U(SCH_1):PAGE13_I57@PURE_QUANTA.SOCKET4677_AZIF0045P001C01CS(CHIPS)':
 'BCLK0_DN': CDS_PINID='BCLK0_DN';
NODE_NAME     U38 K1
 '@S9S_MB_2U_LIB.S9S_MB_2U(SCH_1):PAGE195_I119@PURE_QUANTA.9QXL2001BNHGI8(CHIPS)':
 'DIF0#': CDS_PINID='\dif0#\';
NET_NAME
'CLK_100M_DB2000_CPU0_BCLK0_DP'
 '@S9S_MB_2U_LIB.S9S_MB_2U(SCH_1):CLK_100M_DB2000_CPU0_BCLK0_DP':
 C_SIGNAL='@s9s_mb_2u_lib.s9s_mb_2u(sch_1):clk_100m_db2000_cpu0_bclk0_dp';
NODE_NAME     U2 AV30
 '@S9S_MB_2U_LIB.S9S_MB_2U(SCH_1):PAGE13_I57@PURE_QUANTA.SOCKET4677_AZIF0045P001C01CS(CHIPS)':
 'BCLK0_DP': CDS_PINID='BCLK0_DP';
NODE_NAME     U38 J1
 '@S9S_MB_2U_LIB.S9S_MB_2U(SCH_1):PAGE195_I119@PURE_QUANTA.9QXL2001BNHGI8(CHIPS)':
 'DIF0': CDS_PINID='DIF0';
NET_NAME
'CLK_100M_DB2000_CPU0_BCLK1_DN'
 '@S9S_MB_2U_LIB.S9S_MB_2U(SCH_1):CLK_100M_DB2000_CPU0_BCLK1_DN':
 C_SIGNAL='@s9s_mb_2u_lib.s9s_mb_2u(sch_1):clk_100m_db2000_cpu0_bclk1_dn';
NODE_NAME     U2 CY28
 '@S9S_MB_2U_LIB.S9S_MB_2U(SCH_1):PAGE13_I57@PURE_QUANTA.SOCKET4677_AZIF0045P001C01CS(CHIPS)':
 'BCLK1_DN': CDS_PINID='BCLK1_DN';
NODE_NAME     U38 M1
 '@S9S_MB_2U_LIB.S9S_MB_2U(SCH_1):PAGE195_I119@PURE_QUANTA.9QXL2001BNHGI8(CHIPS)':
 'DIF1#': CDS_PINID='\dif1#\';
NET_NAME
'CLK_100M_DB2000_CPU0_BCLK1_DP'
 '@S9S_MB_2U_LIB.S9S_MB_2U(SCH_1):CLK_100M_DB2000_CPU0_BCLK1_DP':
 C_SIGNAL='@s9s_mb_2u_lib.s9s_mb_2u(sch_1):clk_100m_db2000_cpu0_bclk1_dp';
NODE_NAME     U2 CW29
 '@S9S_MB_2U_LIB.S9S_MB_2U(SCH_1):PAGE13_I57@PURE_QUANTA.SOCKET4677_AZIF0045P001C01CS(CHIPS)':
 'BCLK1_DP': CDS_PINID='BCLK1_DP';
NODE_NAME     U38 L1
 '@S9S_MB_2U_LIB.S9S_MB_2U(SCH_1):PAGE195_I119@PURE_QUANTA.9QXL2001BNHGI8(CHIPS)':
 'DIF1': CDS_PINID='DIF1';
NET_NAME
'CLK_100M_DB2000_CPU0_BCLK2_DN'
 '@S9S_MB_2U_LIB.S9S_MB_2U(SCH_1):CLK_100M_DB2000_CPU0_BCLK2_DN':
 C_SIGNAL='@s9s_mb_2u_lib.s9s_mb_2u(sch_1):clk_100m_db2000_cpu0_bclk2_dn';
NODE_NAME     U2 AU29
 '@S9S_MB_2U_LIB.S9S_MB_2U(SCH_1):PAGE13_I57@PURE_QUANTA.SOCKET4677_AZIF0045P001C01CS(CHIPS)':
 'BCLK2_DN': CDS_PINID='BCLK2_DN';
NODE_NAME     U38 M3
 '@S9S_MB_2U_LIB.S9S_MB_2U(SCH_1):PAGE195_I119@PURE_QUANTA.9QXL2001BNHGI8(CHIPS)':
 'DIF2#': CDS_PINID='\dif2#\';
NET_NAME
'CLK_100M_DB2000_CPU0_BCLK2_DP'
 '@S9S_MB_2U_LIB.S9S_MB_2U(SCH_1):CLK_100M_DB2000_CPU0_BCLK2_DP':
 C_SIGNAL='@s9s_mb_2u_lib.s9s_mb_2u(sch_1):clk_100m_db2000_cpu0_bclk2_dp';
NODE_NAME     U2 AV28
 '@S9S_MB_2U_LIB.S9S_MB_2U(SCH_1):PAGE13_I57@PURE_QUANTA.SOCKET4677_AZIF0045P001C01CS(CHIPS)':
 'BCLK2_DP': CDS_PINID='BCLK2_DP';
NODE_NAME     U38 M2
 '@S9S_MB_2U_LIB.S9S_MB_2U(SCH_1):PAGE195_I119@PURE_QUANTA.9QXL2001BNHGI8(CHIPS)':
 'DIF2': CDS_PINID='DIF2';
NET_NAME
'CLK_100M_DB2000_CPU0_BCLK3_DN'
 '@S9S_MB_2U_LIB.S9S_MB_2U(SCH_1):CLK_100M_DB2000_CPU0_BCLK3_DN':
 C_SIGNAL='@s9s_mb_2u_lib.s9s_mb_2u(sch_1):clk_100m_db2000_cpu0_bclk3_dn';
NODE_NAME     U2 CW27
 '@S9S_MB_2U_LIB.S9S_MB_2U(SCH_1):PAGE13_I57@PURE_QUANTA.SOCKET4677_AZIF0045P001C01CS(CHIPS)':
 'BCLK3_DN': CDS_PINID='BCLK3_DN';
NODE_NAME     U38 M5
 '@S9S_MB_2U_LIB.S9S_MB_2U(SCH_1):PAGE195_I119@PURE_QUANTA.9QXL2001BNHGI8(CHIPS)':
 'DIF3#': CDS_PINID='\dif3#\';
NET_NAME
'CLK_100M_DB2000_CPU0_BCLK3_DP'
 '@S9S_MB_2U_LIB.S9S_MB_2U(SCH_1):CLK_100M_DB2000_CPU0_BCLK3_DP':
 C_SIGNAL='@s9s_mb_2u_lib.s9s_mb_2u(sch_1):clk_100m_db2000_cpu0_bclk3_dp';
NODE_NAME     U2 DA27
 '@S9S_MB_2U_LIB.S9S_MB_2U(SCH_1):PAGE13_I57@PURE_QUANTA.SOCKET4677_AZIF0045P001C01CS(CHIPS)':
 'BCLK3_DP': CDS_PINID='BCLK3_DP';
NODE_NAME     U38 M4
 '@S9S_MB_2U_LIB.S9S_MB_2U(SCH_1):PAGE195_I119@PURE_QUANTA.9QXL2001BNHGI8(CHIPS)':
 'DIF3': CDS_PINID='DIF3';
NET_NAME
'CLK_100M_DB2000_CPU1_BCLK0_DN'
 '@S9S_MB_2U_LIB.S9S_MB_2U(SCH_1):CLK_100M_DB2000_CPU1_BCLK0_DN':
 C_SIGNAL='@s9s_mb_2u_lib.s9s_mb_2u(sch_1):clk_100m_db2000_cpu1_bclk0_dn';
NODE_NAME     U1 AT30
 '@S9S_MB_2U_LIB.S9S_MB_2U(SCH_1):PAGE44_I51@PURE_QUANTA.SOCKET4677_AZIF0045P001C01CS(CHIPS)':
 'BCLK0_DN': CDS_PINID='BCLK0_DN';
NODE_NAME     U38 M8
 '@S9S_MB_2U_LIB.S9S_MB_2U(SCH_1):PAGE195_I119@PURE_QUANTA.9QXL2001BNHGI8(CHIPS)':
 'DIF4#': CDS_PINID='\dif4#\';
NET_NAME
'CLK_100M_DB2000_CPU1_BCLK0_DP'
 '@S9S_MB_2U_LIB.S9S_MB_2U(SCH_1):CLK_100M_DB2000_CPU1_BCLK0_DP':
 C_SIGNAL='@s9s_mb_2u_lib.s9s_mb_2u(sch_1):clk_100m_db2000_cpu1_bclk0_dp';
NODE_NAME     U1 AV30
 '@S9S_MB_2U_LIB.S9S_MB_2U(SCH_1):PAGE44_I51@PURE_QUANTA.SOCKET4677_AZIF0045P001C01CS(CHIPS)':
 'BCLK0_DP': CDS_PINID='BCLK0_DP';
NODE_NAME     U38 M7
 '@S9S_MB_2U_LIB.S9S_MB_2U(SCH_1):PAGE195_I119@PURE_QUANTA.9QXL2001BNHGI8(CHIPS)':
 'DIF4': CDS_PINID='DIF4';
NET_NAME
'CLK_100M_DB2000_CPU1_BCLK1_DN'
 '@S9S_MB_2U_LIB.S9S_MB_2U(SCH_1):CLK_100M_DB2000_CPU1_BCLK1_DN':
 C_SIGNAL='@s9s_mb_2u_lib.s9s_mb_2u(sch_1):clk_100m_db2000_cpu1_bclk1_dn';
NODE_NAME     U1 CY28
 '@S9S_MB_2U_LIB.S9S_MB_2U(SCH_1):PAGE44_I51@PURE_QUANTA.SOCKET4677_AZIF0045P001C01CS(CHIPS)':
 'BCLK1_DN': CDS_PINID='BCLK1_DN';
NODE_NAME     U38 M10
 '@S9S_MB_2U_LIB.S9S_MB_2U(SCH_1):PAGE195_I119@PURE_QUANTA.9QXL2001BNHGI8(CHIPS)':
 'DIF5#': CDS_PINID='\dif5#\';
NET_NAME
'CLK_100M_DB2000_CPU1_BCLK1_DP'
 '@S9S_MB_2U_LIB.S9S_MB_2U(SCH_1):CLK_100M_DB2000_CPU1_BCLK1_DP':
 C_SIGNAL='@s9s_mb_2u_lib.s9s_mb_2u(sch_1):clk_100m_db2000_cpu1_bclk1_dp';
NODE_NAME     U1 CW29
 '@S9S_MB_2U_LIB.S9S_MB_2U(SCH_1):PAGE44_I51@PURE_QUANTA.SOCKET4677_AZIF0045P001C01CS(CHIPS)':
 'BCLK1_DP': CDS_PINID='BCLK1_DP';
NODE_NAME     U38 M9
 '@S9S_MB_2U_LIB.S9S_MB_2U(SCH_1):PAGE195_I119@PURE_QUANTA.9QXL2001BNHGI8(CHIPS)':
 'DIF5': CDS_PINID='DIF5';
NET_NAME
'CLK_100M_DB2000_CPU1_BCLK2_DN'
 '@S9S_MB_2U_LIB.S9S_MB_2U(SCH_1):CLK_100M_DB2000_CPU1_BCLK2_DN':
 C_SIGNAL='@s9s_mb_2u_lib.s9s_mb_2u(sch_1):clk_100m_db2000_cpu1_bclk2_dn';
NODE_NAME     U1 AU29
 '@S9S_MB_2U_LIB.S9S_MB_2U(SCH_1):PAGE44_I51@PURE_QUANTA.SOCKET4677_AZIF0045P001C01CS(CHIPS)':
 'BCLK2_DN': CDS_PINID='BCLK2_DN';
NODE_NAME     U38 M12
 '@S9S_MB_2U_LIB.S9S_MB_2U(SCH_1):PAGE195_I119@PURE_QUANTA.9QXL2001BNHGI8(CHIPS)':
 'DIF6#': CDS_PINID='\dif6#\';
NET_NAME
'CLK_100M_DB2000_CPU1_BCLK2_DP'
 '@S9S_MB_2U_LIB.S9S_MB_2U(SCH_1):CLK_100M_DB2000_CPU1_BCLK2_DP':
 C_SIGNAL='@s9s_mb_2u_lib.s9s_mb_2u(sch_1):clk_100m_db2000_cpu1_bclk2_dp';
NODE_NAME     U1 AV28
 '@S9S_MB_2U_LIB.S9S_MB_2U(SCH_1):PAGE44_I51@PURE_QUANTA.SOCKET4677_AZIF0045P001C01CS(CHIPS)':
 'BCLK2_DP': CDS_PINID='BCLK2_DP';
NODE_NAME     U38 M11
 '@S9S_MB_2U_LIB.S9S_MB_2U(SCH_1):PAGE195_I119@PURE_QUANTA.9QXL2001BNHGI8(CHIPS)':
 'DIF6': CDS_PINID='DIF6';
NET_NAME
'CLK_100M_DB2000_CPU1_BCLK3_DN'
 '@S9S_MB_2U_LIB.S9S_MB_2U(SCH_1):CLK_100M_DB2000_CPU1_BCLK3_DN':
 C_SIGNAL='@s9s_mb_2u_lib.s9s_mb_2u(sch_1):clk_100m_db2000_cpu1_bclk3_dn';
NODE_NAME     U1 CW27
 '@S9S_MB_2U_LIB.S9S_MB_2U(SCH_1):PAGE44_I51@PURE_QUANTA.SOCKET4677_AZIF0045P001C01CS(CHIPS)':
 'BCLK3_DN': CDS_PINID='BCLK3_DN';
NODE_NAME     U38 K12
 '@S9S_MB_2U_LIB.S9S_MB_2U(SCH_1):PAGE195_I119@PURE_QUANTA.9QXL2001BNHGI8(CHIPS)':
 'DIF7#': CDS_PINID='\dif7#\';
NET_NAME
'CLK_100M_DB2000_CPU1_BCLK3_DP'
 '@S9S_MB_2U_LIB.S9S_MB_2U(SCH_1):CLK_100M_DB2000_CPU1_BCLK3_DP':
 C_SIGNAL='@s9s_mb_2u_lib.s9s_mb_2u(sch_1):clk_100m_db2000_cpu1_bclk3_dp';
NODE_NAME     U1 DA27
 '@S9S_MB_2U_LIB.S9S_MB_2U(SCH_1):PAGE44_I51@PURE_QUANTA.SOCKET4677_AZIF0045P001C01CS(CHIPS)':
 'BCLK3_DP': CDS_PINID='BCLK3_DP';
NODE_NAME     U38 L12
 '@S9S_MB_2U_LIB.S9S_MB_2U(SCH_1):PAGE195_I119@PURE_QUANTA.9QXL2001BNHGI8(CHIPS)':
 'DIF7': CDS_PINID='DIF7';
NET_NAME
'CLK_100M_DB2000_DN'
 '@S9S_MB_2U_LIB.S9S_MB_2U(SCH_1):CLK_100M_DB2000_DN':
 C_SIGNAL='@s9s_mb_2u_lib.s9s_mb_2u(sch_1):clk_100m_db2000_dn';
NODE_NAME     U38 H1
 '@S9S_MB_2U_LIB.S9S_MB_2U(SCH_1):PAGE195_I119@PURE_QUANTA.9QXL2001BNHGI8(CHIPS)':
 'DIF_IN#': CDS_PINID='\dif_in#\';
NODE_NAME     U13 A33
 '@S9S_MB_2U_LIB.S9S_MB_2U(SCH_1):PAGE197_I180@PURE_QUANTA.9SQ440NQQI8(CHIPS)':
 '100M0#': CDS_PINID='\100m0#\';
NET_NAME
'CLK_100M_DB2000_DP'
 '@S9S_MB_2U_LIB.S9S_MB_2U(SCH_1):CLK_100M_DB2000_DP':
 C_SIGNAL='@s9s_mb_2u_lib.s9s_mb_2u(sch_1):clk_100m_db2000_dp';
NODE_NAME     U38 G1
 '@S9S_MB_2U_LIB.S9S_MB_2U(SCH_1):PAGE195_I119@PURE_QUANTA.9QXL2001BNHGI8(CHIPS)':
 'DIF_IN': CDS_PINID='DIF_IN';
NODE_NAME     U13 A34
 '@S9S_MB_2U_LIB.S9S_MB_2U(SCH_1):PAGE197_I180@PURE_QUANTA.9SQ440NQQI8(CHIPS)':
 '100M0': CDS_PINID='\100m0\';
NET_NAME
'CLK_100M_E1S_0_DN'
 '@S9S_MB_2U_LIB.S9S_MB_2U(SCH_1):CLK_100M_E1S_0_DN':
 C_SIGNAL='@s9s_mb_2u_lib.s9s_mb_2u(sch_1):clk_100m_e1s_0_dn';
NODE_NAME     J90 B14
 '@S9S_MB_2U_LIB.S9S_MB_2U(SCH_1):PAGE297_I318@PURE_QUANTA.SCONN56_123276793(CHIPS)':
 'REFCLK_N0': CDS_PINID='REFCLK_N0';
NODE_NAME     R4304 2
 '@S9S_MB_2U_LIB.S9S_MB_2U(SCH_1):PAGE171_I122@PURE_QUANTA.Q_RES(CHIPS)':
 'B': CDS_PINID='B';
NET_NAME
'CLK_100M_E1S_0_DP'
 '@S9S_MB_2U_LIB.S9S_MB_2U(SCH_1):CLK_100M_E1S_0_DP':
 C_SIGNAL='@s9s_mb_2u_lib.s9s_mb_2u(sch_1):clk_100m_e1s_0_dp';
NODE_NAME     J90 B15
 '@S9S_MB_2U_LIB.S9S_MB_2U(SCH_1):PAGE297_I318@PURE_QUANTA.SCONN56_123276793(CHIPS)':
 'REFCLK_P0': CDS_PINID='REFCLK_P0';
NODE_NAME     R4303 2
 '@S9S_MB_2U_LIB.S9S_MB_2U(SCH_1):PAGE171_I121@PURE_QUANTA.Q_RES(CHIPS)':
 'B': CDS_PINID='B';
NET_NAME
'CLK_100M_E1S_0_R_DN'
 '@S9S_MB_2U_LIB.S9S_MB_2U(SCH_1):CLK_100M_E1S_0_R_DN':
 C_SIGNAL='@s9s_mb_2u_lib.s9s_mb_2u(sch_1):clk_100m_e1s_0_r_dn';
NODE_NAME     U4 B17
 '@S9S_MB_2U_LIB.S9S_MB_2U(SCH_1):PAGE171_I78@PURE_QUANTA.EMMITSBURG_REV0P9(CHIPS)':
 'CLKOUT_SRC_N_3': CDS_PINID='CLKOUT_SRC_N_3';
NODE_NAME     R4304 1
 '@S9S_MB_2U_LIB.S9S_MB_2U(SCH_1):PAGE171_I122@PURE_QUANTA.Q_RES(CHIPS)':
 'A': CDS_PINID='A';
NET_NAME
'CLK_100M_E1S_0_R_DP'
 '@S9S_MB_2U_LIB.S9S_MB_2U(SCH_1):CLK_100M_E1S_0_R_DP':
 C_SIGNAL='@s9s_mb_2u_lib.s9s_mb_2u(sch_1):clk_100m_e1s_0_r_dp';
NODE_NAME     U4 D17
 '@S9S_MB_2U_LIB.S9S_MB_2U(SCH_1):PAGE171_I78@PURE_QUANTA.EMMITSBURG_REV0P9(CHIPS)':
 'CLKOUT_SRC_P_3': CDS_PINID='CLKOUT_SRC_P_3';
NODE_NAME     R4303 1
 '@S9S_MB_2U_LIB.S9S_MB_2U(SCH_1):PAGE171_I121@PURE_QUANTA.Q_RES(CHIPS)':
 'A': CDS_PINID='A';
NET_NAME
'CLK_100M_GPU_1_DN'
 '@S9S_MB_2U_LIB.S9S_MB_2U(SCH_1):CLK_100M_GPU_1_DN':
 C_SIGNAL='@s9s_mb_2u_lib.s9s_mb_2u(sch_1):clk_100m_gpu_1_dn';
NODE_NAME     J112 N4
 '@S9S_MB_2U_LIB.S9S_MB_2U(SCH_1):PAGE149_I76@PURE_QUANTA.CONN160_10131762101LF(CHIPS)':
 'N4': CDS_PINID='N4';
NODE_NAME     R3353 2
 '@S9S_MB_2U_LIB.S9S_MB_2U(SCH_1):PAGE196_I25@PURE_QUANTA.Q_RES(CHIPS)':
 'B': CDS_PINID='B';
NET_NAME
'CLK_100M_GPU_1_DP'
 '@S9S_MB_2U_LIB.S9S_MB_2U(SCH_1):CLK_100M_GPU_1_DP':
 C_SIGNAL='@s9s_mb_2u_lib.s9s_mb_2u(sch_1):clk_100m_gpu_1_dp';
NODE_NAME     J112 O4
 '@S9S_MB_2U_LIB.S9S_MB_2U(SCH_1):PAGE149_I76@PURE_QUANTA.CONN160_10131762101LF(CHIPS)':
 'O4': CDS_PINID='O4';
NODE_NAME     R3352 2
 '@S9S_MB_2U_LIB.S9S_MB_2U(SCH_1):PAGE196_I26@PURE_QUANTA.Q_RES(CHIPS)':
 'B': CDS_PINID='B';
NET_NAME
'CLK_100M_GPU_1_R_DN'
 '@S9S_MB_2U_LIB.S9S_MB_2U(SCH_1):CLK_100M_GPU_1_R_DN':
 C_SIGNAL='@s9s_mb_2u_lib.s9s_mb_2u(sch_1):clk_100m_gpu_1_r_dn';
NODE_NAME     U314 20
 '@S9S_MB_2U_LIB.S9S_MB_2U(SCH_1):PAGE200_I1@PURE_QUANTA.9ZXL0451EKILFT(CHIPS)':
 'DIF1#': CDS_PINID='\dif1#\';
NODE_NAME     R3353 1
 '@S9S_MB_2U_LIB.S9S_MB_2U(SCH_1):PAGE196_I25@PURE_QUANTA.Q_RES(CHIPS)':
 'A': CDS_PINID='A';
NET_NAME
'CLK_100M_GPU_1_R_DP'
 '@S9S_MB_2U_LIB.S9S_MB_2U(SCH_1):CLK_100M_GPU_1_R_DP':
 C_SIGNAL='@s9s_mb_2u_lib.s9s_mb_2u(sch_1):clk_100m_gpu_1_r_dp';
NODE_NAME     U314 19
 '@S9S_MB_2U_LIB.S9S_MB_2U(SCH_1):PAGE200_I1@PURE_QUANTA.9ZXL0451EKILFT(CHIPS)':
 'DIF1': CDS_PINID='DIF1';
NODE_NAME     R3352 1
 '@S9S_MB_2U_LIB.S9S_MB_2U(SCH_1):PAGE196_I26@PURE_QUANTA.Q_RES(CHIPS)':
 'A': CDS_PINID='A';
NET_NAME
'CLK_100M_GPU_2_DN'
 '@S9S_MB_2U_LIB.S9S_MB_2U(SCH_1):CLK_100M_GPU_2_DN':
 C_SIGNAL='@s9s_mb_2u_lib.s9s_mb_2u(sch_1):clk_100m_gpu_2_dn';
NODE_NAME     J112 O1
 '@S9S_MB_2U_LIB.S9S_MB_2U(SCH_1):PAGE149_I76@PURE_QUANTA.CONN160_10131762101LF(CHIPS)':
 'O1': CDS_PINID='O1';
NODE_NAME     R3355 2
 '@S9S_MB_2U_LIB.S9S_MB_2U(SCH_1):PAGE196_I18@PURE_QUANTA.Q_RES(CHIPS)':
 'B': CDS_PINID='B';
NET_NAME
'CLK_100M_GPU_2_DP'
 '@S9S_MB_2U_LIB.S9S_MB_2U(SCH_1):CLK_100M_GPU_2_DP':
 C_SIGNAL='@s9s_mb_2u_lib.s9s_mb_2u(sch_1):clk_100m_gpu_2_dp';
NODE_NAME     J112 P1
 '@S9S_MB_2U_LIB.S9S_MB_2U(SCH_1):PAGE149_I76@PURE_QUANTA.CONN160_10131762101LF(CHIPS)':
 'P1': CDS_PINID='P1';
NODE_NAME     R3354 2
 '@S9S_MB_2U_LIB.S9S_MB_2U(SCH_1):PAGE196_I24@PURE_QUANTA.Q_RES(CHIPS)':
 'B': CDS_PINID='B';
NET_NAME
'CLK_100M_GPU_2_R_DN'
 '@S9S_MB_2U_LIB.S9S_MB_2U(SCH_1):CLK_100M_GPU_2_R_DN':
 C_SIGNAL='@s9s_mb_2u_lib.s9s_mb_2u(sch_1):clk_100m_gpu_2_r_dn';
NODE_NAME     U314 23
 '@S9S_MB_2U_LIB.S9S_MB_2U(SCH_1):PAGE200_I1@PURE_QUANTA.9ZXL0451EKILFT(CHIPS)':
 'DIF2#': CDS_PINID='\dif2#\';
NODE_NAME     R3355 1
 '@S9S_MB_2U_LIB.S9S_MB_2U(SCH_1):PAGE196_I18@PURE_QUANTA.Q_RES(CHIPS)':
 'A': CDS_PINID='A';
NET_NAME
'CLK_100M_GPU_2_R_DP'
 '@S9S_MB_2U_LIB.S9S_MB_2U(SCH_1):CLK_100M_GPU_2_R_DP':
 C_SIGNAL='@s9s_mb_2u_lib.s9s_mb_2u(sch_1):clk_100m_gpu_2_r_dp';
NODE_NAME     U314 22
 '@S9S_MB_2U_LIB.S9S_MB_2U(SCH_1):PAGE200_I1@PURE_QUANTA.9ZXL0451EKILFT(CHIPS)':
 'DIF2': CDS_PINID='DIF2';
NODE_NAME     R3354 1
 '@S9S_MB_2U_LIB.S9S_MB_2U(SCH_1):PAGE196_I24@PURE_QUANTA.Q_RES(CHIPS)':
 'A': CDS_PINID='A';
NET_NAME
'CLK_100M_GPU_FPGA_DN'
 '@S9S_MB_2U_LIB.S9S_MB_2U(SCH_1):CLK_100M_GPU_FPGA_DN':
 C_SIGNAL='@s9s_mb_2u_lib.s9s_mb_2u(sch_1):clk_100m_gpu_fpga_dn';
NODE_NAME     J112 Q2
 '@S9S_MB_2U_LIB.S9S_MB_2U(SCH_1):PAGE149_I76@PURE_QUANTA.CONN160_10131762101LF(CHIPS)':
 'Q2': CDS_PINID='Q2';
NODE_NAME     R3338 2
 '@S9S_MB_2U_LIB.S9S_MB_2U(SCH_1):PAGE201_I76@PURE_QUANTA.Q_RES(CHIPS)':
 'B': CDS_PINID='B';
NET_NAME
'CLK_100M_GPU_FPGA_DN_R'
 '@S9S_MB_2U_LIB.S9S_MB_2U(SCH_1):CLK_100M_GPU_FPGA_DN_R':
 C_SIGNAL='@s9s_mb_2u_lib.s9s_mb_2u(sch_1):clk_100m_gpu_fpga_dn_r';
NODE_NAME     R3338 1
 '@S9S_MB_2U_LIB.S9S_MB_2U(SCH_1):PAGE201_I76@PURE_QUANTA.Q_RES(CHIPS)':
 'A': CDS_PINID='A';
NODE_NAME     U247 18
 '@S9S_MB_2U_LIB.S9S_MB_2U(SCH_1):PAGE201_I167@PURE_QUANTA.9FGL0251DKILFT(CHIPS)':
 'DIF1#': CDS_PINID='\dif1#\';
NET_NAME
'CLK_100M_GPU_FPGA_DP'
 '@S9S_MB_2U_LIB.S9S_MB_2U(SCH_1):CLK_100M_GPU_FPGA_DP':
 C_SIGNAL='@s9s_mb_2u_lib.s9s_mb_2u(sch_1):clk_100m_gpu_fpga_dp';
NODE_NAME     J112 R2
 '@S9S_MB_2U_LIB.S9S_MB_2U(SCH_1):PAGE149_I76@PURE_QUANTA.CONN160_10131762101LF(CHIPS)':
 'R2': CDS_PINID='R2';
NODE_NAME     R3337 2
 '@S9S_MB_2U_LIB.S9S_MB_2U(SCH_1):PAGE201_I75@PURE_QUANTA.Q_RES(CHIPS)':
 'B': CDS_PINID='B';
NET_NAME
'CLK_100M_GPU_FPGA_DP_R'
 '@S9S_MB_2U_LIB.S9S_MB_2U(SCH_1):CLK_100M_GPU_FPGA_DP_R':
 C_SIGNAL='@s9s_mb_2u_lib.s9s_mb_2u(sch_1):clk_100m_gpu_fpga_dp_r';
NODE_NAME     R3337 1
 '@S9S_MB_2U_LIB.S9S_MB_2U(SCH_1):PAGE201_I75@PURE_QUANTA.Q_RES(CHIPS)':
 'A': CDS_PINID='A';
NODE_NAME     U247 17
 '@S9S_MB_2U_LIB.S9S_MB_2U(SCH_1):PAGE201_I167@PURE_QUANTA.9FGL0251DKILFT(CHIPS)':
 'DIF1': CDS_PINID='DIF1';
NET_NAME
'CLK_100M_GPU_SWB_REF_DN'
 '@S9S_MB_2U_LIB.S9S_MB_2U(SCH_1):CLK_100M_GPU_SWB_REF_DN':
 C_SIGNAL='@s9s_mb_2u_lib.s9s_mb_2u(sch_1):clk_100m_gpu_swb_ref_dn';
NODE_NAME     U38 H12
 '@S9S_MB_2U_LIB.S9S_MB_2U(SCH_1):PAGE195_I119@PURE_QUANTA.9QXL2001BNHGI8(CHIPS)':
 'DIF8#': CDS_PINID='\dif8#\';
NODE_NAME     U314 4
 '@S9S_MB_2U_LIB.S9S_MB_2U(SCH_1):PAGE200_I1@PURE_QUANTA.9ZXL0451EKILFT(CHIPS)':
 'DIF_IN#': CDS_PINID='\dif_in#\';
NET_NAME
'CLK_100M_GPU_SWB_REF_DP'
 '@S9S_MB_2U_LIB.S9S_MB_2U(SCH_1):CLK_100M_GPU_SWB_REF_DP':
 C_SIGNAL='@s9s_mb_2u_lib.s9s_mb_2u(sch_1):clk_100m_gpu_swb_ref_dp';
NODE_NAME     U38 J12
 '@S9S_MB_2U_LIB.S9S_MB_2U(SCH_1):PAGE195_I119@PURE_QUANTA.9QXL2001BNHGI8(CHIPS)':
 'DIF8': CDS_PINID='DIF8';
NODE_NAME     U314 3
 '@S9S_MB_2U_LIB.S9S_MB_2U(SCH_1):PAGE200_I1@PURE_QUANTA.9ZXL0451EKILFT(CHIPS)':
 'DIF_IN': CDS_PINID='DIF_IN';
NET_NAME
'CLK_100M_OCP_SFF_0_DN'
 '@S9S_MB_2U_LIB.S9S_MB_2U(SCH_1):CLK_100M_OCP_SFF_0_DN':
 C_SIGNAL='@s9s_mb_2u_lib.s9s_mb_2u(sch_1):clk_100m_ocp_sff_0_dn';
NODE_NAME     J37 B14
 '@S9S_MB_2U_LIB.S9S_MB_2U(SCH_1):PAGE150_I199@PURE_QUANTA.SCONN168_ME1016810202011(CHIPS)':
 'REFCLKN0': CDS_PINID='REFCLKN0';
NODE_NAME     R564 2
 '@S9S_MB_2U_LIB.S9S_MB_2U(SCH_1):PAGE198_I47@PURE_QUANTA.Q_RES(CHIPS)':
 'B': CDS_PINID='B';
NET_NAME
'CLK_100M_OCP_SFF_0_DP'
 '@S9S_MB_2U_LIB.S9S_MB_2U(SCH_1):CLK_100M_OCP_SFF_0_DP':
 C_SIGNAL='@s9s_mb_2u_lib.s9s_mb_2u(sch_1):clk_100m_ocp_sff_0_dp';
NODE_NAME     J37 B15
 '@S9S_MB_2U_LIB.S9S_MB_2U(SCH_1):PAGE150_I199@PURE_QUANTA.SCONN168_ME1016810202011(CHIPS)':
 'REFCLKP0': CDS_PINID='REFCLKP0';
NODE_NAME     R563 2
 '@S9S_MB_2U_LIB.S9S_MB_2U(SCH_1):PAGE198_I48@PURE_QUANTA.Q_RES(CHIPS)':
 'B': CDS_PINID='B';
NET_NAME
'CLK_100M_OCP_SFF_0_R_DN'
 '@S9S_MB_2U_LIB.S9S_MB_2U(SCH_1):CLK_100M_OCP_SFF_0_R_DN':
 C_SIGNAL='@s9s_mb_2u_lib.s9s_mb_2u(sch_1):clk_100m_ocp_sff_0_r_dn';
NODE_NAME     U38 F12
 '@S9S_MB_2U_LIB.S9S_MB_2U(SCH_1):PAGE195_I119@PURE_QUANTA.9QXL2001BNHGI8(CHIPS)':
 'DIF9#': CDS_PINID='\dif9#\';
NODE_NAME     R564 1
 '@S9S_MB_2U_LIB.S9S_MB_2U(SCH_1):PAGE198_I47@PURE_QUANTA.Q_RES(CHIPS)':
 'A': CDS_PINID='A';
NET_NAME
'CLK_100M_OCP_SFF_0_R_DP'
 '@S9S_MB_2U_LIB.S9S_MB_2U(SCH_1):CLK_100M_OCP_SFF_0_R_DP':
 C_SIGNAL='@s9s_mb_2u_lib.s9s_mb_2u(sch_1):clk_100m_ocp_sff_0_r_dp';
NODE_NAME     U38 G12
 '@S9S_MB_2U_LIB.S9S_MB_2U(SCH_1):PAGE195_I119@PURE_QUANTA.9QXL2001BNHGI8(CHIPS)':
 'DIF9': CDS_PINID='DIF9';
NODE_NAME     R563 1
 '@S9S_MB_2U_LIB.S9S_MB_2U(SCH_1):PAGE198_I48@PURE_QUANTA.Q_RES(CHIPS)':
 'A': CDS_PINID='A';
NET_NAME
'CLK_100M_OCP_SFF_1_DN'
 '@S9S_MB_2U_LIB.S9S_MB_2U(SCH_1):CLK_100M_OCP_SFF_1_DN':
 C_SIGNAL='@s9s_mb_2u_lib.s9s_mb_2u(sch_1):clk_100m_ocp_sff_1_dn';
NODE_NAME     J37 A14
 '@S9S_MB_2U_LIB.S9S_MB_2U(SCH_1):PAGE150_I199@PURE_QUANTA.SCONN168_ME1016810202011(CHIPS)':
 'REFCLKN1': CDS_PINID='REFCLKN1';
NODE_NAME     R566 2
 '@S9S_MB_2U_LIB.S9S_MB_2U(SCH_1):PAGE198_I45@PURE_QUANTA.Q_RES(CHIPS)':
 'B': CDS_PINID='B';
NET_NAME
'CLK_100M_OCP_SFF_1_DP'
 '@S9S_MB_2U_LIB.S9S_MB_2U(SCH_1):CLK_100M_OCP_SFF_1_DP':
 C_SIGNAL='@s9s_mb_2u_lib.s9s_mb_2u(sch_1):clk_100m_ocp_sff_1_dp';
NODE_NAME     J37 A15
 '@S9S_MB_2U_LIB.S9S_MB_2U(SCH_1):PAGE150_I199@PURE_QUANTA.SCONN168_ME1016810202011(CHIPS)':
 'REFCLKP1': CDS_PINID='REFCLKP1';
NODE_NAME     R565 2
 '@S9S_MB_2U_LIB.S9S_MB_2U(SCH_1):PAGE198_I46@PURE_QUANTA.Q_RES(CHIPS)':
 'B': CDS_PINID='B';
NET_NAME
'CLK_100M_OCP_SFF_1_R_DN'
 '@S9S_MB_2U_LIB.S9S_MB_2U(SCH_1):CLK_100M_OCP_SFF_1_R_DN':
 C_SIGNAL='@s9s_mb_2u_lib.s9s_mb_2u(sch_1):clk_100m_ocp_sff_1_r_dn';
NODE_NAME     U38 C12
 '@S9S_MB_2U_LIB.S9S_MB_2U(SCH_1):PAGE195_I119@PURE_QUANTA.9QXL2001BNHGI8(CHIPS)':
 'DIF10#': CDS_PINID='\dif10#\';
NODE_NAME     R566 1
 '@S9S_MB_2U_LIB.S9S_MB_2U(SCH_1):PAGE198_I45@PURE_QUANTA.Q_RES(CHIPS)':
 'A': CDS_PINID='A';
NET_NAME
'CLK_100M_OCP_SFF_1_R_DP'
 '@S9S_MB_2U_LIB.S9S_MB_2U(SCH_1):CLK_100M_OCP_SFF_1_R_DP':
 C_SIGNAL='@s9s_mb_2u_lib.s9s_mb_2u(sch_1):clk_100m_ocp_sff_1_r_dp';
NODE_NAME     U38 D12
 '@S9S_MB_2U_LIB.S9S_MB_2U(SCH_1):PAGE195_I119@PURE_QUANTA.9QXL2001BNHGI8(CHIPS)':
 'DIF10': CDS_PINID='DIF10';
NODE_NAME     R565 1
 '@S9S_MB_2U_LIB.S9S_MB_2U(SCH_1):PAGE198_I46@PURE_QUANTA.Q_RES(CHIPS)':
 'A': CDS_PINID='A';
NET_NAME
'CLK_100M_OCP_SFF_2_DN'
 '@S9S_MB_2U_LIB.S9S_MB_2U(SCH_1):CLK_100M_OCP_SFF_2_DN':
 C_SIGNAL='@s9s_mb_2u_lib.s9s_mb_2u(sch_1):clk_100m_ocp_sff_2_dn';
NODE_NAME     J37 OB11
 '@S9S_MB_2U_LIB.S9S_MB_2U(SCH_1):PAGE150_I199@PURE_QUANTA.SCONN168_ME1016810202011(CHIPS)':
 'REFCLKN2': CDS_PINID='REFCLKN2';
NODE_NAME     R1274 2
 '@S9S_MB_2U_LIB.S9S_MB_2U(SCH_1):PAGE198_I43@PURE_QUANTA.Q_RES(CHIPS)':
 'B': CDS_PINID='B';
NET_NAME
'CLK_100M_OCP_SFF_2_DP'
 '@S9S_MB_2U_LIB.S9S_MB_2U(SCH_1):CLK_100M_OCP_SFF_2_DP':
 C_SIGNAL='@s9s_mb_2u_lib.s9s_mb_2u(sch_1):clk_100m_ocp_sff_2_dp';
NODE_NAME     J37 OB12
 '@S9S_MB_2U_LIB.S9S_MB_2U(SCH_1):PAGE150_I199@PURE_QUANTA.SCONN168_ME1016810202011(CHIPS)':
 'REFCLKP2': CDS_PINID='REFCLKP2';
NODE_NAME     R1273 2
 '@S9S_MB_2U_LIB.S9S_MB_2U(SCH_1):PAGE198_I44@PURE_QUANTA.Q_RES(CHIPS)':
 'B': CDS_PINID='B';
NET_NAME
'CLK_100M_OCP_SFF_2_R_DN'
 '@S9S_MB_2U_LIB.S9S_MB_2U(SCH_1):CLK_100M_OCP_SFF_2_R_DN':
 C_SIGNAL='@s9s_mb_2u_lib.s9s_mb_2u(sch_1):clk_100m_ocp_sff_2_r_dn';
NODE_NAME     U38 A12
 '@S9S_MB_2U_LIB.S9S_MB_2U(SCH_1):PAGE195_I119@PURE_QUANTA.9QXL2001BNHGI8(CHIPS)':
 'DIF11#': CDS_PINID='\dif11#\';
NODE_NAME     R1274 1
 '@S9S_MB_2U_LIB.S9S_MB_2U(SCH_1):PAGE198_I43@PURE_QUANTA.Q_RES(CHIPS)':
 'A': CDS_PINID='A';
NET_NAME
'CLK_100M_OCP_SFF_2_R_DP'
 '@S9S_MB_2U_LIB.S9S_MB_2U(SCH_1):CLK_100M_OCP_SFF_2_R_DP':
 C_SIGNAL='@s9s_mb_2u_lib.s9s_mb_2u(sch_1):clk_100m_ocp_sff_2_r_dp';
NODE_NAME     U38 B12
 '@S9S_MB_2U_LIB.S9S_MB_2U(SCH_1):PAGE195_I119@PURE_QUANTA.9QXL2001BNHGI8(CHIPS)':
 'DIF11': CDS_PINID='DIF11';
NODE_NAME     R1273 1
 '@S9S_MB_2U_LIB.S9S_MB_2U(SCH_1):PAGE198_I44@PURE_QUANTA.Q_RES(CHIPS)':
 'A': CDS_PINID='A';
NET_NAME
'CLK_100M_OCP_SFF_3_DN'
 '@S9S_MB_2U_LIB.S9S_MB_2U(SCH_1):CLK_100M_OCP_SFF_3_DN':
 C_SIGNAL='@s9s_mb_2u_lib.s9s_mb_2u(sch_1):clk_100m_ocp_sff_3_dn';
NODE_NAME     J37 OA11
 '@S9S_MB_2U_LIB.S9S_MB_2U(SCH_1):PAGE150_I199@PURE_QUANTA.SCONN168_ME1016810202011(CHIPS)':
 'REFCLKN3': CDS_PINID='REFCLKN3';
NODE_NAME     R1276 2
 '@S9S_MB_2U_LIB.S9S_MB_2U(SCH_1):PAGE198_I23@PURE_QUANTA.Q_RES(CHIPS)':
 'B': CDS_PINID='B';
NET_NAME
'CLK_100M_OCP_SFF_3_DP'
 '@S9S_MB_2U_LIB.S9S_MB_2U(SCH_1):CLK_100M_OCP_SFF_3_DP':
 C_SIGNAL='@s9s_mb_2u_lib.s9s_mb_2u(sch_1):clk_100m_ocp_sff_3_dp';
NODE_NAME     J37 OA12
 '@S9S_MB_2U_LIB.S9S_MB_2U(SCH_1):PAGE150_I199@PURE_QUANTA.SCONN168_ME1016810202011(CHIPS)':
 'REFCLKP3': CDS_PINID='REFCLKP3';
NODE_NAME     R1275 2
 '@S9S_MB_2U_LIB.S9S_MB_2U(SCH_1):PAGE198_I24@PURE_QUANTA.Q_RES(CHIPS)':
 'B': CDS_PINID='B';
NET_NAME
'CLK_100M_OCP_SFF_3_R_DN'
 '@S9S_MB_2U_LIB.S9S_MB_2U(SCH_1):CLK_100M_OCP_SFF_3_R_DN':
 C_SIGNAL='@s9s_mb_2u_lib.s9s_mb_2u(sch_1):clk_100m_ocp_sff_3_r_dn';
NODE_NAME     U38 A10
 '@S9S_MB_2U_LIB.S9S_MB_2U(SCH_1):PAGE195_I119@PURE_QUANTA.9QXL2001BNHGI8(CHIPS)':
 'DIF12#': CDS_PINID='\dif12#\';
NODE_NAME     R1276 1
 '@S9S_MB_2U_LIB.S9S_MB_2U(SCH_1):PAGE198_I23@PURE_QUANTA.Q_RES(CHIPS)':
 'A': CDS_PINID='A';
NET_NAME
'CLK_100M_OCP_SFF_3_R_DP'
 '@S9S_MB_2U_LIB.S9S_MB_2U(SCH_1):CLK_100M_OCP_SFF_3_R_DP':
 C_SIGNAL='@s9s_mb_2u_lib.s9s_mb_2u(sch_1):clk_100m_ocp_sff_3_r_dp';
NODE_NAME     U38 A11
 '@S9S_MB_2U_LIB.S9S_MB_2U(SCH_1):PAGE195_I119@PURE_QUANTA.9QXL2001BNHGI8(CHIPS)':
 'DIF12': CDS_PINID='DIF12';
NODE_NAME     R1275 1
 '@S9S_MB_2U_LIB.S9S_MB_2U(SCH_1):PAGE198_I24@PURE_QUANTA.Q_RES(CHIPS)':
 'A': CDS_PINID='A';
NET_NAME
'CLK_100M_OCP_V3_2_A_DN'
 '@S9S_MB_2U_LIB.S9S_MB_2U(SCH_1):CLK_100M_OCP_V3_2_A_DN':
 C_SIGNAL='@s9s_mb_2u_lib.s9s_mb_2u(sch_1):clk_100m_ocp_v3_2_a_dn';
NODE_NAME     J35 B14
 '@S9S_MB_2U_LIB.S9S_MB_2U(SCH_1):PAGE146_I303@PURE_QUANTA.SCONN168_ME1016810202011(CHIPS)':
 'REFCLKN0': CDS_PINID='REFCLKN0';
NODE_NAME     R3195 2
 '@S9S_MB_2U_LIB.S9S_MB_2U(SCH_1):PAGE196_I16@PURE_QUANTA.Q_RES(CHIPS)':
 'B': CDS_PINID='B';
NET_NAME
'CLK_100M_OCP_V3_2_A_DP'
 '@S9S_MB_2U_LIB.S9S_MB_2U(SCH_1):CLK_100M_OCP_V3_2_A_DP':
 C_SIGNAL='@s9s_mb_2u_lib.s9s_mb_2u(sch_1):clk_100m_ocp_v3_2_a_dp';
NODE_NAME     J35 B15
 '@S9S_MB_2U_LIB.S9S_MB_2U(SCH_1):PAGE146_I303@PURE_QUANTA.SCONN168_ME1016810202011(CHIPS)':
 'REFCLKP0': CDS_PINID='REFCLKP0';
NODE_NAME     R3194 2
 '@S9S_MB_2U_LIB.S9S_MB_2U(SCH_1):PAGE196_I17@PURE_QUANTA.Q_RES(CHIPS)':
 'B': CDS_PINID='B';
NET_NAME
'CLK_100M_OCP_V3_2_A_R_DN'
 '@S9S_MB_2U_LIB.S9S_MB_2U(SCH_1):CLK_100M_OCP_V3_2_A_R_DN':
 C_SIGNAL='@s9s_mb_2u_lib.s9s_mb_2u(sch_1):clk_100m_ocp_v3_2_a_r_dn';
NODE_NAME     U38 A6
 '@S9S_MB_2U_LIB.S9S_MB_2U(SCH_1):PAGE195_I119@PURE_QUANTA.9QXL2001BNHGI8(CHIPS)':
 'DIF14#': CDS_PINID='\dif14#\';
NODE_NAME     R3195 1
 '@S9S_MB_2U_LIB.S9S_MB_2U(SCH_1):PAGE196_I16@PURE_QUANTA.Q_RES(CHIPS)':
 'A': CDS_PINID='A';
NET_NAME
'CLK_100M_OCP_V3_2_A_R_DP'
 '@S9S_MB_2U_LIB.S9S_MB_2U(SCH_1):CLK_100M_OCP_V3_2_A_R_DP':
 C_SIGNAL='@s9s_mb_2u_lib.s9s_mb_2u(sch_1):clk_100m_ocp_v3_2_a_r_dp';
NODE_NAME     U38 A7
 '@S9S_MB_2U_LIB.S9S_MB_2U(SCH_1):PAGE195_I119@PURE_QUANTA.9QXL2001BNHGI8(CHIPS)':
 'DIF14': CDS_PINID='DIF14';
NODE_NAME     R3194 1
 '@S9S_MB_2U_LIB.S9S_MB_2U(SCH_1):PAGE196_I17@PURE_QUANTA.Q_RES(CHIPS)':
 'A': CDS_PINID='A';
NET_NAME
'CLK_100M_OCP_V3_2_B_DN'
 '@S9S_MB_2U_LIB.S9S_MB_2U(SCH_1):CLK_100M_OCP_V3_2_B_DN':
 C_SIGNAL='@s9s_mb_2u_lib.s9s_mb_2u(sch_1):clk_100m_ocp_v3_2_b_dn';
NODE_NAME     J35 A14
 '@S9S_MB_2U_LIB.S9S_MB_2U(SCH_1):PAGE146_I303@PURE_QUANTA.SCONN168_ME1016810202011(CHIPS)':
 'REFCLKN1': CDS_PINID='REFCLKN1';
NODE_NAME     R3197 2
 '@S9S_MB_2U_LIB.S9S_MB_2U(SCH_1):PAGE196_I14@PURE_QUANTA.Q_RES(CHIPS)':
 'B': CDS_PINID='B';
NET_NAME
'CLK_100M_OCP_V3_2_B_DP'
 '@S9S_MB_2U_LIB.S9S_MB_2U(SCH_1):CLK_100M_OCP_V3_2_B_DP':
 C_SIGNAL='@s9s_mb_2u_lib.s9s_mb_2u(sch_1):clk_100m_ocp_v3_2_b_dp';
NODE_NAME     J35 A15
 '@S9S_MB_2U_LIB.S9S_MB_2U(SCH_1):PAGE146_I303@PURE_QUANTA.SCONN168_ME1016810202011(CHIPS)':
 'REFCLKP1': CDS_PINID='REFCLKP1';
NODE_NAME     R3196 2
 '@S9S_MB_2U_LIB.S9S_MB_2U(SCH_1):PAGE196_I15@PURE_QUANTA.Q_RES(CHIPS)':
 'B': CDS_PINID='B';
NET_NAME
'CLK_100M_OCP_V3_2_B_R_DN'
 '@S9S_MB_2U_LIB.S9S_MB_2U(SCH_1):CLK_100M_OCP_V3_2_B_R_DN':
 C_SIGNAL='@s9s_mb_2u_lib.s9s_mb_2u(sch_1):clk_100m_ocp_v3_2_b_r_dn';
NODE_NAME     U38 A4
 '@S9S_MB_2U_LIB.S9S_MB_2U(SCH_1):PAGE195_I119@PURE_QUANTA.9QXL2001BNHGI8(CHIPS)':
 'DIF15#': CDS_PINID='\dif15#\';
NODE_NAME     R3197 1
 '@S9S_MB_2U_LIB.S9S_MB_2U(SCH_1):PAGE196_I14@PURE_QUANTA.Q_RES(CHIPS)':
 'A': CDS_PINID='A';
NET_NAME
'CLK_100M_OCP_V3_2_B_R_DP'
 '@S9S_MB_2U_LIB.S9S_MB_2U(SCH_1):CLK_100M_OCP_V3_2_B_R_DP':
 C_SIGNAL='@s9s_mb_2u_lib.s9s_mb_2u(sch_1):clk_100m_ocp_v3_2_b_r_dp';
NODE_NAME     U38 A5
 '@S9S_MB_2U_LIB.S9S_MB_2U(SCH_1):PAGE195_I119@PURE_QUANTA.9QXL2001BNHGI8(CHIPS)':
 'DIF15': CDS_PINID='DIF15';
NODE_NAME     R3196 1
 '@S9S_MB_2U_LIB.S9S_MB_2U(SCH_1):PAGE196_I15@PURE_QUANTA.Q_RES(CHIPS)':
 'A': CDS_PINID='A';
NET_NAME
'CLK_100M_OCP_V3_2_C_DN'
 '@S9S_MB_2U_LIB.S9S_MB_2U(SCH_1):CLK_100M_OCP_V3_2_C_DN':
 C_SIGNAL='@s9s_mb_2u_lib.s9s_mb_2u(sch_1):clk_100m_ocp_v3_2_c_dn';
NODE_NAME     J35 OB11
 '@S9S_MB_2U_LIB.S9S_MB_2U(SCH_1):PAGE146_I303@PURE_QUANTA.SCONN168_ME1016810202011(CHIPS)':
 'REFCLKN2': CDS_PINID='REFCLKN2';
NODE_NAME     R3199 2
 '@S9S_MB_2U_LIB.S9S_MB_2U(SCH_1):PAGE196_I12@PURE_QUANTA.Q_RES(CHIPS)':
 'B': CDS_PINID='B';
NET_NAME
'CLK_100M_OCP_V3_2_C_DP'
 '@S9S_MB_2U_LIB.S9S_MB_2U(SCH_1):CLK_100M_OCP_V3_2_C_DP':
 C_SIGNAL='@s9s_mb_2u_lib.s9s_mb_2u(sch_1):clk_100m_ocp_v3_2_c_dp';
NODE_NAME     J35 OB12
 '@S9S_MB_2U_LIB.S9S_MB_2U(SCH_1):PAGE146_I303@PURE_QUANTA.SCONN168_ME1016810202011(CHIPS)':
 'REFCLKP2': CDS_PINID='REFCLKP2';
NODE_NAME     R3198 2
 '@S9S_MB_2U_LIB.S9S_MB_2U(SCH_1):PAGE196_I13@PURE_QUANTA.Q_RES(CHIPS)':
 'B': CDS_PINID='B';
NET_NAME
'CLK_100M_OCP_V3_2_C_R_DN'
 '@S9S_MB_2U_LIB.S9S_MB_2U(SCH_1):CLK_100M_OCP_V3_2_C_R_DN':
 C_SIGNAL='@s9s_mb_2u_lib.s9s_mb_2u(sch_1):clk_100m_ocp_v3_2_c_r_dn';
NODE_NAME     U38 A2
 '@S9S_MB_2U_LIB.S9S_MB_2U(SCH_1):PAGE195_I119@PURE_QUANTA.9QXL2001BNHGI8(CHIPS)':
 'DIF16#': CDS_PINID='\dif16#\';
NODE_NAME     R3199 1
 '@S9S_MB_2U_LIB.S9S_MB_2U(SCH_1):PAGE196_I12@PURE_QUANTA.Q_RES(CHIPS)':
 'A': CDS_PINID='A';
NET_NAME
'CLK_100M_OCP_V3_2_C_R_DP'
 '@S9S_MB_2U_LIB.S9S_MB_2U(SCH_1):CLK_100M_OCP_V3_2_C_R_DP':
 C_SIGNAL='@s9s_mb_2u_lib.s9s_mb_2u(sch_1):clk_100m_ocp_v3_2_c_r_dp';
NODE_NAME     U38 A3
 '@S9S_MB_2U_LIB.S9S_MB_2U(SCH_1):PAGE195_I119@PURE_QUANTA.9QXL2001BNHGI8(CHIPS)':
 'DIF16': CDS_PINID='DIF16';
NODE_NAME     R3198 1
 '@S9S_MB_2U_LIB.S9S_MB_2U(SCH_1):PAGE196_I13@PURE_QUANTA.Q_RES(CHIPS)':
 'A': CDS_PINID='A';
NET_NAME
'CLK_100M_OCP_V3_2_D_DN'
 '@S9S_MB_2U_LIB.S9S_MB_2U(SCH_1):CLK_100M_OCP_V3_2_D_DN':
 C_SIGNAL='@s9s_mb_2u_lib.s9s_mb_2u(sch_1):clk_100m_ocp_v3_2_d_dn';
NODE_NAME     J35 OA11
 '@S9S_MB_2U_LIB.S9S_MB_2U(SCH_1):PAGE146_I303@PURE_QUANTA.SCONN168_ME1016810202011(CHIPS)':
 'REFCLKN3': CDS_PINID='REFCLKN3';
NODE_NAME     R3201 2
 '@S9S_MB_2U_LIB.S9S_MB_2U(SCH_1):PAGE196_I10@PURE_QUANTA.Q_RES(CHIPS)':
 'B': CDS_PINID='B';
NET_NAME
'CLK_100M_OCP_V3_2_D_DP'
 '@S9S_MB_2U_LIB.S9S_MB_2U(SCH_1):CLK_100M_OCP_V3_2_D_DP':
 C_SIGNAL='@s9s_mb_2u_lib.s9s_mb_2u(sch_1):clk_100m_ocp_v3_2_d_dp';
NODE_NAME     J35 OA12
 '@S9S_MB_2U_LIB.S9S_MB_2U(SCH_1):PAGE146_I303@PURE_QUANTA.SCONN168_ME1016810202011(CHIPS)':
 'REFCLKP3': CDS_PINID='REFCLKP3';
NODE_NAME     R3200 2
 '@S9S_MB_2U_LIB.S9S_MB_2U(SCH_1):PAGE196_I11@PURE_QUANTA.Q_RES(CHIPS)':
 'B': CDS_PINID='B';
NET_NAME
'CLK_100M_OCP_V3_2_D_R_DN'
 '@S9S_MB_2U_LIB.S9S_MB_2U(SCH_1):CLK_100M_OCP_V3_2_D_R_DN':
 C_SIGNAL='@s9s_mb_2u_lib.s9s_mb_2u(sch_1):clk_100m_ocp_v3_2_d_r_dn';
NODE_NAME     U38 B1
 '@S9S_MB_2U_LIB.S9S_MB_2U(SCH_1):PAGE195_I119@PURE_QUANTA.9QXL2001BNHGI8(CHIPS)':
 'DIF17#': CDS_PINID='\dif17#\';
NODE_NAME     R3201 1
 '@S9S_MB_2U_LIB.S9S_MB_2U(SCH_1):PAGE196_I10@PURE_QUANTA.Q_RES(CHIPS)':
 'A': CDS_PINID='A';
NET_NAME
'CLK_100M_OCP_V3_2_D_R_DP'
 '@S9S_MB_2U_LIB.S9S_MB_2U(SCH_1):CLK_100M_OCP_V3_2_D_R_DP':
 C_SIGNAL='@s9s_mb_2u_lib.s9s_mb_2u(sch_1):clk_100m_ocp_v3_2_d_r_dp';
NODE_NAME     U38 A1
 '@S9S_MB_2U_LIB.S9S_MB_2U(SCH_1):PAGE195_I119@PURE_QUANTA.9QXL2001BNHGI8(CHIPS)':
 'DIF17': CDS_PINID='DIF17';
NODE_NAME     R3200 1
 '@S9S_MB_2U_LIB.S9S_MB_2U(SCH_1):PAGE196_I11@PURE_QUANTA.Q_RES(CHIPS)':
 'A': CDS_PINID='A';
NET_NAME
'CLK_100M_PE_M2_0_DN'
 '@S9S_MB_2U_LIB.S9S_MB_2U(SCH_1):CLK_100M_PE_M2_0_DN':
 C_SIGNAL='@s9s_mb_2u_lib.s9s_mb_2u(sch_1):clk_100m_pe_m2_0_dn';
NODE_NAME     J59 53
 '@S9S_MB_2U_LIB.S9S_MB_2U(SCH_1):PAGE182_I178@PURE_QUANTA.SCONN75K_APCI0155P004A(CHIPS)':
 'REFCLKN': CDS_PINID='REFCLKN';
NODE_NAME     R4306 2
 '@S9S_MB_2U_LIB.S9S_MB_2U(SCH_1):PAGE171_I117@PURE_QUANTA.Q_RES(CHIPS)':
 'B': CDS_PINID='B';
NET_NAME
'CLK_100M_PE_M2_0_DP'
 '@S9S_MB_2U_LIB.S9S_MB_2U(SCH_1):CLK_100M_PE_M2_0_DP':
 C_SIGNAL='@s9s_mb_2u_lib.s9s_mb_2u(sch_1):clk_100m_pe_m2_0_dp';
NODE_NAME     J59 55
 '@S9S_MB_2U_LIB.S9S_MB_2U(SCH_1):PAGE182_I178@PURE_QUANTA.SCONN75K_APCI0155P004A(CHIPS)':
 'REFCLKP': CDS_PINID='REFCLKP';
NODE_NAME     R4305 2
 '@S9S_MB_2U_LIB.S9S_MB_2U(SCH_1):PAGE171_I116@PURE_QUANTA.Q_RES(CHIPS)':
 'B': CDS_PINID='B';
NET_NAME
'CLK_100M_PE_M2_0_R_DN'
 '@S9S_MB_2U_LIB.S9S_MB_2U(SCH_1):CLK_100M_PE_M2_0_R_DN':
 C_SIGNAL='@s9s_mb_2u_lib.s9s_mb_2u(sch_1):clk_100m_pe_m2_0_r_dn';
NODE_NAME     U4 H21
 '@S9S_MB_2U_LIB.S9S_MB_2U(SCH_1):PAGE171_I78@PURE_QUANTA.EMMITSBURG_REV0P9(CHIPS)':
 'CLKOUT_SRC_N_2': CDS_PINID='CLKOUT_SRC_N_2';
NODE_NAME     R4306 1
 '@S9S_MB_2U_LIB.S9S_MB_2U(SCH_1):PAGE171_I117@PURE_QUANTA.Q_RES(CHIPS)':
 'A': CDS_PINID='A';
NET_NAME
'CLK_100M_PE_M2_0_R_DP'
 '@S9S_MB_2U_LIB.S9S_MB_2U(SCH_1):CLK_100M_PE_M2_0_R_DP':
 C_SIGNAL='@s9s_mb_2u_lib.s9s_mb_2u(sch_1):clk_100m_pe_m2_0_r_dp';
NODE_NAME     U4 K21
 '@S9S_MB_2U_LIB.S9S_MB_2U(SCH_1):PAGE171_I78@PURE_QUANTA.EMMITSBURG_REV0P9(CHIPS)':
 'CLKOUT_SRC_P_2': CDS_PINID='CLKOUT_SRC_P_2';
NODE_NAME     R4305 1
 '@S9S_MB_2U_LIB.S9S_MB_2U(SCH_1):PAGE171_I116@PURE_QUANTA.Q_RES(CHIPS)':
 'A': CDS_PINID='A';
NET_NAME
'CLK_100M_SWB_DN'
 '@S9S_MB_2U_LIB.S9S_MB_2U(SCH_1):CLK_100M_SWB_DN':
 C_SIGNAL='@s9s_mb_2u_lib.s9s_mb_2u(sch_1):clk_100m_swb_dn';
NODE_NAME     J112 O3
 '@S9S_MB_2U_LIB.S9S_MB_2U(SCH_1):PAGE149_I76@PURE_QUANTA.CONN160_10131762101LF(CHIPS)':
 'O3': CDS_PINID='O3';
NODE_NAME     R2660 2
 '@S9S_MB_2U_LIB.S9S_MB_2U(SCH_1):PAGE196_I28@PURE_QUANTA.Q_RES(CHIPS)':
 'B': CDS_PINID='B';
NET_NAME
'CLK_100M_SWB_DP'
 '@S9S_MB_2U_LIB.S9S_MB_2U(SCH_1):CLK_100M_SWB_DP':
 C_SIGNAL='@s9s_mb_2u_lib.s9s_mb_2u(sch_1):clk_100m_swb_dp';
NODE_NAME     J112 P3
 '@S9S_MB_2U_LIB.S9S_MB_2U(SCH_1):PAGE149_I76@PURE_QUANTA.CONN160_10131762101LF(CHIPS)':
 'P3': CDS_PINID='P3';
NODE_NAME     R2659 2
 '@S9S_MB_2U_LIB.S9S_MB_2U(SCH_1):PAGE196_I27@PURE_QUANTA.Q_RES(CHIPS)':
 'B': CDS_PINID='B';
NET_NAME
'CLK_100M_SWB_R_DN'
 '@S9S_MB_2U_LIB.S9S_MB_2U(SCH_1):CLK_100M_SWB_R_DN':
 C_SIGNAL='@s9s_mb_2u_lib.s9s_mb_2u(sch_1):clk_100m_swb_r_dn';
NODE_NAME     U314 14
 '@S9S_MB_2U_LIB.S9S_MB_2U(SCH_1):PAGE200_I1@PURE_QUANTA.9ZXL0451EKILFT(CHIPS)':
 'DIF0#': CDS_PINID='\dif0#\';
NODE_NAME     R2660 1
 '@S9S_MB_2U_LIB.S9S_MB_2U(SCH_1):PAGE196_I28@PURE_QUANTA.Q_RES(CHIPS)':
 'A': CDS_PINID='A';
NET_NAME
'CLK_100M_SWB_R_DP'
 '@S9S_MB_2U_LIB.S9S_MB_2U(SCH_1):CLK_100M_SWB_R_DP':
 C_SIGNAL='@s9s_mb_2u_lib.s9s_mb_2u(sch_1):clk_100m_swb_r_dp';
NODE_NAME     U314 13
 '@S9S_MB_2U_LIB.S9S_MB_2U(SCH_1):PAGE200_I1@PURE_QUANTA.9ZXL0451EKILFT(CHIPS)':
 'DIF0': CDS_PINID='DIF0';
NODE_NAME     R2659 1
 '@S9S_MB_2U_LIB.S9S_MB_2U(SCH_1):PAGE196_I27@PURE_QUANTA.Q_RES(CHIPS)':
 'A': CDS_PINID='A';
NET_NAME
'CLK_24M_66M_LPC0_ESPI'
 '@S9S_MB_2U_LIB.S9S_MB_2U(SCH_1):CLK_24M_66M_LPC0_ESPI':
 C_SIGNAL='@s9s_mb_2u_lib.s9s_mb_2u(sch_1):clk_24m_66m_lpc0_espi';
NODE_NAME     U4 BD13
 '@S9S_MB_2U_LIB.S9S_MB_2U(SCH_1):PAGE175_I93@PURE_QUANTA.EMMITSBURG_REV0P9(CHIPS)':
 'GPPC_A_9_ESPI_CLK': CDS_PINID='GPPC_A_9_ESPI_CLK';
NODE_NAME     R1872 1
 '@S9S_MB_2U_LIB.S9S_MB_2U(SCH_1):PAGE190_I100@PURE_QUANTA.Q_RES(CHIPS)':
 'A': CDS_PINID='A';
NET_NAME
'CLK_25M_CK440_CPU0_DN'
 '@S9S_MB_2U_LIB.S9S_MB_2U(SCH_1):CLK_25M_CK440_CPU0_DN':
 C_SIGNAL='@s9s_mb_2u_lib.s9s_mb_2u(sch_1):clk_25m_ck440_cpu0_dn';
NODE_NAME     U13 A4
 '@S9S_MB_2U_LIB.S9S_MB_2U(SCH_1):PAGE197_I180@PURE_QUANTA.9SQ440NQQI8(CHIPS)':
 '25M0#': CDS_PINID='\25m0#\';
NODE_NAME     R1014 1
 '@S9S_MB_2U_LIB.S9S_MB_2U(SCH_1):PAGE198_I20@PURE_QUANTA.Q_RES(CHIPS)':
 'A': CDS_PINID='A';
NET_NAME
'CLK_25M_CK440_CPU0_DP'
 '@S9S_MB_2U_LIB.S9S_MB_2U(SCH_1):CLK_25M_CK440_CPU0_DP':
 C_SIGNAL='@s9s_mb_2u_lib.s9s_mb_2u(sch_1):clk_25m_ck440_cpu0_dp';
NODE_NAME     U13 A5
 '@S9S_MB_2U_LIB.S9S_MB_2U(SCH_1):PAGE197_I180@PURE_QUANTA.9SQ440NQQI8(CHIPS)':
 '25M0': CDS_PINID='\25m0\';
NODE_NAME     R1012 1
 '@S9S_MB_2U_LIB.S9S_MB_2U(SCH_1):PAGE198_I22@PURE_QUANTA.Q_RES(CHIPS)':
 'A': CDS_PINID='A';
NET_NAME
'CLK_25M_CK440_CPU0_R_DN'
 '@S9S_MB_2U_LIB.S9S_MB_2U(SCH_1):CLK_25M_CK440_CPU0_R_DN':
 C_SIGNAL='@s9s_mb_2u_lib.s9s_mb_2u(sch_1):clk_25m_ck440_cpu0_r_dn';
NODE_NAME     R1014 2
 '@S9S_MB_2U_LIB.S9S_MB_2U(SCH_1):PAGE198_I20@PURE_QUANTA.Q_RES(CHIPS)':
 'B': CDS_PINID='B';
NODE_NAME     R1021 1
 '@S9S_MB_2U_LIB.S9S_MB_2U(SCH_1):PAGE198_I29@PURE_QUANTA.Q_RES(CHIPS)':
 'A': CDS_PINID='A';
NET_NAME
'CLK_25M_CK440_CPU0_R_DP'
 '@S9S_MB_2U_LIB.S9S_MB_2U(SCH_1):CLK_25M_CK440_CPU0_R_DP':
 C_SIGNAL='@s9s_mb_2u_lib.s9s_mb_2u(sch_1):clk_25m_ck440_cpu0_r_dp';
NODE_NAME     R1012 2
 '@S9S_MB_2U_LIB.S9S_MB_2U(SCH_1):PAGE198_I22@PURE_QUANTA.Q_RES(CHIPS)':
 'B': CDS_PINID='B';
NODE_NAME     R1020 1
 '@S9S_MB_2U_LIB.S9S_MB_2U(SCH_1):PAGE198_I30@PURE_QUANTA.Q_RES(CHIPS)':
 'A': CDS_PINID='A';
NET_NAME
'CLK_25M_CK440_CPU1_DN'
 '@S9S_MB_2U_LIB.S9S_MB_2U(SCH_1):CLK_25M_CK440_CPU1_DN':
 C_SIGNAL='@s9s_mb_2u_lib.s9s_mb_2u(sch_1):clk_25m_ck440_cpu1_dn';
NODE_NAME     U13 A2
 '@S9S_MB_2U_LIB.S9S_MB_2U(SCH_1):PAGE197_I180@PURE_QUANTA.9SQ440NQQI8(CHIPS)':
 '25M1#': CDS_PINID='\25m1#\';
NODE_NAME     R1018 1
 '@S9S_MB_2U_LIB.S9S_MB_2U(SCH_1):PAGE198_I10@PURE_QUANTA.Q_RES(CHIPS)':
 'A': CDS_PINID='A';
NET_NAME
'CLK_25M_CK440_CPU1_DP'
 '@S9S_MB_2U_LIB.S9S_MB_2U(SCH_1):CLK_25M_CK440_CPU1_DP':
 C_SIGNAL='@s9s_mb_2u_lib.s9s_mb_2u(sch_1):clk_25m_ck440_cpu1_dp';
NODE_NAME     U13 A3
 '@S9S_MB_2U_LIB.S9S_MB_2U(SCH_1):PAGE197_I180@PURE_QUANTA.9SQ440NQQI8(CHIPS)':
 '25M1': CDS_PINID='\25m1\';
NODE_NAME     R1016 1
 '@S9S_MB_2U_LIB.S9S_MB_2U(SCH_1):PAGE198_I12@PURE_QUANTA.Q_RES(CHIPS)':
 'A': CDS_PINID='A';
NET_NAME
'CLK_25M_CK440_CPU1_R_DN'
 '@S9S_MB_2U_LIB.S9S_MB_2U(SCH_1):CLK_25M_CK440_CPU1_R_DN':
 C_SIGNAL='@s9s_mb_2u_lib.s9s_mb_2u(sch_1):clk_25m_ck440_cpu1_r_dn';
NODE_NAME     R1018 2
 '@S9S_MB_2U_LIB.S9S_MB_2U(SCH_1):PAGE198_I10@PURE_QUANTA.Q_RES(CHIPS)':
 'B': CDS_PINID='B';
NODE_NAME     R1023 1
 '@S9S_MB_2U_LIB.S9S_MB_2U(SCH_1):PAGE198_I27@PURE_QUANTA.Q_RES(CHIPS)':
 'A': CDS_PINID='A';
NET_NAME
'CLK_25M_CK440_CPU1_R_DP'
 '@S9S_MB_2U_LIB.S9S_MB_2U(SCH_1):CLK_25M_CK440_CPU1_R_DP':
 C_SIGNAL='@s9s_mb_2u_lib.s9s_mb_2u(sch_1):clk_25m_ck440_cpu1_r_dp';
NODE_NAME     R1016 2
 '@S9S_MB_2U_LIB.S9S_MB_2U(SCH_1):PAGE198_I12@PURE_QUANTA.Q_RES(CHIPS)':
 'B': CDS_PINID='B';
NODE_NAME     R1022 1
 '@S9S_MB_2U_LIB.S9S_MB_2U(SCH_1):PAGE198_I28@PURE_QUANTA.Q_RES(CHIPS)':
 'A': CDS_PINID='A';
NET_NAME
'CLK_25M_CK440_ISCLK_REF_DN'
 '@S9S_MB_2U_LIB.S9S_MB_2U(SCH_1):CLK_25M_CK440_ISCLK_REF_DN':
 C_SIGNAL='@s9s_mb_2u_lib.s9s_mb_2u(sch_1):clk_25m_ck440_isclk_ref_dn';
NODE_NAME     U13 A55
 '@S9S_MB_2U_LIB.S9S_MB_2U(SCH_1):PAGE197_I180@PURE_QUANTA.9SQ440NQQI8(CHIPS)':
 '25M2#': CDS_PINID='\25m2#\';
NODE_NAME     R1011 1
 '@S9S_MB_2U_LIB.S9S_MB_2U(SCH_1):PAGE198_I7@PURE_QUANTA.Q_RES(CHIPS)':
 'A': CDS_PINID='A';
NET_NAME
'CLK_25M_CK440_ISCLK_REF_DP'
 '@S9S_MB_2U_LIB.S9S_MB_2U(SCH_1):CLK_25M_CK440_ISCLK_REF_DP':
 C_SIGNAL='@s9s_mb_2u_lib.s9s_mb_2u(sch_1):clk_25m_ck440_isclk_ref_dp';
NODE_NAME     U13 A56
 '@S9S_MB_2U_LIB.S9S_MB_2U(SCH_1):PAGE197_I180@PURE_QUANTA.9SQ440NQQI8(CHIPS)':
 '25M2': CDS_PINID='\25m2\';
NODE_NAME     R1010 1
 '@S9S_MB_2U_LIB.S9S_MB_2U(SCH_1):PAGE198_I8@PURE_QUANTA.Q_RES(CHIPS)':
 'A': CDS_PINID='A';
NET_NAME
'CLK_25M_NSSC_CPU0_DN'
 '@S9S_MB_2U_LIB.S9S_MB_2U(SCH_1):CLK_25M_NSSC_CPU0_DN':
 C_SIGNAL='@s9s_mb_2u_lib.s9s_mb_2u(sch_1):clk_25m_nssc_cpu0_dn';
NODE_NAME     U2 CW31
 '@S9S_MB_2U_LIB.S9S_MB_2U(SCH_1):PAGE13_I57@PURE_QUANTA.SOCKET4677_AZIF0045P001C01CS(CHIPS)':
 'XTAL_CLK_DN': CDS_PINID='XTAL_CLK_DN';
NODE_NAME     R1015 2
 '@S9S_MB_2U_LIB.S9S_MB_2U(SCH_1):PAGE198_I19@PURE_QUANTA.Q_RES(CHIPS)':
 'B': CDS_PINID='B';
NODE_NAME     R1021 2
 '@S9S_MB_2U_LIB.S9S_MB_2U(SCH_1):PAGE198_I29@PURE_QUANTA.Q_RES(CHIPS)':
 'B': CDS_PINID='B';
NET_NAME
'CLK_25M_NSSC_CPU0_DP'
 '@S9S_MB_2U_LIB.S9S_MB_2U(SCH_1):CLK_25M_NSSC_CPU0_DP':
 C_SIGNAL='@s9s_mb_2u_lib.s9s_mb_2u(sch_1):clk_25m_nssc_cpu0_dp';
NODE_NAME     U2 CY32
 '@S9S_MB_2U_LIB.S9S_MB_2U(SCH_1):PAGE13_I57@PURE_QUANTA.SOCKET4677_AZIF0045P001C01CS(CHIPS)':
 'XTAL_CLK_DP': CDS_PINID='XTAL_CLK_DP';
NODE_NAME     R1013 2
 '@S9S_MB_2U_LIB.S9S_MB_2U(SCH_1):PAGE198_I21@PURE_QUANTA.Q_RES(CHIPS)':
 'B': CDS_PINID='B';
NODE_NAME     R1020 2
 '@S9S_MB_2U_LIB.S9S_MB_2U(SCH_1):PAGE198_I30@PURE_QUANTA.Q_RES(CHIPS)':
 'B': CDS_PINID='B';
NET_NAME
'CLK_25M_NSSC_CPU1_DN'
 '@S9S_MB_2U_LIB.S9S_MB_2U(SCH_1):CLK_25M_NSSC_CPU1_DN':
 C_SIGNAL='@s9s_mb_2u_lib.s9s_mb_2u(sch_1):clk_25m_nssc_cpu1_dn';
NODE_NAME     U1 CW31
 '@S9S_MB_2U_LIB.S9S_MB_2U(SCH_1):PAGE44_I51@PURE_QUANTA.SOCKET4677_AZIF0045P001C01CS(CHIPS)':
 'XTAL_CLK_DN': CDS_PINID='XTAL_CLK_DN';
NODE_NAME     R1019 2
 '@S9S_MB_2U_LIB.S9S_MB_2U(SCH_1):PAGE198_I9@PURE_QUANTA.Q_RES(CHIPS)':
 'B': CDS_PINID='B';
NODE_NAME     R1023 2
 '@S9S_MB_2U_LIB.S9S_MB_2U(SCH_1):PAGE198_I27@PURE_QUANTA.Q_RES(CHIPS)':
 'B': CDS_PINID='B';
NET_NAME
'CLK_25M_NSSC_CPU1_DP'
 '@S9S_MB_2U_LIB.S9S_MB_2U(SCH_1):CLK_25M_NSSC_CPU1_DP':
 C_SIGNAL='@s9s_mb_2u_lib.s9s_mb_2u(sch_1):clk_25m_nssc_cpu1_dp';
NODE_NAME     U1 CY32
 '@S9S_MB_2U_LIB.S9S_MB_2U(SCH_1):PAGE44_I51@PURE_QUANTA.SOCKET4677_AZIF0045P001C01CS(CHIPS)':
 'XTAL_CLK_DP': CDS_PINID='XTAL_CLK_DP';
NODE_NAME     R1017 2
 '@S9S_MB_2U_LIB.S9S_MB_2U(SCH_1):PAGE198_I11@PURE_QUANTA.Q_RES(CHIPS)':
 'B': CDS_PINID='B';
NODE_NAME     R1022 2
 '@S9S_MB_2U_LIB.S9S_MB_2U(SCH_1):PAGE198_I28@PURE_QUANTA.Q_RES(CHIPS)':
 'B': CDS_PINID='B';
NET_NAME
'CLK_25M_OSC_FPGA_R'
 '@S9S_MB_2U_LIB.S9S_MB_2U(SCH_1):CLK_25M_OSC_FPGA_R':
 C_SIGNAL='@s9s_mb_2u_lib.s9s_mb_2u(sch_1):clk_25m_osc_fpga_r';
NODE_NAME     R1100 1
 '@S9S_MB_2U_LIB.S9S_MB_2U(SCH_1):PAGE313_I115@PURE_QUANTA.Q_RES(CHIPS)':
 'A': CDS_PINID='A';
NODE_NAME     OSC2 3
 '@S9S_MB_2U_LIB.S9S_MB_2U(SCH_1):PAGE313_I127@PURE_QUANTA.Q_OSC4P(CHIPS)':
 'OUT': CDS_PINID='\out\';
NET_NAME
'CLK_25M_OSC_MAIN_FPGA'
 '@S9S_MB_2U_LIB.S9S_MB_2U(SCH_1):CLK_25M_OSC_MAIN_FPGA':
 C_SIGNAL='@s9s_mb_2u_lib.s9s_mb_2u(sch_1):clk_25m_osc_main_fpga';
NODE_NAME     R1100 2
 '@S9S_MB_2U_LIB.S9S_MB_2U(SCH_1):PAGE313_I115@PURE_QUANTA.Q_RES(CHIPS)':
 'B': CDS_PINID='B';
NODE_NAME     U249 AA10
 '@S9S_MB_2U_LIB.S9S_MB_2U(SCH_1):PAGE312_I1@PURE_QUANTA.LCMXO3LF9400C5BG484C(CHIPS)':
 'PB22A||PCLKT2_0': CDS_PINID='\pb22a||pclkt2_0\';
NET_NAME
'CLK_25M_PCH_CPU0_DN'
 '@S9S_MB_2U_LIB.S9S_MB_2U(SCH_1):CLK_25M_PCH_CPU0_DN':
 C_SIGNAL='@s9s_mb_2u_lib.s9s_mb_2u(sch_1):clk_25m_pch_cpu0_dn';
NODE_NAME     U4 D27
 '@S9S_MB_2U_LIB.S9S_MB_2U(SCH_1):PAGE171_I78@PURE_QUANTA.EMMITSBURG_REV0P9(CHIPS)':
 'PMSYNC_CLK_N_0': CDS_PINID='PMSYNC_CLK_N_0';
NODE_NAME     R1015 1
 '@S9S_MB_2U_LIB.S9S_MB_2U(SCH_1):PAGE198_I19@PURE_QUANTA.Q_RES(CHIPS)':
 'A': CDS_PINID='A';
NET_NAME
'CLK_25M_PCH_CPU0_DP'
 '@S9S_MB_2U_LIB.S9S_MB_2U(SCH_1):CLK_25M_PCH_CPU0_DP':
 C_SIGNAL='@s9s_mb_2u_lib.s9s_mb_2u(sch_1):clk_25m_pch_cpu0_dp';
NODE_NAME     U4 B27
 '@S9S_MB_2U_LIB.S9S_MB_2U(SCH_1):PAGE171_I78@PURE_QUANTA.EMMITSBURG_REV0P9(CHIPS)':
 'PMSYNC_CLK_P_0': CDS_PINID='PMSYNC_CLK_P_0';
NODE_NAME     R1013 1
 '@S9S_MB_2U_LIB.S9S_MB_2U(SCH_1):PAGE198_I21@PURE_QUANTA.Q_RES(CHIPS)':
 'A': CDS_PINID='A';
NET_NAME
'CLK_25M_PCH_CPU1_DN'
 '@S9S_MB_2U_LIB.S9S_MB_2U(SCH_1):CLK_25M_PCH_CPU1_DN':
 C_SIGNAL='@s9s_mb_2u_lib.s9s_mb_2u(sch_1):clk_25m_pch_cpu1_dn';
NODE_NAME     U4 C28
 '@S9S_MB_2U_LIB.S9S_MB_2U(SCH_1):PAGE171_I78@PURE_QUANTA.EMMITSBURG_REV0P9(CHIPS)':
 'PMSYNC_CLK_N_1': CDS_PINID='PMSYNC_CLK_N_1';
NODE_NAME     R1019 1
 '@S9S_MB_2U_LIB.S9S_MB_2U(SCH_1):PAGE198_I9@PURE_QUANTA.Q_RES(CHIPS)':
 'A': CDS_PINID='A';
NET_NAME
'CLK_25M_PCH_CPU1_DP'
 '@S9S_MB_2U_LIB.S9S_MB_2U(SCH_1):CLK_25M_PCH_CPU1_DP':
 C_SIGNAL='@s9s_mb_2u_lib.s9s_mb_2u(sch_1):clk_25m_pch_cpu1_dp';
NODE_NAME     U4 A28
 '@S9S_MB_2U_LIB.S9S_MB_2U(SCH_1):PAGE171_I78@PURE_QUANTA.EMMITSBURG_REV0P9(CHIPS)':
 'PMSYNC_CLK_P_1': CDS_PINID='PMSYNC_CLK_P_1';
NODE_NAME     R1017 1
 '@S9S_MB_2U_LIB.S9S_MB_2U(SCH_1):PAGE198_I11@PURE_QUANTA.Q_RES(CHIPS)':
 'A': CDS_PINID='A';
NET_NAME
'CLK_25M_PCH_REF_NS_DN'
 '@S9S_MB_2U_LIB.S9S_MB_2U(SCH_1):CLK_25M_PCH_REF_NS_DN':
 C_SIGNAL='@s9s_mb_2u_lib.s9s_mb_2u(sch_1):clk_25m_pch_ref_ns_dn';
NODE_NAME     U4 D25
 '@S9S_MB_2U_LIB.S9S_MB_2U(SCH_1):PAGE171_I78@PURE_QUANTA.EMMITSBURG_REV0P9(CHIPS)':
 'REFCLK_INJ_NS_N': CDS_PINID='REFCLK_INJ_NS_N';
NODE_NAME     R1011 2
 '@S9S_MB_2U_LIB.S9S_MB_2U(SCH_1):PAGE198_I7@PURE_QUANTA.Q_RES(CHIPS)':
 'B': CDS_PINID='B';
NET_NAME
'CLK_25M_PCH_REF_NS_DP'
 '@S9S_MB_2U_LIB.S9S_MB_2U(SCH_1):CLK_25M_PCH_REF_NS_DP':
 C_SIGNAL='@s9s_mb_2u_lib.s9s_mb_2u(sch_1):clk_25m_pch_ref_ns_dp';
NODE_NAME     U4 B25
 '@S9S_MB_2U_LIB.S9S_MB_2U(SCH_1):PAGE171_I78@PURE_QUANTA.EMMITSBURG_REV0P9(CHIPS)':
 'REFCLK_INJ_NS_P': CDS_PINID='REFCLK_INJ_NS_P';
NODE_NAME     R1010 2
 '@S9S_MB_2U_LIB.S9S_MB_2U(SCH_1):PAGE198_I8@PURE_QUANTA.Q_RES(CHIPS)':
 'B': CDS_PINID='B';
NET_NAME
'CLK_50M_BMC_MAC_R'
 '@S9S_MB_2U_LIB.S9S_MB_2U(SCH_1):CLK_50M_BMC_MAC_R':
 C_SIGNAL='@s9s_mb_2u_lib.s9s_mb_2u(sch_1):clk_50m_bmc_mac_r';
NODE_NAME     U90 3
 '@S9S_MB_2U_LIB.S9S_MB_2U(SCH_1):PAGE152_I46@PURE_QUANTA.PI6CV304LE(CHIPS)':
 'Y0': CDS_PINID='Y0';
NODE_NAME     R1140 1
 '@S9S_MB_2U_LIB.S9S_MB_2U(SCH_1):PAGE152_I52@PURE_QUANTA.Q_RES(CHIPS)':
 'A': CDS_PINID='A';
NET_NAME
'CLK_50M_EN'
 '@S9S_MB_2U_LIB.S9S_MB_2U(SCH_1):CLK_50M_EN':
 C_SIGNAL='@s9s_mb_2u_lib.s9s_mb_2u(sch_1):clk_50m_en';
NODE_NAME     U90 2
 '@S9S_MB_2U_LIB.S9S_MB_2U(SCH_1):PAGE152_I46@PURE_QUANTA.PI6CV304LE(CHIPS)':
 'OE': CDS_PINID='OE';
NODE_NAME     R1138 2
 '@S9S_MB_2U_LIB.S9S_MB_2U(SCH_1):PAGE152_I61@PURE_QUANTA.Q_RES(CHIPS)':
 'B': CDS_PINID='B';
NODE_NAME     OSC1 1
 '@S9S_MB_2U_LIB.S9S_MB_2U(SCH_1):PAGE152_I76@PURE_QUANTA.Q_OSC4P(CHIPS)':
 'OE': CDS_PINID='OE';
NET_NAME
'CLK_50M_NCSI_OCP_1'
 '@S9S_MB_2U_LIB.S9S_MB_2U(SCH_1):CLK_50M_NCSI_OCP_1':
 C_SIGNAL='@s9s_mb_2u_lib.s9s_mb_2u(sch_1):clk_50m_ncsi_ocp_1';
NODE_NAME     U90 5
 '@S9S_MB_2U_LIB.S9S_MB_2U(SCH_1):PAGE152_I46@PURE_QUANTA.PI6CV304LE(CHIPS)':
 'Y1': CDS_PINID='Y1';
NODE_NAME     R1141 1
 '@S9S_MB_2U_LIB.S9S_MB_2U(SCH_1):PAGE152_I53@PURE_QUANTA.Q_RES(CHIPS)':
 'A': CDS_PINID='A';
NET_NAME
'CLK_50M_NCSI_OCP_2'
 '@S9S_MB_2U_LIB.S9S_MB_2U(SCH_1):CLK_50M_NCSI_OCP_2':
 C_SIGNAL='@s9s_mb_2u_lib.s9s_mb_2u(sch_1):clk_50m_ncsi_ocp_2';
NODE_NAME     U90 7
 '@S9S_MB_2U_LIB.S9S_MB_2U(SCH_1):PAGE152_I46@PURE_QUANTA.PI6CV304LE(CHIPS)':
 'Y2': CDS_PINID='Y2';
NODE_NAME     R3181 1
 '@S9S_MB_2U_LIB.S9S_MB_2U(SCH_1):PAGE152_I78@PURE_QUANTA.Q_RES(CHIPS)':
 'A': CDS_PINID='A';
NET_NAME
'CLK_50M_NCSI_OCP_SFF'
 '@S9S_MB_2U_LIB.S9S_MB_2U(SCH_1):CLK_50M_NCSI_OCP_SFF':
 C_SIGNAL='@s9s_mb_2u_lib.s9s_mb_2u(sch_1):clk_50m_ncsi_ocp_sff';
NODE_NAME     R1141 2
 '@S9S_MB_2U_LIB.S9S_MB_2U(SCH_1):PAGE152_I53@PURE_QUANTA.Q_RES(CHIPS)':
 'B': CDS_PINID='B';
NODE_NAME     U320 1
 '@S9S_MB_2U_LIB.S9S_MB_2U(SCH_1):PAGE152_I92@PURE_QUANTA.74LVC1G66GV(CHIPS)':
 'Y': CDS_PINID='Y';
NET_NAME
'CLK_50M_NCSI_OCP_SFF_ISO'
 '@S9S_MB_2U_LIB.S9S_MB_2U(SCH_1):CLK_50M_NCSI_OCP_SFF_ISO':
 C_SIGNAL='@s9s_mb_2u_lib.s9s_mb_2u(sch_1):clk_50m_ncsi_ocp_sff_iso';
NODE_NAME     J37 OA14
 '@S9S_MB_2U_LIB.S9S_MB_2U(SCH_1):PAGE150_I199@PURE_QUANTA.SCONN168_ME1016810202011(CHIPS)':
 'RBT_CLK_IN': CDS_PINID='RBT_CLK_IN';
NODE_NAME     R4601 1
 '@S9S_MB_2U_LIB.S9S_MB_2U(SCH_1):PAGE152_I90@PURE_QUANTA.Q_RES(CHIPS)':
 'A': CDS_PINID='A';
NET_NAME
'CLK_50M_NCSI_OCP_SFF_ISO_R'
 '@S9S_MB_2U_LIB.S9S_MB_2U(SCH_1):CLK_50M_NCSI_OCP_SFF_ISO_R':
 C_SIGNAL='@s9s_mb_2u_lib.s9s_mb_2u(sch_1):clk_50m_ncsi_ocp_sff_iso_r';
NODE_NAME     R4601 2
 '@S9S_MB_2U_LIB.S9S_MB_2U(SCH_1):PAGE152_I90@PURE_QUANTA.Q_RES(CHIPS)':
 'B': CDS_PINID='B';
NODE_NAME     U320 2
 '@S9S_MB_2U_LIB.S9S_MB_2U(SCH_1):PAGE152_I92@PURE_QUANTA.74LVC1G66GV(CHIPS)':
 'Z': CDS_PINID='Z';
NET_NAME
'CLK_50M_NCSI_OCP_V3_2'
 '@S9S_MB_2U_LIB.S9S_MB_2U(SCH_1):CLK_50M_NCSI_OCP_V3_2':
 C_SIGNAL='@s9s_mb_2u_lib.s9s_mb_2u(sch_1):clk_50m_ncsi_ocp_v3_2';
NODE_NAME     R3181 2
 '@S9S_MB_2U_LIB.S9S_MB_2U(SCH_1):PAGE152_I78@PURE_QUANTA.Q_RES(CHIPS)':
 'B': CDS_PINID='B';
NODE_NAME     U321 1
 '@S9S_MB_2U_LIB.S9S_MB_2U(SCH_1):PAGE156_I92@PURE_QUANTA.74LVC1G66GV(CHIPS)':
 'Y': CDS_PINID='Y';
NET_NAME
'CLK_50M_NCSI_OCP_V3_2_ISO'
 '@S9S_MB_2U_LIB.S9S_MB_2U(SCH_1):CLK_50M_NCSI_OCP_V3_2_ISO':
 C_SIGNAL='@s9s_mb_2u_lib.s9s_mb_2u(sch_1):clk_50m_ncsi_ocp_v3_2_iso';
NODE_NAME     J35 OA14
 '@S9S_MB_2U_LIB.S9S_MB_2U(SCH_1):PAGE146_I303@PURE_QUANTA.SCONN168_ME1016810202011(CHIPS)':
 'RBT_CLK_IN': CDS_PINID='RBT_CLK_IN';
NODE_NAME     R4602 1
 '@S9S_MB_2U_LIB.S9S_MB_2U(SCH_1):PAGE156_I90@PURE_QUANTA.Q_RES(CHIPS)':
 'A': CDS_PINID='A';
NET_NAME
'CLK_50M_NCSI_OCP_V3_2_ISO_R'
 '@S9S_MB_2U_LIB.S9S_MB_2U(SCH_1):CLK_50M_NCSI_OCP_V3_2_ISO_R':
 C_SIGNAL='@s9s_mb_2u_lib.s9s_mb_2u(sch_1):clk_50m_ncsi_ocp_v3_2_iso_r';
NODE_NAME     R4602 2
 '@S9S_MB_2U_LIB.S9S_MB_2U(SCH_1):PAGE156_I90@PURE_QUANTA.Q_RES(CHIPS)':
 'B': CDS_PINID='B';
NODE_NAME     U321 2
 '@S9S_MB_2U_LIB.S9S_MB_2U(SCH_1):PAGE156_I92@PURE_QUANTA.74LVC1G66GV(CHIPS)':
 'Z': CDS_PINID='Z';
NET_NAME
'CLK_50M_RMII'
 '@S9S_MB_2U_LIB.S9S_MB_2U(SCH_1):CLK_50M_RMII':
 C_SIGNAL='@s9s_mb_2u_lib.s9s_mb_2u(sch_1):clk_50m_rmii';
NODE_NAME     R1139 1
 '@S9S_MB_2U_LIB.S9S_MB_2U(SCH_1):PAGE152_I56@PURE_QUANTA.Q_RES(CHIPS)':
 'A': CDS_PINID='A';
NODE_NAME     OSC1 3
 '@S9S_MB_2U_LIB.S9S_MB_2U(SCH_1):PAGE152_I76@PURE_QUANTA.Q_OSC4P(CHIPS)':
 'OUT': CDS_PINID='\out\';
NET_NAME
'CLK_50M_RMII_BMC_OCP'
 '@S9S_MB_2U_LIB.S9S_MB_2U(SCH_1):CLK_50M_RMII_BMC_OCP':
 C_SIGNAL='@s9s_mb_2u_lib.s9s_mb_2u(sch_1):clk_50m_rmii_bmc_ocp';
NODE_NAME     R1140 2
 '@S9S_MB_2U_LIB.S9S_MB_2U(SCH_1):PAGE152_I52@PURE_QUANTA.Q_RES(CHIPS)':
 'B': CDS_PINID='B';
NODE_NAME     J41 B18
 '@S9S_MB_2U_LIB.S9S_MB_2U(SCH_1):PAGE227_I173@PURE_QUANTA.SCONN168_ME1016810202011(CHIPS)':
 'PETP0': CDS_PINID='PETP0';
NET_NAME
'CLK_50M_RMII_R'
 '@S9S_MB_2U_LIB.S9S_MB_2U(SCH_1):CLK_50M_RMII_R':
 C_SIGNAL='@s9s_mb_2u_lib.s9s_mb_2u(sch_1):clk_50m_rmii_r';
NODE_NAME     U90 1
 '@S9S_MB_2U_LIB.S9S_MB_2U(SCH_1):PAGE152_I46@PURE_QUANTA.PI6CV304LE(CHIPS)':
 'CLK_IN': CDS_PINID='CLK_IN';
NODE_NAME     R1139 2
 '@S9S_MB_2U_LIB.S9S_MB_2U(SCH_1):PAGE152_I56@PURE_QUANTA.Q_RES(CHIPS)':
 'B': CDS_PINID='B';
NET_NAME
'CLK_9ZXL045_HIBW'
 '@S9S_MB_2U_LIB.S9S_MB_2U(SCH_1):CLK_9ZXL045_HIBW':
 C_SIGNAL='@s9s_mb_2u_lib.s9s_mb_2u(sch_1):clk_9zxl045_hibw';
NODE_NAME     U314 32
 '@S9S_MB_2U_LIB.S9S_MB_2U(SCH_1):PAGE200_I1@PURE_QUANTA.9ZXL0451EKILFT(CHIPS)':
 '^HIBW_BYPM_LOBW#': CDS_PINID='\^hibw_bypm_lobw#\';
NODE_NAME     R4491 2
 '@S9S_MB_2U_LIB.S9S_MB_2U(SCH_1):PAGE200_I48@PURE_QUANTA.Q_RES(CHIPS)':
 'B': CDS_PINID='B';
NODE_NAME     R4492 1
 '@S9S_MB_2U_LIB.S9S_MB_2U(SCH_1):PAGE200_I49@PURE_QUANTA.Q_RES(CHIPS)':
 'A': CDS_PINID='A';
NET_NAME
'CLK_9ZXL045_SADR0'
 '@S9S_MB_2U_LIB.S9S_MB_2U(SCH_1):CLK_9ZXL045_SADR0':
 C_SIGNAL='@s9s_mb_2u_lib.s9s_mb_2u(sch_1):clk_9zxl045_sadr0';
NODE_NAME     U314 5
 '@S9S_MB_2U_LIB.S9S_MB_2U(SCH_1):PAGE200_I1@PURE_QUANTA.9ZXL0451EKILFT(CHIPS)':
 'VSADR0_TRI': CDS_PINID='VSADR0_TRI';
NODE_NAME     R4489 2
 '@S9S_MB_2U_LIB.S9S_MB_2U(SCH_1):PAGE200_I30@PURE_QUANTA.Q_RES(CHIPS)':
 'B': CDS_PINID='B';
NODE_NAME     R4490 1
 '@S9S_MB_2U_LIB.S9S_MB_2U(SCH_1):PAGE200_I31@PURE_QUANTA.Q_RES(CHIPS)':
 'A': CDS_PINID='A';
NET_NAME
'CLK_CK440_SMB_ADDR0'
 '@S9S_MB_2U_LIB.S9S_MB_2U(SCH_1):CLK_CK440_SMB_ADDR0':
 C_SIGNAL='@s9s_mb_2u_lib.s9s_mb_2u(sch_1):clk_ck440_smb_addr0';
NODE_NAME     U13 A11
 '@S9S_MB_2U_LIB.S9S_MB_2U(SCH_1):PAGE197_I180@PURE_QUANTA.9SQ440NQQI8(CHIPS)':
 'SMB_ADR0_TRI': CDS_PINID='SMB_ADR0_TRI';
NODE_NAME     R912 2
 '@S9S_MB_2U_LIB.S9S_MB_2U(SCH_1):PAGE197_I278@PURE_QUANTA.Q_RES(CHIPS)':
 'B': CDS_PINID='B';
NODE_NAME     R953 1
 '@S9S_MB_2U_LIB.S9S_MB_2U(SCH_1):PAGE197_I282@PURE_QUANTA.Q_RES(CHIPS)':
 'A': CDS_PINID='A';
NET_NAME
'CLK_CK440_SMB_ADDR1'
 '@S9S_MB_2U_LIB.S9S_MB_2U(SCH_1):CLK_CK440_SMB_ADDR1':
 C_SIGNAL='@s9s_mb_2u_lib.s9s_mb_2u(sch_1):clk_ck440_smb_addr1';
NODE_NAME     U13 B9
 '@S9S_MB_2U_LIB.S9S_MB_2U(SCH_1):PAGE197_I180@PURE_QUANTA.9SQ440NQQI8(CHIPS)':
 'SMB_ADR1_TRI': CDS_PINID='SMB_ADR1_TRI';
NODE_NAME     R2481 2
 '@S9S_MB_2U_LIB.S9S_MB_2U(SCH_1):PAGE197_I280@PURE_QUANTA.Q_RES(CHIPS)':
 'B': CDS_PINID='B';
NODE_NAME     R734 1
 '@S9S_MB_2U_LIB.S9S_MB_2U(SCH_1):PAGE197_I283@PURE_QUANTA.Q_RES(CHIPS)':
 'A': CDS_PINID='A';
NET_NAME
'CLK_GEN2_BMC_RC_OE_N'
 '@S9S_MB_2U_LIB.S9S_MB_2U(SCH_1):CLK_GEN2_BMC_RC_OE_N':
 C_SIGNAL='@s9s_mb_2u_lib.s9s_mb_2u(sch_1):clk_gen2_bmc_rc_oe_n';
NODE_NAME     U249 AB19
 '@S9S_MB_2U_LIB.S9S_MB_2U(SCH_1):PAGE312_I1@PURE_QUANTA.LCMXO3LF9400C5BG484C(CHIPS)':
 'PB43A': CDS_PINID='PB43A';
NODE_NAME     R4075 1
 '@S9S_MB_2U_LIB.S9S_MB_2U(SCH_1):PAGE201_I147@PURE_QUANTA.Q_RES(CHIPS)':
 'A': CDS_PINID='A';
NODE_NAME     R4521 2
 '@S9S_MB_2U_LIB.S9S_MB_2U(SCH_1):PAGE201_I163@PURE_QUANTA.Q_RES(CHIPS)':
 'B': CDS_PINID='B';
NET_NAME
'CLK_GEN2_BMC_RC_OE_R3_N'
 '@S9S_MB_2U_LIB.S9S_MB_2U(SCH_1):CLK_GEN2_BMC_RC_OE_R3_N':
 C_SIGNAL='@s9s_mb_2u_lib.s9s_mb_2u(sch_1):clk_gen2_bmc_rc_oe_r3_n';
NODE_NAME     R4075 2
 '@S9S_MB_2U_LIB.S9S_MB_2U(SCH_1):PAGE201_I147@PURE_QUANTA.Q_RES(CHIPS)':
 'B': CDS_PINID='B';
NODE_NAME     U247 12
 '@S9S_MB_2U_LIB.S9S_MB_2U(SCH_1):PAGE201_I167@PURE_QUANTA.9FGL0251DKILFT(CHIPS)':
 'VOE0#': CDS_PINID='\voe0#\';
NET_NAME
'CLK_GEN2_GPU_FPGA_OE_N'
 '@S9S_MB_2U_LIB.S9S_MB_2U(SCH_1):CLK_GEN2_GPU_FPGA_OE_N':
 C_SIGNAL='@s9s_mb_2u_lib.s9s_mb_2u(sch_1):clk_gen2_gpu_fpga_oe_n';
NODE_NAME     R3327 1
 '@S9S_MB_2U_LIB.S9S_MB_2U(SCH_1):PAGE201_I85@PURE_QUANTA.Q_RES(CHIPS)':
 'A': CDS_PINID='A';
NODE_NAME     R4610 2
 '@S9S_MB_2U_LIB.S9S_MB_2U(SCH_1):PAGE313_I200@PURE_QUANTA.Q_RES(CHIPS)':
 'B': CDS_PINID='B';
NET_NAME
'CLK_GEN2_GPU_FPGA_OE_OR_N'
 '@S9S_MB_2U_LIB.S9S_MB_2U(SCH_1):CLK_GEN2_GPU_FPGA_OE_OR_N':
 C_SIGNAL='@s9s_mb_2u_lib.s9s_mb_2u(sch_1):clk_gen2_gpu_fpga_oe_or_n';
NODE_NAME     R4537 2
 '@S9S_MB_2U_LIB.S9S_MB_2U(SCH_1):PAGE136_I73@PURE_QUANTA.Q_RES(CHIPS)':
 'B': CDS_PINID='B';
NODE_NAME     R4076 1
 '@S9S_MB_2U_LIB.S9S_MB_2U(SCH_1):PAGE201_I146@PURE_QUANTA.Q_RES(CHIPS)':
 'A': CDS_PINID='A';
NODE_NAME     R4651 2
 '@S9S_MB_2U_LIB.S9S_MB_2U(SCH_1):PAGE159_I102@PURE_QUANTA.Q_RES(CHIPS)':
 'B': CDS_PINID='B';
NODE_NAME     U248 4
 '@S9S_MB_2U_LIB.S9S_MB_2U(SCH_1):PAGE201_I158@PURE_QUANTA.74LVC1G32GW(CHIPS)':
 'O': CDS_PINID='O';
NODE_NAME     R3265 1
 '@S9S_MB_2U_LIB.S9S_MB_2U(SCH_1):PAGE136_I84@PURE_QUANTA.Q_RES(CHIPS)':
 'A': CDS_PINID='A';
NODE_NAME     R3292 2
 '@S9S_MB_2U_LIB.S9S_MB_2U(SCH_1):PAGE136_I85@PURE_QUANTA.Q_RES(CHIPS)':
 'B': CDS_PINID='B';
NET_NAME
'CLK_GEN2_GPU_FPGA_OE_R2_N'
 '@S9S_MB_2U_LIB.S9S_MB_2U(SCH_1):CLK_GEN2_GPU_FPGA_OE_R2_N':
 C_SIGNAL='@s9s_mb_2u_lib.s9s_mb_2u(sch_1):clk_gen2_gpu_fpga_oe_r2_n';
NODE_NAME     R3327 2
 '@S9S_MB_2U_LIB.S9S_MB_2U(SCH_1):PAGE201_I85@PURE_QUANTA.Q_RES(CHIPS)':
 'B': CDS_PINID='B';
NODE_NAME     R3322 2
 '@S9S_MB_2U_LIB.S9S_MB_2U(SCH_1):PAGE201_I157@PURE_QUANTA.Q_RES(CHIPS)':
 'B': CDS_PINID='B';
NODE_NAME     U248 2
 '@S9S_MB_2U_LIB.S9S_MB_2U(SCH_1):PAGE201_I158@PURE_QUANTA.74LVC1G32GW(CHIPS)':
 'I1': CDS_PINID='I1';
NODE_NAME     R4514 1
 '@S9S_MB_2U_LIB.S9S_MB_2U(SCH_1):PAGE201_I161@PURE_QUANTA.Q_RES(CHIPS)':
 'A': CDS_PINID='A';
NET_NAME
'CLK_GEN2_GPU_FPGA_OE_R_N'
 '@S9S_MB_2U_LIB.S9S_MB_2U(SCH_1):CLK_GEN2_GPU_FPGA_OE_R_N':
 C_SIGNAL='@s9s_mb_2u_lib.s9s_mb_2u(sch_1):clk_gen2_gpu_fpga_oe_r_n';
NODE_NAME     U249 V19
 '@S9S_MB_2U_LIB.S9S_MB_2U(SCH_1):PAGE313_I1@PURE_QUANTA.LCMXO3LF9400C5BG484C(CHIPS)':
 'PR29D': CDS_PINID='PR29D';
NODE_NAME     R4610 1
 '@S9S_MB_2U_LIB.S9S_MB_2U(SCH_1):PAGE313_I200@PURE_QUANTA.Q_RES(CHIPS)':
 'A': CDS_PINID='A';
NET_NAME
'CLK_GEN2_GPU_OE_N'
 '@S9S_MB_2U_LIB.S9S_MB_2U(SCH_1):CLK_GEN2_GPU_OE_N':
 C_SIGNAL='@s9s_mb_2u_lib.s9s_mb_2u(sch_1):clk_gen2_gpu_oe_n';
NODE_NAME     R4076 2
 '@S9S_MB_2U_LIB.S9S_MB_2U(SCH_1):PAGE201_I146@PURE_QUANTA.Q_RES(CHIPS)':
 'B': CDS_PINID='B';
NODE_NAME     U247 19
 '@S9S_MB_2U_LIB.S9S_MB_2U(SCH_1):PAGE201_I167@PURE_QUANTA.9FGL0251DKILFT(CHIPS)':
 'VOE1#': CDS_PINID='\voe1#\';
NET_NAME
'CLK_GEN2_SMB_SADR'
 '@S9S_MB_2U_LIB.S9S_MB_2U(SCH_1):CLK_GEN2_SMB_SADR':
 C_SIGNAL='@s9s_mb_2u_lib.s9s_mb_2u(sch_1):clk_gen2_smb_sadr';
NODE_NAME     R4082 1
 '@S9S_MB_2U_LIB.S9S_MB_2U(SCH_1):PAGE201_I134@PURE_QUANTA.Q_RES(CHIPS)':
 'A': CDS_PINID='A';
NODE_NAME     R4081 2
 '@S9S_MB_2U_LIB.S9S_MB_2U(SCH_1):PAGE201_I135@PURE_QUANTA.Q_RES(CHIPS)':
 'B': CDS_PINID='B';
NODE_NAME     U247 4
 '@S9S_MB_2U_LIB.S9S_MB_2U(SCH_1):PAGE201_I167@PURE_QUANTA.9FGL0251DKILFT(CHIPS)':
 'VSADR||REF3.3': CDS_PINID='\vsadr||ref3.3\';
NET_NAME
'CLK_GEN2_XTAL_IN'
 '@S9S_MB_2U_LIB.S9S_MB_2U(SCH_1):CLK_GEN2_XTAL_IN':
 C_SIGNAL='@s9s_mb_2u_lib.s9s_mb_2u(sch_1):clk_gen2_xtal_in';
NODE_NAME     R4501 2
 '@S9S_MB_2U_LIB.S9S_MB_2U(SCH_1):PAGE201_I160@PURE_QUANTA.Q_RES(CHIPS)':
 'B': CDS_PINID='B';
NODE_NAME     U247 1
 '@S9S_MB_2U_LIB.S9S_MB_2U(SCH_1):PAGE201_I167@PURE_QUANTA.9FGL0251DKILFT(CHIPS)':
 'XIN||CLKIN_25': CDS_PINID='\xin||clkin_25\';
NET_NAME
'CLK_GEN2_XTAL_IN_R'
 '@S9S_MB_2U_LIB.S9S_MB_2U(SCH_1):CLK_GEN2_XTAL_IN_R':
 C_SIGNAL='@s9s_mb_2u_lib.s9s_mb_2u(sch_1):clk_gen2_xtal_in_r';
NODE_NAME     Y3 1
 '@S9S_MB_2U_LIB.S9S_MB_2U(SCH_1):PAGE201_I159@PURE_QUANTA.Q_XTAL_4P_13BI_24GND(CHIPS)':
 'X1': CDS_PINID='X1';
NODE_NAME     R4501 1
 '@S9S_MB_2U_LIB.S9S_MB_2U(SCH_1):PAGE201_I160@PURE_QUANTA.Q_RES(CHIPS)':
 'A': CDS_PINID='A';
NODE_NAME     C2255 1
 '@S9S_MB_2U_LIB.S9S_MB_2U(SCH_1):PAGE201_I165@PURE_QUANTA.Q_CAP(CHIPS)':
 'A': CDS_PINID='A';
NET_NAME
'CLK_GEN2_XTAL_OUT'
 '@S9S_MB_2U_LIB.S9S_MB_2U(SCH_1):CLK_GEN2_XTAL_OUT':
 C_SIGNAL='@s9s_mb_2u_lib.s9s_mb_2u(sch_1):clk_gen2_xtal_out';
NODE_NAME     Y3 3
 '@S9S_MB_2U_LIB.S9S_MB_2U(SCH_1):PAGE201_I159@PURE_QUANTA.Q_XTAL_4P_13BI_24GND(CHIPS)':
 'X2': CDS_PINID='X2';
NODE_NAME     C2256 1
 '@S9S_MB_2U_LIB.S9S_MB_2U(SCH_1):PAGE201_I166@PURE_QUANTA.Q_CAP(CHIPS)':
 'A': CDS_PINID='A';
NODE_NAME     U247 2
 '@S9S_MB_2U_LIB.S9S_MB_2U(SCH_1):PAGE201_I167@PURE_QUANTA.9FGL0251DKILFT(CHIPS)':
 'X2': CDS_PINID='X2';
NET_NAME
'CLK_GPU_1_OE_N'
 '@S9S_MB_2U_LIB.S9S_MB_2U(SCH_1):CLK_GPU_1_OE_N':
 C_SIGNAL='@s9s_mb_2u_lib.s9s_mb_2u(sch_1):clk_gpu_1_oe_n';
NODE_NAME     U249 AA18
 '@S9S_MB_2U_LIB.S9S_MB_2U(SCH_1):PAGE312_I1@PURE_QUANTA.LCMXO3LF9400C5BG484C(CHIPS)':
 'PB41B': CDS_PINID='PB41B';
NODE_NAME     R4478 2
 '@S9S_MB_2U_LIB.S9S_MB_2U(SCH_1):PAGE200_I75@PURE_QUANTA.Q_RES(CHIPS)':
 'B': CDS_PINID='B';
NODE_NAME     R4519 2
 '@S9S_MB_2U_LIB.S9S_MB_2U(SCH_1):PAGE200_I78@PURE_QUANTA.Q_RES(CHIPS)':
 'B': CDS_PINID='B';
NET_NAME
'CLK_GPU_2_OE_N'
 '@S9S_MB_2U_LIB.S9S_MB_2U(SCH_1):CLK_GPU_2_OE_N':
 C_SIGNAL='@s9s_mb_2u_lib.s9s_mb_2u(sch_1):clk_gpu_2_oe_n';
NODE_NAME     U249 Y18
 '@S9S_MB_2U_LIB.S9S_MB_2U(SCH_1):PAGE312_I1@PURE_QUANTA.LCMXO3LF9400C5BG484C(CHIPS)':
 'PB41C': CDS_PINID='PB41C';
NODE_NAME     R4479 2
 '@S9S_MB_2U_LIB.S9S_MB_2U(SCH_1):PAGE200_I76@PURE_QUANTA.Q_RES(CHIPS)':
 'B': CDS_PINID='B';
NODE_NAME     R4518 2
 '@S9S_MB_2U_LIB.S9S_MB_2U(SCH_1):PAGE200_I77@PURE_QUANTA.Q_RES(CHIPS)':
 'B': CDS_PINID='B';
NET_NAME
'CLK_SWB_BUF2_OE_N'
 '@S9S_MB_2U_LIB.S9S_MB_2U(SCH_1):CLK_SWB_BUF2_OE_N':
 C_SIGNAL='@s9s_mb_2u_lib.s9s_mb_2u(sch_1):clk_swb_buf2_oe_n';
NODE_NAME     U249 T15
 '@S9S_MB_2U_LIB.S9S_MB_2U(SCH_1):PAGE312_I1@PURE_QUANTA.LCMXO3LF9400C5BG484C(CHIPS)':
 'PB43C': CDS_PINID='PB43C';
NODE_NAME     R4477 2
 '@S9S_MB_2U_LIB.S9S_MB_2U(SCH_1):PAGE200_I74@PURE_QUANTA.Q_RES(CHIPS)':
 'B': CDS_PINID='B';
NODE_NAME     R4520 2
 '@S9S_MB_2U_LIB.S9S_MB_2U(SCH_1):PAGE200_I79@PURE_QUANTA.Q_RES(CHIPS)':
 'B': CDS_PINID='B';
NET_NAME
'CLK_SWB_OE_N'
 '@S9S_MB_2U_LIB.S9S_MB_2U(SCH_1):CLK_SWB_OE_N':
 C_SIGNAL='@s9s_mb_2u_lib.s9s_mb_2u(sch_1):clk_swb_oe_n';
NODE_NAME     R4534 1
 '@S9S_MB_2U_LIB.S9S_MB_2U(SCH_1):PAGE195_I487@PURE_QUANTA.Q_RES(CHIPS)':
 'A': CDS_PINID='A';
NODE_NAME     U249 W17
 '@S9S_MB_2U_LIB.S9S_MB_2U(SCH_1):PAGE312_I1@PURE_QUANTA.LCMXO3LF9400C5BG484C(CHIPS)':
 'PB41D': CDS_PINID='PB41D';
NODE_NAME     R4516 2
 '@S9S_MB_2U_LIB.S9S_MB_2U(SCH_1):PAGE195_I539@PURE_QUANTA.Q_RES(CHIPS)':
 'B': CDS_PINID='B';
NET_NAME
'CPU1_RSVD<107>'
 '@S9S_MB_2U_LIB.S9S_MB_2U(SCH_1):CPU1_RSVD'<107>:
 C_SIGNAL='@s9s_mb_2u_lib.s9s_mb_2u(sch_1):cpu1_rsvd(107)';
NODE_NAME     U1 CL21
 '@S9S_MB_2U_LIB.S9S_MB_2U(SCH_1):PAGE45_I29@PURE_QUANTA.SOCKET4677_AZIF0045P001C01CS(CHIPS)':
 'RSVD113': CDS_PINID='RSVD113';
NET_NAME
'CPU1_RSVD<110>'
 '@S9S_MB_2U_LIB.S9S_MB_2U(SCH_1):CPU1_RSVD'<110>:
 C_SIGNAL='@s9s_mb_2u_lib.s9s_mb_2u(sch_1):cpu1_rsvd(110)';
NODE_NAME     U1 CL64
 '@S9S_MB_2U_LIB.S9S_MB_2U(SCH_1):PAGE45_I29@PURE_QUANTA.SOCKET4677_AZIF0045P001C01CS(CHIPS)':
 'RSVD116': CDS_PINID='RSVD116';
NET_NAME
'CPU1_RSVD<115>'
 '@S9S_MB_2U_LIB.S9S_MB_2U(SCH_1):CPU1_RSVD'<115>:
 C_SIGNAL='@s9s_mb_2u_lib.s9s_mb_2u(sch_1):cpu1_rsvd(115)';
NODE_NAME     U1 CM63
 '@S9S_MB_2U_LIB.S9S_MB_2U(SCH_1):PAGE45_I29@PURE_QUANTA.SOCKET4677_AZIF0045P001C01CS(CHIPS)':
 'RSVD121': CDS_PINID='RSVD121';
NET_NAME
'CPU1_RSVD<120>'
 '@S9S_MB_2U_LIB.S9S_MB_2U(SCH_1):CPU1_RSVD'<120>:
 C_SIGNAL='@s9s_mb_2u_lib.s9s_mb_2u(sch_1):cpu1_rsvd(120)';
NODE_NAME     U1 CN62
 '@S9S_MB_2U_LIB.S9S_MB_2U(SCH_1):PAGE45_I29@PURE_QUANTA.SOCKET4677_AZIF0045P001C01CS(CHIPS)':
 'RSVD126': CDS_PINID='RSVD126';
NET_NAME
'CPU1_RSVD<126>'
 '@S9S_MB_2U_LIB.S9S_MB_2U(SCH_1):CPU1_RSVD'<126>:
 C_SIGNAL='@s9s_mb_2u_lib.s9s_mb_2u(sch_1):cpu1_rsvd(126)';
NODE_NAME     U1 CR23
 '@S9S_MB_2U_LIB.S9S_MB_2U(SCH_1):PAGE45_I29@PURE_QUANTA.SOCKET4677_AZIF0045P001C01CS(CHIPS)':
 'RSVD132': CDS_PINID='RSVD132';
NET_NAME
'CPU1_RSVD<135>'
 '@S9S_MB_2U_LIB.S9S_MB_2U(SCH_1):CPU1_RSVD'<135>:
 C_SIGNAL='@s9s_mb_2u_lib.s9s_mb_2u(sch_1):cpu1_rsvd(135)';
NODE_NAME     U1 CV24
 '@S9S_MB_2U_LIB.S9S_MB_2U(SCH_1):PAGE45_I29@PURE_QUANTA.SOCKET4677_AZIF0045P001C01CS(CHIPS)':
 'RSVD141': CDS_PINID='RSVD141';
NET_NAME
'CPU1_RSVD<139>'
 '@S9S_MB_2U_LIB.S9S_MB_2U(SCH_1):CPU1_RSVD'<139>:
 C_SIGNAL='@s9s_mb_2u_lib.s9s_mb_2u(sch_1):cpu1_rsvd(139)';
NODE_NAME     U1 CW23
 '@S9S_MB_2U_LIB.S9S_MB_2U(SCH_1):PAGE45_I29@PURE_QUANTA.SOCKET4677_AZIF0045P001C01CS(CHIPS)':
 'RSVD145': CDS_PINID='RSVD145';
NET_NAME
'CPU1_RSVD<140>'
 '@S9S_MB_2U_LIB.S9S_MB_2U(SCH_1):CPU1_RSVD'<140>:
 C_SIGNAL='@s9s_mb_2u_lib.s9s_mb_2u(sch_1):cpu1_rsvd(140)';
NODE_NAME     U1 CW25
 '@S9S_MB_2U_LIB.S9S_MB_2U(SCH_1):PAGE45_I29@PURE_QUANTA.SOCKET4677_AZIF0045P001C01CS(CHIPS)':
 'RSVD146': CDS_PINID='RSVD146';
NET_NAME
'CPU1_RSVD<144>'
 '@S9S_MB_2U_LIB.S9S_MB_2U(SCH_1):CPU1_RSVD'<144>:
 C_SIGNAL='@s9s_mb_2u_lib.s9s_mb_2u(sch_1):cpu1_rsvd(144)';
NODE_NAME     U1 CW68
 '@S9S_MB_2U_LIB.S9S_MB_2U(SCH_1):PAGE45_I29@PURE_QUANTA.SOCKET4677_AZIF0045P001C01CS(CHIPS)':
 'RSVD150': CDS_PINID='RSVD150';
NET_NAME
'CPU1_RSVD<153>'
 '@S9S_MB_2U_LIB.S9S_MB_2U(SCH_1):CPU1_RSVD'<153>:
 C_SIGNAL='@s9s_mb_2u_lib.s9s_mb_2u(sch_1):cpu1_rsvd(153)';
NODE_NAME     U1 D4
 '@S9S_MB_2U_LIB.S9S_MB_2U(SCH_1):PAGE44_I51@PURE_QUANTA.SOCKET4677_AZIF0045P001C01CS(CHIPS)':
 'RSVD157': CDS_PINID='RSVD157';
NET_NAME
'CPU1_RSVD<157>'
 '@S9S_MB_2U_LIB.S9S_MB_2U(SCH_1):CPU1_RSVD'<157>:
 C_SIGNAL='@s9s_mb_2u_lib.s9s_mb_2u(sch_1):cpu1_rsvd(157)';
NODE_NAME     U1 G5
 '@S9S_MB_2U_LIB.S9S_MB_2U(SCH_1):PAGE44_I51@PURE_QUANTA.SOCKET4677_AZIF0045P001C01CS(CHIPS)':
 'RSVD161': CDS_PINID='RSVD161';
NET_NAME
'CPU1_RSVD<15>'
 '@S9S_MB_2U_LIB.S9S_MB_2U(SCH_1):CPU1_RSVD'<15>:
 C_SIGNAL='@s9s_mb_2u_lib.s9s_mb_2u(sch_1):cpu1_rsvd(15)';
NODE_NAME     U1 AV26
 '@S9S_MB_2U_LIB.S9S_MB_2U(SCH_1):PAGE45_I29@PURE_QUANTA.SOCKET4677_AZIF0045P001C01CS(CHIPS)':
 'RSVD15': CDS_PINID='RSVD15';
NET_NAME
'CPU1_RSVD<25>'
 '@S9S_MB_2U_LIB.S9S_MB_2U(SCH_1):CPU1_RSVD'<25>:
 C_SIGNAL='@s9s_mb_2u_lib.s9s_mb_2u(sch_1):cpu1_rsvd(25)';
NODE_NAME     U1 AY26
 '@S9S_MB_2U_LIB.S9S_MB_2U(SCH_1):PAGE45_I29@PURE_QUANTA.SOCKET4677_AZIF0045P001C01CS(CHIPS)':
 'RSVD27': CDS_PINID='RSVD27';
NET_NAME
'CPU1_RSVD<27>'
 '@S9S_MB_2U_LIB.S9S_MB_2U(SCH_1):CPU1_RSVD'<27>:
 C_SIGNAL='@s9s_mb_2u_lib.s9s_mb_2u(sch_1):cpu1_rsvd(27)';
NODE_NAME     U1 AY65
 '@S9S_MB_2U_LIB.S9S_MB_2U(SCH_1):PAGE45_I29@PURE_QUANTA.SOCKET4677_AZIF0045P001C01CS(CHIPS)':
 'RSVD29': CDS_PINID='RSVD29';
NET_NAME
'CPU1_RSVD<4>'
 '@S9S_MB_2U_LIB.S9S_MB_2U(SCH_1):CPU1_RSVD'<4>:
 C_SIGNAL='@s9s_mb_2u_lib.s9s_mb_2u(sch_1):cpu1_rsvd(4)';
NODE_NAME     U1 AT24
 '@S9S_MB_2U_LIB.S9S_MB_2U(SCH_1):PAGE45_I29@PURE_QUANTA.SOCKET4677_AZIF0045P001C01CS(CHIPS)':
 'RSVD4': CDS_PINID='RSVD4';
NET_NAME
'CPU1_RSVD<54>'
 '@S9S_MB_2U_LIB.S9S_MB_2U(SCH_1):CPU1_RSVD'<54>:
 C_SIGNAL='@s9s_mb_2u_lib.s9s_mb_2u(sch_1):cpu1_rsvd(54)';
NODE_NAME     U1 BJ70
 '@S9S_MB_2U_LIB.S9S_MB_2U(SCH_1):PAGE45_I29@PURE_QUANTA.SOCKET4677_AZIF0045P001C01CS(CHIPS)':
 'RSVD59': CDS_PINID='RSVD59';
NET_NAME
'CPU1_RSVD<64>'
 '@S9S_MB_2U_LIB.S9S_MB_2U(SCH_1):CPU1_RSVD'<64>:
 C_SIGNAL='@s9s_mb_2u_lib.s9s_mb_2u(sch_1):cpu1_rsvd(64)';
NODE_NAME     U1 BP67
 '@S9S_MB_2U_LIB.S9S_MB_2U(SCH_1):PAGE45_I29@PURE_QUANTA.SOCKET4677_AZIF0045P001C01CS(CHIPS)':
 'RSVD69': CDS_PINID='RSVD69';
NET_NAME
'CPU1_RSVD<65>'
 '@S9S_MB_2U_LIB.S9S_MB_2U(SCH_1):CPU1_RSVD'<65>:
 C_SIGNAL='@s9s_mb_2u_lib.s9s_mb_2u(sch_1):cpu1_rsvd(65)';
NODE_NAME     U1 BP69
 '@S9S_MB_2U_LIB.S9S_MB_2U(SCH_1):PAGE45_I29@PURE_QUANTA.SOCKET4677_AZIF0045P001C01CS(CHIPS)':
 'RSVD70': CDS_PINID='RSVD70';
NET_NAME
'CPU1_RSVD<6>'
 '@S9S_MB_2U_LIB.S9S_MB_2U(SCH_1):CPU1_RSVD'<6>:
 C_SIGNAL='@s9s_mb_2u_lib.s9s_mb_2u(sch_1):cpu1_rsvd(6)';
NODE_NAME     U1 AU25
 '@S9S_MB_2U_LIB.S9S_MB_2U(SCH_1):PAGE45_I29@PURE_QUANTA.SOCKET4677_AZIF0045P001C01CS(CHIPS)':
 'RSVD6': CDS_PINID='RSVD6';
NET_NAME
'CPU1_RSVD<82>'
 '@S9S_MB_2U_LIB.S9S_MB_2U(SCH_1):CPU1_RSVD'<82>:
 C_SIGNAL='@s9s_mb_2u_lib.s9s_mb_2u(sch_1):cpu1_rsvd(82)';
NODE_NAME     U1 CD71
 '@S9S_MB_2U_LIB.S9S_MB_2U(SCH_1):PAGE44_I51@PURE_QUANTA.SOCKET4677_AZIF0045P001C01CS(CHIPS)':
 'RSVD88': CDS_PINID='RSVD88';
NET_NAME
'CPU1_RSVD<85>'
 '@S9S_MB_2U_LIB.S9S_MB_2U(SCH_1):CPU1_RSVD'<85>:
 C_SIGNAL='@s9s_mb_2u_lib.s9s_mb_2u(sch_1):cpu1_rsvd(85)';
NODE_NAME     U1 CE70
 '@S9S_MB_2U_LIB.S9S_MB_2U(SCH_1):PAGE44_I51@PURE_QUANTA.SOCKET4677_AZIF0045P001C01CS(CHIPS)':
 'RSVD91': CDS_PINID='RSVD91';
NET_NAME
'CPU1_RSVD<98>'
 '@S9S_MB_2U_LIB.S9S_MB_2U(SCH_1):CPU1_RSVD'<98>:
 C_SIGNAL='@s9s_mb_2u_lib.s9s_mb_2u(sch_1):cpu1_rsvd(98)';
NODE_NAME     U1 CJ62
 '@S9S_MB_2U_LIB.S9S_MB_2U(SCH_1):PAGE45_I29@PURE_QUANTA.SOCKET4677_AZIF0045P001C01CS(CHIPS)':
 'RSVD104': CDS_PINID='RSVD104';
NET_NAME
'CPU_RMCA_CATERR_LVT3_N'
 '@S9S_MB_2U_LIB.S9S_MB_2U(SCH_1):CPU_RMCA_CATERR_LVT3_N':
 C_SIGNAL='@s9s_mb_2u_lib.s9s_mb_2u(sch_1):cpu_rmca_caterr_lvt3_n';
NODE_NAME     Q33 G
 '@S9S_MB_2U_LIB.S9S_MB_2U(SCH_1):PAGE207_I272@PURE_QUANTA.MOSFET_NCH_GDS_ESD_PROTECTED(CHIPS)':
 'G': CDS_PINID='G';
NODE_NAME     R365 2
 '@S9S_MB_2U_LIB.S9S_MB_2U(SCH_1):PAGE207_I273@PURE_QUANTA.Q_RES(CHIPS)':
 'B': CDS_PINID='B';
NET_NAME
'DBP_CPU0_HOOK8_MBP2_GTL_QS_R_N'
 '@S9S_MB_2U_LIB.S9S_MB_2U(SCH_1):DBP_CPU0_HOOK8_MBP2_GTL_QS_R_N':
 C_SIGNAL='@s9s_mb_2u_lib.s9s_mb_2u(sch_1):dbp_cpu0_hook8_mbp2_gtl_qs_r_n';
NODE_NAME     U2 BJ23
 '@S9S_MB_2U_LIB.S9S_MB_2U(SCH_1):PAGE16_I1@PURE_QUANTA.SOCKET4677_AZIF0045P001C01CS(CHIPS)':
 'MBP2_N': CDS_PINID='MBP2_N';
NODE_NAME     R24 1
 '@S9S_MB_2U_LIB.S9S_MB_2U(SCH_1):PAGE16_I25@PURE_QUANTA.Q_RES(CHIPS)':
 'A': CDS_PINID='A';
NET_NAME
'DBP_CPU0_HOOK9_MBP3_GTL_QS_R_N'
 '@S9S_MB_2U_LIB.S9S_MB_2U(SCH_1):DBP_CPU0_HOOK9_MBP3_GTL_QS_R_N':
 C_SIGNAL='@s9s_mb_2u_lib.s9s_mb_2u(sch_1):dbp_cpu0_hook9_mbp3_gtl_qs_r_n';
NODE_NAME     U2 BK24
 '@S9S_MB_2U_LIB.S9S_MB_2U(SCH_1):PAGE16_I1@PURE_QUANTA.SOCKET4677_AZIF0045P001C01CS(CHIPS)':
 'MBP3_N': CDS_PINID='MBP3_N';
NODE_NAME     R25 1
 '@S9S_MB_2U_LIB.S9S_MB_2U(SCH_1):PAGE16_I26@PURE_QUANTA.Q_RES(CHIPS)':
 'A': CDS_PINID='A';
NET_NAME
'DBP_CPU0_MBP0_GTL_R_N'
 '@S9S_MB_2U_LIB.S9S_MB_2U(SCH_1):DBP_CPU0_MBP0_GTL_R_N':
 C_SIGNAL='@s9s_mb_2u_lib.s9s_mb_2u(sch_1):dbp_cpu0_mbp0_gtl_r_n';
NODE_NAME     U2 BL23
 '@S9S_MB_2U_LIB.S9S_MB_2U(SCH_1):PAGE16_I1@PURE_QUANTA.SOCKET4677_AZIF0045P001C01CS(CHIPS)':
 'MBP0_N': CDS_PINID='MBP0_N';
NODE_NAME     R22 1
 '@S9S_MB_2U_LIB.S9S_MB_2U(SCH_1):PAGE16_I19@PURE_QUANTA.Q_RES(CHIPS)':
 'A': CDS_PINID='A';
NET_NAME
'DBP_CPU0_MBP1_GTL_R_N'
 '@S9S_MB_2U_LIB.S9S_MB_2U(SCH_1):DBP_CPU0_MBP1_GTL_R_N':
 C_SIGNAL='@s9s_mb_2u_lib.s9s_mb_2u(sch_1):dbp_cpu0_mbp1_gtl_r_n';
NODE_NAME     U2 BN25
 '@S9S_MB_2U_LIB.S9S_MB_2U(SCH_1):PAGE16_I1@PURE_QUANTA.SOCKET4677_AZIF0045P001C01CS(CHIPS)':
 'MBP1_N': CDS_PINID='MBP1_N';
NODE_NAME     R23 1
 '@S9S_MB_2U_LIB.S9S_MB_2U(SCH_1):PAGE16_I20@PURE_QUANTA.Q_RES(CHIPS)':
 'A': CDS_PINID='A';
NET_NAME
'DBP_CPU1_HOOK8_MBP2_GTL_QS_R_N'
 '@S9S_MB_2U_LIB.S9S_MB_2U(SCH_1):DBP_CPU1_HOOK8_MBP2_GTL_QS_R_N':
 C_SIGNAL='@s9s_mb_2u_lib.s9s_mb_2u(sch_1):dbp_cpu1_hook8_mbp2_gtl_qs_r_n';
NODE_NAME     U1 BJ23
 '@S9S_MB_2U_LIB.S9S_MB_2U(SCH_1):PAGE47_I16@PURE_QUANTA.SOCKET4677_AZIF0045P001C01CS(CHIPS)':
 'MBP2_N': CDS_PINID='MBP2_N';
NODE_NAME     R53 1
 '@S9S_MB_2U_LIB.S9S_MB_2U(SCH_1):PAGE47_I23@PURE_QUANTA.Q_RES(CHIPS)':
 'A': CDS_PINID='A';
NET_NAME
'DBP_CPU1_HOOK9_MBP3_GTL_QS_R_N'
 '@S9S_MB_2U_LIB.S9S_MB_2U(SCH_1):DBP_CPU1_HOOK9_MBP3_GTL_QS_R_N':
 C_SIGNAL='@s9s_mb_2u_lib.s9s_mb_2u(sch_1):dbp_cpu1_hook9_mbp3_gtl_qs_r_n';
NODE_NAME     U1 BK24
 '@S9S_MB_2U_LIB.S9S_MB_2U(SCH_1):PAGE47_I16@PURE_QUANTA.SOCKET4677_AZIF0045P001C01CS(CHIPS)':
 'MBP3_N': CDS_PINID='MBP3_N';
NODE_NAME     R54 1
 '@S9S_MB_2U_LIB.S9S_MB_2U(SCH_1):PAGE47_I22@PURE_QUANTA.Q_RES(CHIPS)':
 'A': CDS_PINID='A';
NET_NAME
'DBP_CPU1_MBP0_GTL_R_N'
 '@S9S_MB_2U_LIB.S9S_MB_2U(SCH_1):DBP_CPU1_MBP0_GTL_R_N':
 C_SIGNAL='@s9s_mb_2u_lib.s9s_mb_2u(sch_1):dbp_cpu1_mbp0_gtl_r_n';
NODE_NAME     U1 BL23
 '@S9S_MB_2U_LIB.S9S_MB_2U(SCH_1):PAGE47_I16@PURE_QUANTA.SOCKET4677_AZIF0045P001C01CS(CHIPS)':
 'MBP0_N': CDS_PINID='MBP0_N';
NODE_NAME     R51 1
 '@S9S_MB_2U_LIB.S9S_MB_2U(SCH_1):PAGE47_I24@PURE_QUANTA.Q_RES(CHIPS)':
 'A': CDS_PINID='A';
NET_NAME
'DBP_CPU1_MBP1_GTL_R_N'
 '@S9S_MB_2U_LIB.S9S_MB_2U(SCH_1):DBP_CPU1_MBP1_GTL_R_N':
 C_SIGNAL='@s9s_mb_2u_lib.s9s_mb_2u(sch_1):dbp_cpu1_mbp1_gtl_r_n';
NODE_NAME     U1 BN25
 '@S9S_MB_2U_LIB.S9S_MB_2U(SCH_1):PAGE47_I16@PURE_QUANTA.SOCKET4677_AZIF0045P001C01CS(CHIPS)':
 'MBP1_N': CDS_PINID='MBP1_N';
NODE_NAME     R52 1
 '@S9S_MB_2U_LIB.S9S_MB_2U(SCH_1):PAGE47_I25@PURE_QUANTA.Q_RES(CHIPS)':
 'A': CDS_PINID='A';
NET_NAME
'DBP_CPU_HOOK8_MBP2_GTL_QS_N'
 '@S9S_MB_2U_LIB.S9S_MB_2U(SCH_1):DBP_CPU_HOOK8_MBP2_GTL_QS_N':
 C_SIGNAL='@s9s_mb_2u_lib.s9s_mb_2u(sch_1):dbp_cpu_hook8_mbp2_gtl_qs_n';
NODE_NAME     R24 2
 '@S9S_MB_2U_LIB.S9S_MB_2U(SCH_1):PAGE16_I25@PURE_QUANTA.Q_RES(CHIPS)':
 'B': CDS_PINID='B';
NODE_NAME     R53 2
 '@S9S_MB_2U_LIB.S9S_MB_2U(SCH_1):PAGE47_I23@PURE_QUANTA.Q_RES(CHIPS)':
 'B': CDS_PINID='B';
NODE_NAME     U18 6
 '@S9S_MB_2U_LIB.S9S_MB_2U(SCH_1):PAGE134_I129@PURE_QUANTA.74CBTLV3126PW(CHIPS)':
 '2B': CDS_PINID='\2b\';
NODE_NAME     R760 2
 '@S9S_MB_2U_LIB.S9S_MB_2U(SCH_1):PAGE134_I174@PURE_QUANTA.Q_RES(CHIPS)':
 'B': CDS_PINID='B';
NET_NAME
'DBP_CPU_HOOK9_MBP3_GTL_QS_N'
 '@S9S_MB_2U_LIB.S9S_MB_2U(SCH_1):DBP_CPU_HOOK9_MBP3_GTL_QS_N':
 C_SIGNAL='@s9s_mb_2u_lib.s9s_mb_2u(sch_1):dbp_cpu_hook9_mbp3_gtl_qs_n';
NODE_NAME     R25 2
 '@S9S_MB_2U_LIB.S9S_MB_2U(SCH_1):PAGE16_I26@PURE_QUANTA.Q_RES(CHIPS)':
 'B': CDS_PINID='B';
NODE_NAME     R54 2
 '@S9S_MB_2U_LIB.S9S_MB_2U(SCH_1):PAGE47_I22@PURE_QUANTA.Q_RES(CHIPS)':
 'B': CDS_PINID='B';
NODE_NAME     U18 3
 '@S9S_MB_2U_LIB.S9S_MB_2U(SCH_1):PAGE134_I129@PURE_QUANTA.74CBTLV3126PW(CHIPS)':
 '1B': CDS_PINID='\1b\';
NODE_NAME     R761 2
 '@S9S_MB_2U_LIB.S9S_MB_2U(SCH_1):PAGE134_I175@PURE_QUANTA.Q_RES(CHIPS)':
 'B': CDS_PINID='B';
NET_NAME
'DBP_CPU_MBP0_GTL_N'
 '@S9S_MB_2U_LIB.S9S_MB_2U(SCH_1):DBP_CPU_MBP0_GTL_N':
 C_SIGNAL='@s9s_mb_2u_lib.s9s_mb_2u(sch_1):dbp_cpu_mbp0_gtl_n';
NODE_NAME     R22 2
 '@S9S_MB_2U_LIB.S9S_MB_2U(SCH_1):PAGE16_I19@PURE_QUANTA.Q_RES(CHIPS)':
 'B': CDS_PINID='B';
NODE_NAME     R20 1
 '@S9S_MB_2U_LIB.S9S_MB_2U(SCH_1):PAGE16_I31@PURE_QUANTA.Q_RES(CHIPS)':
 'A': CDS_PINID='A';
NODE_NAME     R18 2
 '@S9S_MB_2U_LIB.S9S_MB_2U(SCH_1):PAGE16_I35@PURE_QUANTA.Q_RES(CHIPS)':
 'B': CDS_PINID='B';
NODE_NAME     R51 2
 '@S9S_MB_2U_LIB.S9S_MB_2U(SCH_1):PAGE47_I24@PURE_QUANTA.Q_RES(CHIPS)':
 'B': CDS_PINID='B';
NODE_NAME     R49 2
 '@S9S_MB_2U_LIB.S9S_MB_2U(SCH_1):PAGE47_I34@PURE_QUANTA.Q_RES(CHIPS)':
 'B': CDS_PINID='B';
NET_NAME
'DBP_CPU_MBP1_GTL_N'
 '@S9S_MB_2U_LIB.S9S_MB_2U(SCH_1):DBP_CPU_MBP1_GTL_N':
 C_SIGNAL='@s9s_mb_2u_lib.s9s_mb_2u(sch_1):dbp_cpu_mbp1_gtl_n';
NODE_NAME     R23 2
 '@S9S_MB_2U_LIB.S9S_MB_2U(SCH_1):PAGE16_I20@PURE_QUANTA.Q_RES(CHIPS)':
 'B': CDS_PINID='B';
NODE_NAME     R21 1
 '@S9S_MB_2U_LIB.S9S_MB_2U(SCH_1):PAGE16_I32@PURE_QUANTA.Q_RES(CHIPS)':
 'A': CDS_PINID='A';
NODE_NAME     R19 2
 '@S9S_MB_2U_LIB.S9S_MB_2U(SCH_1):PAGE16_I36@PURE_QUANTA.Q_RES(CHIPS)':
 'B': CDS_PINID='B';
NODE_NAME     R52 2
 '@S9S_MB_2U_LIB.S9S_MB_2U(SCH_1):PAGE47_I25@PURE_QUANTA.Q_RES(CHIPS)':
 'B': CDS_PINID='B';
NODE_NAME     R50 2
 '@S9S_MB_2U_LIB.S9S_MB_2U(SCH_1):PAGE47_I35@PURE_QUANTA.Q_RES(CHIPS)':
 'B': CDS_PINID='B';
NET_NAME
'DELTA_L_85_10INCH_BOT_DN'
 '@S9S_MB_2U_LIB.S9S_MB_2U(SCH_1):DELTA_L_85_10INCH_BOT_DN':
 C_SIGNAL='@s9s_mb_2u_lib.s9s_mb_2u(sch_1):delta_l_85_10inch_bot_dn';
NODE_NAME     J82 1
 '@S9S_MB_2U_LIB.S9S_MB_2U(SCH_1):PAGE287_I57@PURE_QUANTA.PICOPROBE_BXA(CHIPS)':
 '1_P': CDS_PINID='\1_p\';
NODE_NAME     J76 2
 '@S9S_MB_2U_LIB.S9S_MB_2U(SCH_1):PAGE287_I51@PURE_QUANTA.PICOPROBE_BXA(CHIPS)':
 '2_N': CDS_PINID='\2_n\';
NET_NAME
'DELTA_L_85_10INCH_BOT_DP'
 '@S9S_MB_2U_LIB.S9S_MB_2U(SCH_1):DELTA_L_85_10INCH_BOT_DP':
 C_SIGNAL='@s9s_mb_2u_lib.s9s_mb_2u(sch_1):delta_l_85_10inch_bot_dp';
NODE_NAME     J82 2
 '@S9S_MB_2U_LIB.S9S_MB_2U(SCH_1):PAGE287_I57@PURE_QUANTA.PICOPROBE_BXA(CHIPS)':
 '2_N': CDS_PINID='\2_n\';
NODE_NAME     J76 1
 '@S9S_MB_2U_LIB.S9S_MB_2U(SCH_1):PAGE287_I51@PURE_QUANTA.PICOPROBE_BXA(CHIPS)':
 '1_P': CDS_PINID='\1_p\';
NET_NAME
'DELTA_L_85_10INCH_IN1_DN'
 '@S9S_MB_2U_LIB.S9S_MB_2U(SCH_1):DELTA_L_85_10INCH_IN1_DN':
 C_SIGNAL='@s9s_mb_2u_lib.s9s_mb_2u(sch_1):delta_l_85_10inch_in1_dn';
NODE_NAME     J77 2
 '@S9S_MB_2U_LIB.S9S_MB_2U(SCH_1):PAGE287_I48@PURE_QUANTA.PICOPROBE_BXA(CHIPS)':
 '2_N': CDS_PINID='\2_n\';
NODE_NAME     J83 1
 '@S9S_MB_2U_LIB.S9S_MB_2U(SCH_1):PAGE287_I56@PURE_QUANTA.PICOPROBE_BXA(CHIPS)':
 '1_P': CDS_PINID='\1_p\';
NET_NAME
'DELTA_L_85_10INCH_IN1_DP'
 '@S9S_MB_2U_LIB.S9S_MB_2U(SCH_1):DELTA_L_85_10INCH_IN1_DP':
 C_SIGNAL='@s9s_mb_2u_lib.s9s_mb_2u(sch_1):delta_l_85_10inch_in1_dp';
NODE_NAME     J77 1
 '@S9S_MB_2U_LIB.S9S_MB_2U(SCH_1):PAGE287_I48@PURE_QUANTA.PICOPROBE_BXA(CHIPS)':
 '1_P': CDS_PINID='\1_p\';
NODE_NAME     J83 2
 '@S9S_MB_2U_LIB.S9S_MB_2U(SCH_1):PAGE287_I56@PURE_QUANTA.PICOPROBE_BXA(CHIPS)':
 '2_N': CDS_PINID='\2_n\';
NET_NAME
'DELTA_L_85_10INCH_IN2_DN'
 '@S9S_MB_2U_LIB.S9S_MB_2U(SCH_1):DELTA_L_85_10INCH_IN2_DN':
 C_SIGNAL='@s9s_mb_2u_lib.s9s_mb_2u(sch_1):delta_l_85_10inch_in2_dn';
NODE_NAME     J78 2
 '@S9S_MB_2U_LIB.S9S_MB_2U(SCH_1):PAGE287_I43@PURE_QUANTA.PICOPROBE_BXA(CHIPS)':
 '2_N': CDS_PINID='\2_n\';
NODE_NAME     J84 1
 '@S9S_MB_2U_LIB.S9S_MB_2U(SCH_1):PAGE287_I55@PURE_QUANTA.PICOPROBE_BXA(CHIPS)':
 '1_P': CDS_PINID='\1_p\';
NET_NAME
'DELTA_L_85_10INCH_IN2_DP'
 '@S9S_MB_2U_LIB.S9S_MB_2U(SCH_1):DELTA_L_85_10INCH_IN2_DP':
 C_SIGNAL='@s9s_mb_2u_lib.s9s_mb_2u(sch_1):delta_l_85_10inch_in2_dp';
NODE_NAME     J78 1
 '@S9S_MB_2U_LIB.S9S_MB_2U(SCH_1):PAGE287_I43@PURE_QUANTA.PICOPROBE_BXA(CHIPS)':
 '1_P': CDS_PINID='\1_p\';
NODE_NAME     J84 2
 '@S9S_MB_2U_LIB.S9S_MB_2U(SCH_1):PAGE287_I55@PURE_QUANTA.PICOPROBE_BXA(CHIPS)':
 '2_N': CDS_PINID='\2_n\';
NET_NAME
'DELTA_L_85_10INCH_IN3_DN'
 '@S9S_MB_2U_LIB.S9S_MB_2U(SCH_1):DELTA_L_85_10INCH_IN3_DN':
 C_SIGNAL='@s9s_mb_2u_lib.s9s_mb_2u(sch_1):delta_l_85_10inch_in3_dn';
NODE_NAME     J79 2
 '@S9S_MB_2U_LIB.S9S_MB_2U(SCH_1):PAGE287_I42@PURE_QUANTA.PICOPROBE_BXA(CHIPS)':
 '2_N': CDS_PINID='\2_n\';
NODE_NAME     J85 1
 '@S9S_MB_2U_LIB.S9S_MB_2U(SCH_1):PAGE287_I54@PURE_QUANTA.PICOPROBE_BXA(CHIPS)':
 '1_P': CDS_PINID='\1_p\';
NET_NAME
'DELTA_L_85_10INCH_IN3_DP'
 '@S9S_MB_2U_LIB.S9S_MB_2U(SCH_1):DELTA_L_85_10INCH_IN3_DP':
 C_SIGNAL='@s9s_mb_2u_lib.s9s_mb_2u(sch_1):delta_l_85_10inch_in3_dp';
NODE_NAME     J79 1
 '@S9S_MB_2U_LIB.S9S_MB_2U(SCH_1):PAGE287_I42@PURE_QUANTA.PICOPROBE_BXA(CHIPS)':
 '1_P': CDS_PINID='\1_p\';
NODE_NAME     J85 2
 '@S9S_MB_2U_LIB.S9S_MB_2U(SCH_1):PAGE287_I54@PURE_QUANTA.PICOPROBE_BXA(CHIPS)':
 '2_N': CDS_PINID='\2_n\';
NET_NAME
'DELTA_L_85_10INCH_IN4_DN'
 '@S9S_MB_2U_LIB.S9S_MB_2U(SCH_1):DELTA_L_85_10INCH_IN4_DN':
 C_SIGNAL='@s9s_mb_2u_lib.s9s_mb_2u(sch_1):delta_l_85_10inch_in4_dn';
NODE_NAME     J80 2
 '@S9S_MB_2U_LIB.S9S_MB_2U(SCH_1):PAGE287_I39@PURE_QUANTA.PICOPROBE_BXA(CHIPS)':
 '2_N': CDS_PINID='\2_n\';
NODE_NAME     J86 1
 '@S9S_MB_2U_LIB.S9S_MB_2U(SCH_1):PAGE287_I53@PURE_QUANTA.PICOPROBE_BXA(CHIPS)':
 '1_P': CDS_PINID='\1_p\';
NET_NAME
'DELTA_L_85_10INCH_IN4_DP'
 '@S9S_MB_2U_LIB.S9S_MB_2U(SCH_1):DELTA_L_85_10INCH_IN4_DP':
 C_SIGNAL='@s9s_mb_2u_lib.s9s_mb_2u(sch_1):delta_l_85_10inch_in4_dp';
NODE_NAME     J80 1
 '@S9S_MB_2U_LIB.S9S_MB_2U(SCH_1):PAGE287_I39@PURE_QUANTA.PICOPROBE_BXA(CHIPS)':
 '1_P': CDS_PINID='\1_p\';
NODE_NAME     J86 2
 '@S9S_MB_2U_LIB.S9S_MB_2U(SCH_1):PAGE287_I53@PURE_QUANTA.PICOPROBE_BXA(CHIPS)':
 '2_N': CDS_PINID='\2_n\';
NET_NAME
'DELTA_L_85_10INCH_IN5_DN'
 '@S9S_MB_2U_LIB.S9S_MB_2U(SCH_1):DELTA_L_85_10INCH_IN5_DN':
 C_SIGNAL='@s9s_mb_2u_lib.s9s_mb_2u(sch_1):delta_l_85_10inch_in5_dn';
NODE_NAME     J118 2
 '@S9S_MB_2U_LIB.S9S_MB_2U(SCH_1):PAGE287_I30@PURE_QUANTA.PICOPROBE_BXA(CHIPS)':
 '2_N': CDS_PINID='\2_n\';
NODE_NAME     J120 1
 '@S9S_MB_2U_LIB.S9S_MB_2U(SCH_1):PAGE287_I32@PURE_QUANTA.PICOPROBE_BXA(CHIPS)':
 '1_P': CDS_PINID='\1_p\';
NET_NAME
'DELTA_L_85_10INCH_IN5_DP'
 '@S9S_MB_2U_LIB.S9S_MB_2U(SCH_1):DELTA_L_85_10INCH_IN5_DP':
 C_SIGNAL='@s9s_mb_2u_lib.s9s_mb_2u(sch_1):delta_l_85_10inch_in5_dp';
NODE_NAME     J118 1
 '@S9S_MB_2U_LIB.S9S_MB_2U(SCH_1):PAGE287_I30@PURE_QUANTA.PICOPROBE_BXA(CHIPS)':
 '1_P': CDS_PINID='\1_p\';
NODE_NAME     J120 2
 '@S9S_MB_2U_LIB.S9S_MB_2U(SCH_1):PAGE287_I32@PURE_QUANTA.PICOPROBE_BXA(CHIPS)':
 '2_N': CDS_PINID='\2_n\';
NET_NAME
'DELTA_L_85_10INCH_IN6_DN'
 '@S9S_MB_2U_LIB.S9S_MB_2U(SCH_1):DELTA_L_85_10INCH_IN6_DN':
 C_SIGNAL='@s9s_mb_2u_lib.s9s_mb_2u(sch_1):delta_l_85_10inch_in6_dn';
NODE_NAME     J121 1
 '@S9S_MB_2U_LIB.S9S_MB_2U(SCH_1):PAGE287_I31@PURE_QUANTA.PICOPROBE_BXA(CHIPS)':
 '1_P': CDS_PINID='\1_p\';
NODE_NAME     J119 2
 '@S9S_MB_2U_LIB.S9S_MB_2U(SCH_1):PAGE287_I28@PURE_QUANTA.PICOPROBE_BXA(CHIPS)':
 '2_N': CDS_PINID='\2_n\';
NET_NAME
'DELTA_L_85_10INCH_IN6_DP'
 '@S9S_MB_2U_LIB.S9S_MB_2U(SCH_1):DELTA_L_85_10INCH_IN6_DP':
 C_SIGNAL='@s9s_mb_2u_lib.s9s_mb_2u(sch_1):delta_l_85_10inch_in6_dp';
NODE_NAME     J121 2
 '@S9S_MB_2U_LIB.S9S_MB_2U(SCH_1):PAGE287_I31@PURE_QUANTA.PICOPROBE_BXA(CHIPS)':
 '2_N': CDS_PINID='\2_n\';
NODE_NAME     J119 1
 '@S9S_MB_2U_LIB.S9S_MB_2U(SCH_1):PAGE287_I28@PURE_QUANTA.PICOPROBE_BXA(CHIPS)':
 '1_P': CDS_PINID='\1_p\';
NET_NAME
'DELTA_L_85_10INCH_TOP_DN'
 '@S9S_MB_2U_LIB.S9S_MB_2U(SCH_1):DELTA_L_85_10INCH_TOP_DN':
 C_SIGNAL='@s9s_mb_2u_lib.s9s_mb_2u(sch_1):delta_l_85_10inch_top_dn';
NODE_NAME     J75 2
 '@S9S_MB_2U_LIB.S9S_MB_2U(SCH_1):PAGE287_I52@PURE_QUANTA.PICOPROBE_BXA(CHIPS)':
 '2_N': CDS_PINID='\2_n\';
NODE_NAME     J81 1
 '@S9S_MB_2U_LIB.S9S_MB_2U(SCH_1):PAGE287_I58@PURE_QUANTA.PICOPROBE_BXA(CHIPS)':
 '1_P': CDS_PINID='\1_p\';
NET_NAME
'DELTA_L_85_10INCH_TOP_DP'
 '@S9S_MB_2U_LIB.S9S_MB_2U(SCH_1):DELTA_L_85_10INCH_TOP_DP':
 C_SIGNAL='@s9s_mb_2u_lib.s9s_mb_2u(sch_1):delta_l_85_10inch_top_dp';
NODE_NAME     J75 1
 '@S9S_MB_2U_LIB.S9S_MB_2U(SCH_1):PAGE287_I52@PURE_QUANTA.PICOPROBE_BXA(CHIPS)':
 '1_P': CDS_PINID='\1_p\';
NODE_NAME     J81 2
 '@S9S_MB_2U_LIB.S9S_MB_2U(SCH_1):PAGE287_I58@PURE_QUANTA.PICOPROBE_BXA(CHIPS)':
 '2_N': CDS_PINID='\2_n\';
NET_NAME
'DELTA_L_85_5INCH_BOT_DN'
 '@S9S_MB_2U_LIB.S9S_MB_2U(SCH_1):DELTA_L_85_5INCH_BOT_DN':
 C_SIGNAL='@s9s_mb_2u_lib.s9s_mb_2u(sch_1):delta_l_85_5inch_bot_dn';
NODE_NAME     J70 1
 '@S9S_MB_2U_LIB.S9S_MB_2U(SCH_1):PAGE287_I23@PURE_QUANTA.PICOPROBE_BXA(CHIPS)':
 '1_P': CDS_PINID='\1_p\';
NODE_NAME     J64 2
 '@S9S_MB_2U_LIB.S9S_MB_2U(SCH_1):PAGE287_I17@PURE_QUANTA.PICOPROBE_BXA(CHIPS)':
 '2_N': CDS_PINID='\2_n\';
NET_NAME
'DELTA_L_85_5INCH_BOT_DP'
 '@S9S_MB_2U_LIB.S9S_MB_2U(SCH_1):DELTA_L_85_5INCH_BOT_DP':
 C_SIGNAL='@s9s_mb_2u_lib.s9s_mb_2u(sch_1):delta_l_85_5inch_bot_dp';
NODE_NAME     J70 2
 '@S9S_MB_2U_LIB.S9S_MB_2U(SCH_1):PAGE287_I23@PURE_QUANTA.PICOPROBE_BXA(CHIPS)':
 '2_N': CDS_PINID='\2_n\';
NODE_NAME     J64 1
 '@S9S_MB_2U_LIB.S9S_MB_2U(SCH_1):PAGE287_I17@PURE_QUANTA.PICOPROBE_BXA(CHIPS)':
 '1_P': CDS_PINID='\1_p\';
NET_NAME
'DELTA_L_85_5INCH_IN1_DN'
 '@S9S_MB_2U_LIB.S9S_MB_2U(SCH_1):DELTA_L_85_5INCH_IN1_DN':
 C_SIGNAL='@s9s_mb_2u_lib.s9s_mb_2u(sch_1):delta_l_85_5inch_in1_dn';
NODE_NAME     J65 2
 '@S9S_MB_2U_LIB.S9S_MB_2U(SCH_1):PAGE287_I14@PURE_QUANTA.PICOPROBE_BXA(CHIPS)':
 '2_N': CDS_PINID='\2_n\';
NODE_NAME     J71 1
 '@S9S_MB_2U_LIB.S9S_MB_2U(SCH_1):PAGE287_I22@PURE_QUANTA.PICOPROBE_BXA(CHIPS)':
 '1_P': CDS_PINID='\1_p\';
NET_NAME
'DELTA_L_85_5INCH_IN1_DP'
 '@S9S_MB_2U_LIB.S9S_MB_2U(SCH_1):DELTA_L_85_5INCH_IN1_DP':
 C_SIGNAL='@s9s_mb_2u_lib.s9s_mb_2u(sch_1):delta_l_85_5inch_in1_dp';
NODE_NAME     J65 1
 '@S9S_MB_2U_LIB.S9S_MB_2U(SCH_1):PAGE287_I14@PURE_QUANTA.PICOPROBE_BXA(CHIPS)':
 '1_P': CDS_PINID='\1_p\';
NODE_NAME     J71 2
 '@S9S_MB_2U_LIB.S9S_MB_2U(SCH_1):PAGE287_I22@PURE_QUANTA.PICOPROBE_BXA(CHIPS)':
 '2_N': CDS_PINID='\2_n\';
NET_NAME
'DELTA_L_85_5INCH_IN2_DN'
 '@S9S_MB_2U_LIB.S9S_MB_2U(SCH_1):DELTA_L_85_5INCH_IN2_DN':
 C_SIGNAL='@s9s_mb_2u_lib.s9s_mb_2u(sch_1):delta_l_85_5inch_in2_dn';
NODE_NAME     J66 2
 '@S9S_MB_2U_LIB.S9S_MB_2U(SCH_1):PAGE287_I12@PURE_QUANTA.PICOPROBE_BXA(CHIPS)':
 '2_N': CDS_PINID='\2_n\';
NODE_NAME     J72 1
 '@S9S_MB_2U_LIB.S9S_MB_2U(SCH_1):PAGE287_I21@PURE_QUANTA.PICOPROBE_BXA(CHIPS)':
 '1_P': CDS_PINID='\1_p\';
NET_NAME
'DELTA_L_85_5INCH_IN2_DP'
 '@S9S_MB_2U_LIB.S9S_MB_2U(SCH_1):DELTA_L_85_5INCH_IN2_DP':
 C_SIGNAL='@s9s_mb_2u_lib.s9s_mb_2u(sch_1):delta_l_85_5inch_in2_dp';
NODE_NAME     J66 1
 '@S9S_MB_2U_LIB.S9S_MB_2U(SCH_1):PAGE287_I12@PURE_QUANTA.PICOPROBE_BXA(CHIPS)':
 '1_P': CDS_PINID='\1_p\';
NODE_NAME     J72 2
 '@S9S_MB_2U_LIB.S9S_MB_2U(SCH_1):PAGE287_I21@PURE_QUANTA.PICOPROBE_BXA(CHIPS)':
 '2_N': CDS_PINID='\2_n\';
NET_NAME
'DELTA_L_85_5INCH_IN3_DN'
 '@S9S_MB_2U_LIB.S9S_MB_2U(SCH_1):DELTA_L_85_5INCH_IN3_DN':
 C_SIGNAL='@s9s_mb_2u_lib.s9s_mb_2u(sch_1):delta_l_85_5inch_in3_dn';
NODE_NAME     J67 2
 '@S9S_MB_2U_LIB.S9S_MB_2U(SCH_1):PAGE287_I11@PURE_QUANTA.PICOPROBE_BXA(CHIPS)':
 '2_N': CDS_PINID='\2_n\';
NODE_NAME     J73 1
 '@S9S_MB_2U_LIB.S9S_MB_2U(SCH_1):PAGE287_I20@PURE_QUANTA.PICOPROBE_BXA(CHIPS)':
 '1_P': CDS_PINID='\1_p\';
NET_NAME
'DELTA_L_85_5INCH_IN3_DP'
 '@S9S_MB_2U_LIB.S9S_MB_2U(SCH_1):DELTA_L_85_5INCH_IN3_DP':
 C_SIGNAL='@s9s_mb_2u_lib.s9s_mb_2u(sch_1):delta_l_85_5inch_in3_dp';
NODE_NAME     J67 1
 '@S9S_MB_2U_LIB.S9S_MB_2U(SCH_1):PAGE287_I11@PURE_QUANTA.PICOPROBE_BXA(CHIPS)':
 '1_P': CDS_PINID='\1_p\';
NODE_NAME     J73 2
 '@S9S_MB_2U_LIB.S9S_MB_2U(SCH_1):PAGE287_I20@PURE_QUANTA.PICOPROBE_BXA(CHIPS)':
 '2_N': CDS_PINID='\2_n\';
NET_NAME
'DELTA_L_85_5INCH_IN4_DN'
 '@S9S_MB_2U_LIB.S9S_MB_2U(SCH_1):DELTA_L_85_5INCH_IN4_DN':
 C_SIGNAL='@s9s_mb_2u_lib.s9s_mb_2u(sch_1):delta_l_85_5inch_in4_dn';
NODE_NAME     J68 2
 '@S9S_MB_2U_LIB.S9S_MB_2U(SCH_1):PAGE287_I8@PURE_QUANTA.PICOPROBE_BXA(CHIPS)':
 '2_N': CDS_PINID='\2_n\';
NODE_NAME     J74 1
 '@S9S_MB_2U_LIB.S9S_MB_2U(SCH_1):PAGE287_I19@PURE_QUANTA.PICOPROBE_BXA(CHIPS)':
 '1_P': CDS_PINID='\1_p\';
NET_NAME
'DELTA_L_85_5INCH_IN4_DP'
 '@S9S_MB_2U_LIB.S9S_MB_2U(SCH_1):DELTA_L_85_5INCH_IN4_DP':
 C_SIGNAL='@s9s_mb_2u_lib.s9s_mb_2u(sch_1):delta_l_85_5inch_in4_dp';
NODE_NAME     J68 1
 '@S9S_MB_2U_LIB.S9S_MB_2U(SCH_1):PAGE287_I8@PURE_QUANTA.PICOPROBE_BXA(CHIPS)':
 '1_P': CDS_PINID='\1_p\';
NODE_NAME     J74 2
 '@S9S_MB_2U_LIB.S9S_MB_2U(SCH_1):PAGE287_I19@PURE_QUANTA.PICOPROBE_BXA(CHIPS)':
 '2_N': CDS_PINID='\2_n\';
NET_NAME
'DELTA_L_85_5INCH_IN5_DN'
 '@S9S_MB_2U_LIB.S9S_MB_2U(SCH_1):DELTA_L_85_5INCH_IN5_DN':
 C_SIGNAL='@s9s_mb_2u_lib.s9s_mb_2u(sch_1):delta_l_85_5inch_in5_dn';
NODE_NAME     J114 2
 '@S9S_MB_2U_LIB.S9S_MB_2U(SCH_1):PAGE287_I4@PURE_QUANTA.PICOPROBE_BXA(CHIPS)':
 '2_N': CDS_PINID='\2_n\';
NODE_NAME     J116 1
 '@S9S_MB_2U_LIB.S9S_MB_2U(SCH_1):PAGE287_I6@PURE_QUANTA.PICOPROBE_BXA(CHIPS)':
 '1_P': CDS_PINID='\1_p\';
NET_NAME
'DELTA_L_85_5INCH_IN5_DP'
 '@S9S_MB_2U_LIB.S9S_MB_2U(SCH_1):DELTA_L_85_5INCH_IN5_DP':
 C_SIGNAL='@s9s_mb_2u_lib.s9s_mb_2u(sch_1):delta_l_85_5inch_in5_dp';
NODE_NAME     J114 1
 '@S9S_MB_2U_LIB.S9S_MB_2U(SCH_1):PAGE287_I4@PURE_QUANTA.PICOPROBE_BXA(CHIPS)':
 '1_P': CDS_PINID='\1_p\';
NODE_NAME     J116 2
 '@S9S_MB_2U_LIB.S9S_MB_2U(SCH_1):PAGE287_I6@PURE_QUANTA.PICOPROBE_BXA(CHIPS)':
 '2_N': CDS_PINID='\2_n\';
NET_NAME
'DELTA_L_85_5INCH_IN6_DN'
 '@S9S_MB_2U_LIB.S9S_MB_2U(SCH_1):DELTA_L_85_5INCH_IN6_DN':
 C_SIGNAL='@s9s_mb_2u_lib.s9s_mb_2u(sch_1):delta_l_85_5inch_in6_dn';
NODE_NAME     J115 2
 '@S9S_MB_2U_LIB.S9S_MB_2U(SCH_1):PAGE287_I3@PURE_QUANTA.PICOPROBE_BXA(CHIPS)':
 '2_N': CDS_PINID='\2_n\';
NODE_NAME     J117 1
 '@S9S_MB_2U_LIB.S9S_MB_2U(SCH_1):PAGE287_I5@PURE_QUANTA.PICOPROBE_BXA(CHIPS)':
 '1_P': CDS_PINID='\1_p\';
NET_NAME
'DELTA_L_85_5INCH_IN6_DP'
 '@S9S_MB_2U_LIB.S9S_MB_2U(SCH_1):DELTA_L_85_5INCH_IN6_DP':
 C_SIGNAL='@s9s_mb_2u_lib.s9s_mb_2u(sch_1):delta_l_85_5inch_in6_dp';
NODE_NAME     J115 1
 '@S9S_MB_2U_LIB.S9S_MB_2U(SCH_1):PAGE287_I3@PURE_QUANTA.PICOPROBE_BXA(CHIPS)':
 '1_P': CDS_PINID='\1_p\';
NODE_NAME     J117 2
 '@S9S_MB_2U_LIB.S9S_MB_2U(SCH_1):PAGE287_I5@PURE_QUANTA.PICOPROBE_BXA(CHIPS)':
 '2_N': CDS_PINID='\2_n\';
NET_NAME
'DELTA_L_85_5INCH_TOP_DN'
 '@S9S_MB_2U_LIB.S9S_MB_2U(SCH_1):DELTA_L_85_5INCH_TOP_DN':
 C_SIGNAL='@s9s_mb_2u_lib.s9s_mb_2u(sch_1):delta_l_85_5inch_top_dn';
NODE_NAME     J63 2
 '@S9S_MB_2U_LIB.S9S_MB_2U(SCH_1):PAGE287_I18@PURE_QUANTA.PICOPROBE_BXA(CHIPS)':
 '2_N': CDS_PINID='\2_n\';
NODE_NAME     J69 1
 '@S9S_MB_2U_LIB.S9S_MB_2U(SCH_1):PAGE287_I24@PURE_QUANTA.PICOPROBE_BXA(CHIPS)':
 '1_P': CDS_PINID='\1_p\';
NET_NAME
'DELTA_L_85_5INCH_TOP_DP'
 '@S9S_MB_2U_LIB.S9S_MB_2U(SCH_1):DELTA_L_85_5INCH_TOP_DP':
 C_SIGNAL='@s9s_mb_2u_lib.s9s_mb_2u(sch_1):delta_l_85_5inch_top_dp';
NODE_NAME     J63 1
 '@S9S_MB_2U_LIB.S9S_MB_2U(SCH_1):PAGE287_I18@PURE_QUANTA.PICOPROBE_BXA(CHIPS)':
 '1_P': CDS_PINID='\1_p\';
NODE_NAME     J69 2
 '@S9S_MB_2U_LIB.S9S_MB_2U(SCH_1):PAGE287_I24@PURE_QUANTA.PICOPROBE_BXA(CHIPS)':
 '2_N': CDS_PINID='\2_n\';
NET_NAME
'DELTA_L_GND_1'
 '@S9S_MB_2U_LIB.S9S_MB_2U(SCH_1):DELTA_L_GND_1':
 C_SIGNAL='@s9s_mb_2u_lib.s9s_mb_2u(sch_1):delta_l_gnd_1',
 CDS_GLOBAL_NET='TRUE';
NODE_NAME     J68 3
 '@S9S_MB_2U_LIB.S9S_MB_2U(SCH_1):PAGE287_I8@PURE_QUANTA.PICOPROBE_BXA(CHIPS)':
 '3_G': CDS_PINID='\3_g\';
NODE_NAME     J67 3
 '@S9S_MB_2U_LIB.S9S_MB_2U(SCH_1):PAGE287_I11@PURE_QUANTA.PICOPROBE_BXA(CHIPS)':
 '3_G': CDS_PINID='\3_g\';
NODE_NAME     J66 3
 '@S9S_MB_2U_LIB.S9S_MB_2U(SCH_1):PAGE287_I12@PURE_QUANTA.PICOPROBE_BXA(CHIPS)':
 '3_G': CDS_PINID='\3_g\';
NODE_NAME     J74 3
 '@S9S_MB_2U_LIB.S9S_MB_2U(SCH_1):PAGE287_I19@PURE_QUANTA.PICOPROBE_BXA(CHIPS)':
 '3_G': CDS_PINID='\3_g\';
NODE_NAME     J72 3
 '@S9S_MB_2U_LIB.S9S_MB_2U(SCH_1):PAGE287_I21@PURE_QUANTA.PICOPROBE_BXA(CHIPS)':
 '3_G': CDS_PINID='\3_g\';
NODE_NAME     J70 3
 '@S9S_MB_2U_LIB.S9S_MB_2U(SCH_1):PAGE287_I23@PURE_QUANTA.PICOPROBE_BXA(CHIPS)':
 '3_G': CDS_PINID='\3_g\';
NODE_NAME     J118 3
 '@S9S_MB_2U_LIB.S9S_MB_2U(SCH_1):PAGE287_I30@PURE_QUANTA.PICOPROBE_BXA(CHIPS)':
 '3_G': CDS_PINID='\3_g\';
NODE_NAME     J121 3
 '@S9S_MB_2U_LIB.S9S_MB_2U(SCH_1):PAGE287_I31@PURE_QUANTA.PICOPROBE_BXA(CHIPS)':
 '3_G': CDS_PINID='\3_g\';
NODE_NAME     J120 3
 '@S9S_MB_2U_LIB.S9S_MB_2U(SCH_1):PAGE287_I32@PURE_QUANTA.PICOPROBE_BXA(CHIPS)':
 '3_G': CDS_PINID='\3_g\';
NODE_NAME     J80 3
 '@S9S_MB_2U_LIB.S9S_MB_2U(SCH_1):PAGE287_I39@PURE_QUANTA.PICOPROBE_BXA(CHIPS)':
 '3_G': CDS_PINID='\3_g\';
NODE_NAME     J78 3
 '@S9S_MB_2U_LIB.S9S_MB_2U(SCH_1):PAGE287_I43@PURE_QUANTA.PICOPROBE_BXA(CHIPS)':
 '3_G': CDS_PINID='\3_g\';
NODE_NAME     J75 3
 '@S9S_MB_2U_LIB.S9S_MB_2U(SCH_1):PAGE287_I52@PURE_QUANTA.PICOPROBE_BXA(CHIPS)':
 '3_G': CDS_PINID='\3_g\';
NODE_NAME     J86 3
 '@S9S_MB_2U_LIB.S9S_MB_2U(SCH_1):PAGE287_I53@PURE_QUANTA.PICOPROBE_BXA(CHIPS)':
 '3_G': CDS_PINID='\3_g\';
NODE_NAME     J84 3
 '@S9S_MB_2U_LIB.S9S_MB_2U(SCH_1):PAGE287_I55@PURE_QUANTA.PICOPROBE_BXA(CHIPS)':
 '3_G': CDS_PINID='\3_g\';
NODE_NAME     J82 3
 '@S9S_MB_2U_LIB.S9S_MB_2U(SCH_1):PAGE287_I57@PURE_QUANTA.PICOPROBE_BXA(CHIPS)':
 '3_G': CDS_PINID='\3_g\';
NODE_NAME     J115 3
 '@S9S_MB_2U_LIB.S9S_MB_2U(SCH_1):PAGE287_I3@PURE_QUANTA.PICOPROBE_BXA(CHIPS)':
 '3_G': CDS_PINID='\3_g\';
NODE_NAME     J114 3
 '@S9S_MB_2U_LIB.S9S_MB_2U(SCH_1):PAGE287_I4@PURE_QUANTA.PICOPROBE_BXA(CHIPS)':
 '3_G': CDS_PINID='\3_g\';
NODE_NAME     J117 3
 '@S9S_MB_2U_LIB.S9S_MB_2U(SCH_1):PAGE287_I5@PURE_QUANTA.PICOPROBE_BXA(CHIPS)':
 '3_G': CDS_PINID='\3_g\';
NODE_NAME     J116 3
 '@S9S_MB_2U_LIB.S9S_MB_2U(SCH_1):PAGE287_I6@PURE_QUANTA.PICOPROBE_BXA(CHIPS)':
 '3_G': CDS_PINID='\3_g\';
NODE_NAME     J65 3
 '@S9S_MB_2U_LIB.S9S_MB_2U(SCH_1):PAGE287_I14@PURE_QUANTA.PICOPROBE_BXA(CHIPS)':
 '3_G': CDS_PINID='\3_g\';
NODE_NAME     J64 3
 '@S9S_MB_2U_LIB.S9S_MB_2U(SCH_1):PAGE287_I17@PURE_QUANTA.PICOPROBE_BXA(CHIPS)':
 '3_G': CDS_PINID='\3_g\';
NODE_NAME     J63 3
 '@S9S_MB_2U_LIB.S9S_MB_2U(SCH_1):PAGE287_I18@PURE_QUANTA.PICOPROBE_BXA(CHIPS)':
 '3_G': CDS_PINID='\3_g\';
NODE_NAME     J73 3
 '@S9S_MB_2U_LIB.S9S_MB_2U(SCH_1):PAGE287_I20@PURE_QUANTA.PICOPROBE_BXA(CHIPS)':
 '3_G': CDS_PINID='\3_g\';
NODE_NAME     J71 3
 '@S9S_MB_2U_LIB.S9S_MB_2U(SCH_1):PAGE287_I22@PURE_QUANTA.PICOPROBE_BXA(CHIPS)':
 '3_G': CDS_PINID='\3_g\';
NODE_NAME     J69 3
 '@S9S_MB_2U_LIB.S9S_MB_2U(SCH_1):PAGE287_I24@PURE_QUANTA.PICOPROBE_BXA(CHIPS)':
 '3_G': CDS_PINID='\3_g\';
NODE_NAME     J119 3
 '@S9S_MB_2U_LIB.S9S_MB_2U(SCH_1):PAGE287_I28@PURE_QUANTA.PICOPROBE_BXA(CHIPS)':
 '3_G': CDS_PINID='\3_g\';
NODE_NAME     J79 3
 '@S9S_MB_2U_LIB.S9S_MB_2U(SCH_1):PAGE287_I42@PURE_QUANTA.PICOPROBE_BXA(CHIPS)':
 '3_G': CDS_PINID='\3_g\';
NODE_NAME     J77 3
 '@S9S_MB_2U_LIB.S9S_MB_2U(SCH_1):PAGE287_I48@PURE_QUANTA.PICOPROBE_BXA(CHIPS)':
 '3_G': CDS_PINID='\3_g\';
NODE_NAME     J76 3
 '@S9S_MB_2U_LIB.S9S_MB_2U(SCH_1):PAGE287_I51@PURE_QUANTA.PICOPROBE_BXA(CHIPS)':
 '3_G': CDS_PINID='\3_g\';
NODE_NAME     J85 3
 '@S9S_MB_2U_LIB.S9S_MB_2U(SCH_1):PAGE287_I54@PURE_QUANTA.PICOPROBE_BXA(CHIPS)':
 '3_G': CDS_PINID='\3_g\';
NODE_NAME     J83 3
 '@S9S_MB_2U_LIB.S9S_MB_2U(SCH_1):PAGE287_I56@PURE_QUANTA.PICOPROBE_BXA(CHIPS)':
 '3_G': CDS_PINID='\3_g\';
NODE_NAME     J81 3
 '@S9S_MB_2U_LIB.S9S_MB_2U(SCH_1):PAGE287_I58@PURE_QUANTA.PICOPROBE_BXA(CHIPS)':
 '3_G': CDS_PINID='\3_g\';
NET_NAME
'DMI_CPU0_PCH_RX_C_DN<0>'
 '@S9S_MB_2U_LIB.S9S_MB_2U(SCH_1):DMI_CPU0_PCH_RX_C_DN'<0>:
 C_SIGNAL='@s9s_mb_2u_lib.s9s_mb_2u(sch_1):dmi_cpu0_pch_rx_c_dn(0)';
NODE_NAME     U2 BB18
 '@S9S_MB_2U_LIB.S9S_MB_2U(SCH_1):PAGE28_I169@PURE_QUANTA.SOCKET4677_AZIF0045P001C01CS(CHIPS)':
 'DMI_RX_DN0': CDS_PINID='DMI_RX_DN0';
NODE_NAME     C169 1
 '@S9S_MB_2U_LIB.S9S_MB_2U(SCH_1):PAGE169_I127@PURE_QUANTA.Q_CAP_DIFFBUS(CHIPS)':
 '1': CDS_PINID='\1\';
NET_NAME
'DMI_CPU0_PCH_RX_C_DN<1>'
 '@S9S_MB_2U_LIB.S9S_MB_2U(SCH_1):DMI_CPU0_PCH_RX_C_DN'<1>:
 C_SIGNAL='@s9s_mb_2u_lib.s9s_mb_2u(sch_1):dmi_cpu0_pch_rx_c_dn(1)';
NODE_NAME     U2 BD18
 '@S9S_MB_2U_LIB.S9S_MB_2U(SCH_1):PAGE28_I169@PURE_QUANTA.SOCKET4677_AZIF0045P001C01CS(CHIPS)':
 'DMI_RX_DP1': CDS_PINID='DMI_RX_DP1';
NODE_NAME     C167 1
 '@S9S_MB_2U_LIB.S9S_MB_2U(SCH_1):PAGE169_I126@PURE_QUANTA.Q_CAP_DIFFBUS(CHIPS)':
 '1': CDS_PINID='\1\';
NET_NAME
'DMI_CPU0_PCH_RX_C_DN<2>'
 '@S9S_MB_2U_LIB.S9S_MB_2U(SCH_1):DMI_CPU0_PCH_RX_C_DN'<2>:
 C_SIGNAL='@s9s_mb_2u_lib.s9s_mb_2u(sch_1):dmi_cpu0_pch_rx_c_dn(2)';
NODE_NAME     U2 BF18
 '@S9S_MB_2U_LIB.S9S_MB_2U(SCH_1):PAGE28_I169@PURE_QUANTA.SOCKET4677_AZIF0045P001C01CS(CHIPS)':
 'DMI_RX_DN2': CDS_PINID='DMI_RX_DN2';
NODE_NAME     C165 1
 '@S9S_MB_2U_LIB.S9S_MB_2U(SCH_1):PAGE169_I123@PURE_QUANTA.Q_CAP_DIFFBUS(CHIPS)':
 '1': CDS_PINID='\1\';
NET_NAME
'DMI_CPU0_PCH_RX_C_DN<3>'
 '@S9S_MB_2U_LIB.S9S_MB_2U(SCH_1):DMI_CPU0_PCH_RX_C_DN'<3>:
 C_SIGNAL='@s9s_mb_2u_lib.s9s_mb_2u(sch_1):dmi_cpu0_pch_rx_c_dn(3)';
NODE_NAME     U2 BH18
 '@S9S_MB_2U_LIB.S9S_MB_2U(SCH_1):PAGE28_I169@PURE_QUANTA.SOCKET4677_AZIF0045P001C01CS(CHIPS)':
 'DMI_RX_DP3': CDS_PINID='DMI_RX_DP3';
NODE_NAME     C163 1
 '@S9S_MB_2U_LIB.S9S_MB_2U(SCH_1):PAGE169_I121@PURE_QUANTA.Q_CAP_DIFFBUS(CHIPS)':
 '1': CDS_PINID='\1\';
NET_NAME
'DMI_CPU0_PCH_RX_C_DN<4>'
 '@S9S_MB_2U_LIB.S9S_MB_2U(SCH_1):DMI_CPU0_PCH_RX_C_DN'<4>:
 C_SIGNAL='@s9s_mb_2u_lib.s9s_mb_2u(sch_1):dmi_cpu0_pch_rx_c_dn(4)';
NODE_NAME     U2 BL19
 '@S9S_MB_2U_LIB.S9S_MB_2U(SCH_1):PAGE28_I169@PURE_QUANTA.SOCKET4677_AZIF0045P001C01CS(CHIPS)':
 'DMI_RX_DP4': CDS_PINID='DMI_RX_DP4';
NODE_NAME     C161 1
 '@S9S_MB_2U_LIB.S9S_MB_2U(SCH_1):PAGE169_I119@PURE_QUANTA.Q_CAP_DIFFBUS(CHIPS)':
 '1': CDS_PINID='\1\';
NET_NAME
'DMI_CPU0_PCH_RX_C_DN<5>'
 '@S9S_MB_2U_LIB.S9S_MB_2U(SCH_1):DMI_CPU0_PCH_RX_C_DN'<5>:
 C_SIGNAL='@s9s_mb_2u_lib.s9s_mb_2u(sch_1):dmi_cpu0_pch_rx_c_dn(5)';
NODE_NAME     U2 BM18
 '@S9S_MB_2U_LIB.S9S_MB_2U(SCH_1):PAGE28_I169@PURE_QUANTA.SOCKET4677_AZIF0045P001C01CS(CHIPS)':
 'DMI_RX_DP5': CDS_PINID='DMI_RX_DP5';
NODE_NAME     C159 1
 '@S9S_MB_2U_LIB.S9S_MB_2U(SCH_1):PAGE169_I117@PURE_QUANTA.Q_CAP_DIFFBUS(CHIPS)':
 '1': CDS_PINID='\1\';
NET_NAME
'DMI_CPU0_PCH_RX_C_DN<6>'
 '@S9S_MB_2U_LIB.S9S_MB_2U(SCH_1):DMI_CPU0_PCH_RX_C_DN'<6>:
 C_SIGNAL='@s9s_mb_2u_lib.s9s_mb_2u(sch_1):dmi_cpu0_pch_rx_c_dn(6)';
NODE_NAME     U2 BR19
 '@S9S_MB_2U_LIB.S9S_MB_2U(SCH_1):PAGE28_I169@PURE_QUANTA.SOCKET4677_AZIF0045P001C01CS(CHIPS)':
 'DMI_RX_DP6': CDS_PINID='DMI_RX_DP6';
NODE_NAME     C157 1
 '@S9S_MB_2U_LIB.S9S_MB_2U(SCH_1):PAGE169_I115@PURE_QUANTA.Q_CAP_DIFFBUS(CHIPS)':
 '1': CDS_PINID='\1\';
NET_NAME
'DMI_CPU0_PCH_RX_C_DN<7>'
 '@S9S_MB_2U_LIB.S9S_MB_2U(SCH_1):DMI_CPU0_PCH_RX_C_DN'<7>:
 C_SIGNAL='@s9s_mb_2u_lib.s9s_mb_2u(sch_1):dmi_cpu0_pch_rx_c_dn(7)';
NODE_NAME     U2 BU17
 '@S9S_MB_2U_LIB.S9S_MB_2U(SCH_1):PAGE28_I169@PURE_QUANTA.SOCKET4677_AZIF0045P001C01CS(CHIPS)':
 'DMI_RX_DN7': CDS_PINID='DMI_RX_DN7';
NODE_NAME     C155 1
 '@S9S_MB_2U_LIB.S9S_MB_2U(SCH_1):PAGE169_I113@PURE_QUANTA.Q_CAP_DIFFBUS(CHIPS)':
 '1': CDS_PINID='\1\';
NET_NAME
'DMI_CPU0_PCH_RX_C_DP<0>'
 '@S9S_MB_2U_LIB.S9S_MB_2U(SCH_1):DMI_CPU0_PCH_RX_C_DP'<0>:
 C_SIGNAL='@s9s_mb_2u_lib.s9s_mb_2u(sch_1):dmi_cpu0_pch_rx_c_dp(0)';
NODE_NAME     U2 BC19
 '@S9S_MB_2U_LIB.S9S_MB_2U(SCH_1):PAGE28_I169@PURE_QUANTA.SOCKET4677_AZIF0045P001C01CS(CHIPS)':
 'DMI_RX_DP0': CDS_PINID='DMI_RX_DP0';
NODE_NAME     C170 1
 '@S9S_MB_2U_LIB.S9S_MB_2U(SCH_1):PAGE169_I128@PURE_QUANTA.Q_CAP_DIFFBUS(CHIPS)':
 '1': CDS_PINID='\1\';
NET_NAME
'DMI_CPU0_PCH_RX_C_DP<1>'
 '@S9S_MB_2U_LIB.S9S_MB_2U(SCH_1):DMI_CPU0_PCH_RX_C_DP'<1>:
 C_SIGNAL='@s9s_mb_2u_lib.s9s_mb_2u(sch_1):dmi_cpu0_pch_rx_c_dp(1)';
NODE_NAME     U2 BE17
 '@S9S_MB_2U_LIB.S9S_MB_2U(SCH_1):PAGE28_I169@PURE_QUANTA.SOCKET4677_AZIF0045P001C01CS(CHIPS)':
 'DMI_RX_DN1': CDS_PINID='DMI_RX_DN1';
NODE_NAME     C168 1
 '@S9S_MB_2U_LIB.S9S_MB_2U(SCH_1):PAGE169_I125@PURE_QUANTA.Q_CAP_DIFFBUS(CHIPS)':
 '1': CDS_PINID='\1\';
NET_NAME
'DMI_CPU0_PCH_RX_C_DP<2>'
 '@S9S_MB_2U_LIB.S9S_MB_2U(SCH_1):DMI_CPU0_PCH_RX_C_DP'<2>:
 C_SIGNAL='@s9s_mb_2u_lib.s9s_mb_2u(sch_1):dmi_cpu0_pch_rx_c_dp(2)';
NODE_NAME     U2 BG19
 '@S9S_MB_2U_LIB.S9S_MB_2U(SCH_1):PAGE28_I169@PURE_QUANTA.SOCKET4677_AZIF0045P001C01CS(CHIPS)':
 'DMI_RX_DP2': CDS_PINID='DMI_RX_DP2';
NODE_NAME     C166 1
 '@S9S_MB_2U_LIB.S9S_MB_2U(SCH_1):PAGE169_I124@PURE_QUANTA.Q_CAP_DIFFBUS(CHIPS)':
 '1': CDS_PINID='\1\';
NET_NAME
'DMI_CPU0_PCH_RX_C_DP<3>'
 '@S9S_MB_2U_LIB.S9S_MB_2U(SCH_1):DMI_CPU0_PCH_RX_C_DP'<3>:
 C_SIGNAL='@s9s_mb_2u_lib.s9s_mb_2u(sch_1):dmi_cpu0_pch_rx_c_dp(3)';
NODE_NAME     U2 BJ17
 '@S9S_MB_2U_LIB.S9S_MB_2U(SCH_1):PAGE28_I169@PURE_QUANTA.SOCKET4677_AZIF0045P001C01CS(CHIPS)':
 'DMI_RX_DN3': CDS_PINID='DMI_RX_DN3';
NODE_NAME     C164 1
 '@S9S_MB_2U_LIB.S9S_MB_2U(SCH_1):PAGE169_I122@PURE_QUANTA.Q_CAP_DIFFBUS(CHIPS)':
 '1': CDS_PINID='\1\';
NET_NAME
'DMI_CPU0_PCH_RX_C_DP<4>'
 '@S9S_MB_2U_LIB.S9S_MB_2U(SCH_1):DMI_CPU0_PCH_RX_C_DP'<4>:
 C_SIGNAL='@s9s_mb_2u_lib.s9s_mb_2u(sch_1):dmi_cpu0_pch_rx_c_dp(4)';
NODE_NAME     U2 BK18
 '@S9S_MB_2U_LIB.S9S_MB_2U(SCH_1):PAGE28_I169@PURE_QUANTA.SOCKET4677_AZIF0045P001C01CS(CHIPS)':
 'DMI_RX_DN4': CDS_PINID='DMI_RX_DN4';
NODE_NAME     C162 1
 '@S9S_MB_2U_LIB.S9S_MB_2U(SCH_1):PAGE169_I120@PURE_QUANTA.Q_CAP_DIFFBUS(CHIPS)':
 '1': CDS_PINID='\1\';
NET_NAME
'DMI_CPU0_PCH_RX_C_DP<5>'
 '@S9S_MB_2U_LIB.S9S_MB_2U(SCH_1):DMI_CPU0_PCH_RX_C_DP'<5>:
 C_SIGNAL='@s9s_mb_2u_lib.s9s_mb_2u(sch_1):dmi_cpu0_pch_rx_c_dp(5)';
NODE_NAME     U2 BN17
 '@S9S_MB_2U_LIB.S9S_MB_2U(SCH_1):PAGE28_I169@PURE_QUANTA.SOCKET4677_AZIF0045P001C01CS(CHIPS)':
 'DMI_RX_DN5': CDS_PINID='DMI_RX_DN5';
NODE_NAME     C160 1
 '@S9S_MB_2U_LIB.S9S_MB_2U(SCH_1):PAGE169_I118@PURE_QUANTA.Q_CAP_DIFFBUS(CHIPS)':
 '1': CDS_PINID='\1\';
NET_NAME
'DMI_CPU0_PCH_RX_C_DP<6>'
 '@S9S_MB_2U_LIB.S9S_MB_2U(SCH_1):DMI_CPU0_PCH_RX_C_DP'<6>:
 C_SIGNAL='@s9s_mb_2u_lib.s9s_mb_2u(sch_1):dmi_cpu0_pch_rx_c_dp(6)';
NODE_NAME     U2 BP18
 '@S9S_MB_2U_LIB.S9S_MB_2U(SCH_1):PAGE28_I169@PURE_QUANTA.SOCKET4677_AZIF0045P001C01CS(CHIPS)':
 'DMI_RX_DN6': CDS_PINID='DMI_RX_DN6';
NODE_NAME     C158 1
 '@S9S_MB_2U_LIB.S9S_MB_2U(SCH_1):PAGE169_I116@PURE_QUANTA.Q_CAP_DIFFBUS(CHIPS)':
 '1': CDS_PINID='\1\';
NET_NAME
'DMI_CPU0_PCH_RX_C_DP<7>'
 '@S9S_MB_2U_LIB.S9S_MB_2U(SCH_1):DMI_CPU0_PCH_RX_C_DP'<7>:
 C_SIGNAL='@s9s_mb_2u_lib.s9s_mb_2u(sch_1):dmi_cpu0_pch_rx_c_dp(7)';
NODE_NAME     U2 BT18
 '@S9S_MB_2U_LIB.S9S_MB_2U(SCH_1):PAGE28_I169@PURE_QUANTA.SOCKET4677_AZIF0045P001C01CS(CHIPS)':
 'DMI_RX_DP7': CDS_PINID='DMI_RX_DP7';
NODE_NAME     C156 1
 '@S9S_MB_2U_LIB.S9S_MB_2U(SCH_1):PAGE169_I114@PURE_QUANTA.Q_CAP_DIFFBUS(CHIPS)':
 '1': CDS_PINID='\1\';
NET_NAME
'DMI_CPU0_PCH_RX_DN<0>'
 '@S9S_MB_2U_LIB.S9S_MB_2U(SCH_1):DMI_CPU0_PCH_RX_DN'<0>:
 C_SIGNAL='@s9s_mb_2u_lib.s9s_mb_2u(sch_1):dmi_cpu0_pch_rx_dn(0)';
NODE_NAME     C169 2
 '@S9S_MB_2U_LIB.S9S_MB_2U(SCH_1):PAGE169_I127@PURE_QUANTA.Q_CAP_DIFFBUS(CHIPS)':
 '2': CDS_PINID='\2\';
NODE_NAME     U4 K28
 '@S9S_MB_2U_LIB.S9S_MB_2U(SCH_1):PAGE173_I110@PURE_QUANTA.EMMITSBURG_REV0P9(CHIPS)':
 'DMI_0_TXN': CDS_PINID='DMI_0_TXN';
NET_NAME
'DMI_CPU0_PCH_RX_DN<1>'
 '@S9S_MB_2U_LIB.S9S_MB_2U(SCH_1):DMI_CPU0_PCH_RX_DN'<1>:
 C_SIGNAL='@s9s_mb_2u_lib.s9s_mb_2u(sch_1):dmi_cpu0_pch_rx_dn(1)';
NODE_NAME     C167 2
 '@S9S_MB_2U_LIB.S9S_MB_2U(SCH_1):PAGE169_I126@PURE_QUANTA.Q_CAP_DIFFBUS(CHIPS)':
 '2': CDS_PINID='\2\';
NODE_NAME     U4 G29
 '@S9S_MB_2U_LIB.S9S_MB_2U(SCH_1):PAGE173_I110@PURE_QUANTA.EMMITSBURG_REV0P9(CHIPS)':
 'DMI_1_TXN': CDS_PINID='DMI_1_TXN';
NET_NAME
'DMI_CPU0_PCH_RX_DN<2>'
 '@S9S_MB_2U_LIB.S9S_MB_2U(SCH_1):DMI_CPU0_PCH_RX_DN'<2>:
 C_SIGNAL='@s9s_mb_2u_lib.s9s_mb_2u(sch_1):dmi_cpu0_pch_rx_dn(2)';
NODE_NAME     C165 2
 '@S9S_MB_2U_LIB.S9S_MB_2U(SCH_1):PAGE169_I123@PURE_QUANTA.Q_CAP_DIFFBUS(CHIPS)':
 '2': CDS_PINID='\2\';
NODE_NAME     U4 J29
 '@S9S_MB_2U_LIB.S9S_MB_2U(SCH_1):PAGE173_I110@PURE_QUANTA.EMMITSBURG_REV0P9(CHIPS)':
 'DMI_2_TXN': CDS_PINID='DMI_2_TXN';
NET_NAME
'DMI_CPU0_PCH_RX_DN<3>'
 '@S9S_MB_2U_LIB.S9S_MB_2U(SCH_1):DMI_CPU0_PCH_RX_DN'<3>:
 C_SIGNAL='@s9s_mb_2u_lib.s9s_mb_2u(sch_1):dmi_cpu0_pch_rx_dn(3)';
NODE_NAME     C163 2
 '@S9S_MB_2U_LIB.S9S_MB_2U(SCH_1):PAGE169_I121@PURE_QUANTA.Q_CAP_DIFFBUS(CHIPS)':
 '2': CDS_PINID='\2\';
NODE_NAME     U4 L32
 '@S9S_MB_2U_LIB.S9S_MB_2U(SCH_1):PAGE173_I110@PURE_QUANTA.EMMITSBURG_REV0P9(CHIPS)':
 'DMI_3_TXN': CDS_PINID='DMI_3_TXN';
NET_NAME
'DMI_CPU0_PCH_RX_DN<4>'
 '@S9S_MB_2U_LIB.S9S_MB_2U(SCH_1):DMI_CPU0_PCH_RX_DN'<4>:
 C_SIGNAL='@s9s_mb_2u_lib.s9s_mb_2u(sch_1):dmi_cpu0_pch_rx_dn(4)';
NODE_NAME     C161 2
 '@S9S_MB_2U_LIB.S9S_MB_2U(SCH_1):PAGE169_I119@PURE_QUANTA.Q_CAP_DIFFBUS(CHIPS)':
 '2': CDS_PINID='\2\';
NODE_NAME     U4 J32
 '@S9S_MB_2U_LIB.S9S_MB_2U(SCH_1):PAGE173_I110@PURE_QUANTA.EMMITSBURG_REV0P9(CHIPS)':
 'DMI_4_SATA_19_PCIE3_19_TXN': CDS_PINID='DMI_4_SATA_19_PCIE3_19_TXN';
NET_NAME
'DMI_CPU0_PCH_RX_DN<5>'
 '@S9S_MB_2U_LIB.S9S_MB_2U(SCH_1):DMI_CPU0_PCH_RX_DN'<5>:
 C_SIGNAL='@s9s_mb_2u_lib.s9s_mb_2u(sch_1):dmi_cpu0_pch_rx_dn(5)';
NODE_NAME     C159 2
 '@S9S_MB_2U_LIB.S9S_MB_2U(SCH_1):PAGE169_I117@PURE_QUANTA.Q_CAP_DIFFBUS(CHIPS)':
 '2': CDS_PINID='\2\';
NODE_NAME     U4 G36
 '@S9S_MB_2U_LIB.S9S_MB_2U(SCH_1):PAGE173_I110@PURE_QUANTA.EMMITSBURG_REV0P9(CHIPS)':
 'DMI_5_SATA_18_PCIE3_18_TXN': CDS_PINID='DMI_5_SATA_18_PCIE3_18_TXN';
NET_NAME
'DMI_CPU0_PCH_RX_DN<6>'
 '@S9S_MB_2U_LIB.S9S_MB_2U(SCH_1):DMI_CPU0_PCH_RX_DN'<6>:
 C_SIGNAL='@s9s_mb_2u_lib.s9s_mb_2u(sch_1):dmi_cpu0_pch_rx_dn(6)';
NODE_NAME     C157 2
 '@S9S_MB_2U_LIB.S9S_MB_2U(SCH_1):PAGE169_I115@PURE_QUANTA.Q_CAP_DIFFBUS(CHIPS)':
 '2': CDS_PINID='\2\';
NODE_NAME     U4 K37
 '@S9S_MB_2U_LIB.S9S_MB_2U(SCH_1):PAGE173_I110@PURE_QUANTA.EMMITSBURG_REV0P9(CHIPS)':
 'DMI_6_SATA_17_PCIE3_17_TXN': CDS_PINID='DMI_6_SATA_17_PCIE3_17_TXN';
NET_NAME
'DMI_CPU0_PCH_RX_DN<7>'
 '@S9S_MB_2U_LIB.S9S_MB_2U(SCH_1):DMI_CPU0_PCH_RX_DN'<7>:
 C_SIGNAL='@s9s_mb_2u_lib.s9s_mb_2u(sch_1):dmi_cpu0_pch_rx_dn(7)';
NODE_NAME     C155 2
 '@S9S_MB_2U_LIB.S9S_MB_2U(SCH_1):PAGE169_I113@PURE_QUANTA.Q_CAP_DIFFBUS(CHIPS)':
 '2': CDS_PINID='\2\';
NODE_NAME     U4 F37
 '@S9S_MB_2U_LIB.S9S_MB_2U(SCH_1):PAGE173_I110@PURE_QUANTA.EMMITSBURG_REV0P9(CHIPS)':
 'DMI_7_SATA_16_PCIE3_16_TXN': CDS_PINID='DMI_7_SATA_16_PCIE3_16_TXN';
NET_NAME
'DMI_CPU0_PCH_RX_DP<0>'
 '@S9S_MB_2U_LIB.S9S_MB_2U(SCH_1):DMI_CPU0_PCH_RX_DP'<0>:
 C_SIGNAL='@s9s_mb_2u_lib.s9s_mb_2u(sch_1):dmi_cpu0_pch_rx_dp(0)';
NODE_NAME     C170 2
 '@S9S_MB_2U_LIB.S9S_MB_2U(SCH_1):PAGE169_I128@PURE_QUANTA.Q_CAP_DIFFBUS(CHIPS)':
 '2': CDS_PINID='\2\';
NODE_NAME     U4 H28
 '@S9S_MB_2U_LIB.S9S_MB_2U(SCH_1):PAGE173_I110@PURE_QUANTA.EMMITSBURG_REV0P9(CHIPS)':
 'DMI_0_TXP': CDS_PINID='DMI_0_TXP';
NET_NAME
'DMI_CPU0_PCH_RX_DP<1>'
 '@S9S_MB_2U_LIB.S9S_MB_2U(SCH_1):DMI_CPU0_PCH_RX_DP'<1>:
 C_SIGNAL='@s9s_mb_2u_lib.s9s_mb_2u(sch_1):dmi_cpu0_pch_rx_dp(1)';
NODE_NAME     C168 2
 '@S9S_MB_2U_LIB.S9S_MB_2U(SCH_1):PAGE169_I125@PURE_QUANTA.Q_CAP_DIFFBUS(CHIPS)':
 '2': CDS_PINID='\2\';
NODE_NAME     U4 F28
 '@S9S_MB_2U_LIB.S9S_MB_2U(SCH_1):PAGE173_I110@PURE_QUANTA.EMMITSBURG_REV0P9(CHIPS)':
 'DMI_1_TXP': CDS_PINID='DMI_1_TXP';
NET_NAME
'DMI_CPU0_PCH_RX_DP<2>'
 '@S9S_MB_2U_LIB.S9S_MB_2U(SCH_1):DMI_CPU0_PCH_RX_DP'<2>:
 C_SIGNAL='@s9s_mb_2u_lib.s9s_mb_2u(sch_1):dmi_cpu0_pch_rx_dp(2)';
NODE_NAME     C166 2
 '@S9S_MB_2U_LIB.S9S_MB_2U(SCH_1):PAGE169_I124@PURE_QUANTA.Q_CAP_DIFFBUS(CHIPS)':
 '2': CDS_PINID='\2\';
NODE_NAME     U4 H31
 '@S9S_MB_2U_LIB.S9S_MB_2U(SCH_1):PAGE173_I110@PURE_QUANTA.EMMITSBURG_REV0P9(CHIPS)':
 'DMI_2_TXP': CDS_PINID='DMI_2_TXP';
NET_NAME
'DMI_CPU0_PCH_RX_DP<3>'
 '@S9S_MB_2U_LIB.S9S_MB_2U(SCH_1):DMI_CPU0_PCH_RX_DP'<3>:
 C_SIGNAL='@s9s_mb_2u_lib.s9s_mb_2u(sch_1):dmi_cpu0_pch_rx_dp(3)';
NODE_NAME     C164 2
 '@S9S_MB_2U_LIB.S9S_MB_2U(SCH_1):PAGE169_I122@PURE_QUANTA.Q_CAP_DIFFBUS(CHIPS)':
 '2': CDS_PINID='\2\';
NODE_NAME     U4 K31
 '@S9S_MB_2U_LIB.S9S_MB_2U(SCH_1):PAGE173_I110@PURE_QUANTA.EMMITSBURG_REV0P9(CHIPS)':
 'DMI_3_TXP': CDS_PINID='DMI_3_TXP';
NET_NAME
'DMI_CPU0_PCH_RX_DP<4>'
 '@S9S_MB_2U_LIB.S9S_MB_2U(SCH_1):DMI_CPU0_PCH_RX_DP'<4>:
 C_SIGNAL='@s9s_mb_2u_lib.s9s_mb_2u(sch_1):dmi_cpu0_pch_rx_dp(4)';
NODE_NAME     C162 2
 '@S9S_MB_2U_LIB.S9S_MB_2U(SCH_1):PAGE169_I120@PURE_QUANTA.Q_CAP_DIFFBUS(CHIPS)':
 '2': CDS_PINID='\2\';
NODE_NAME     U4 G32
 '@S9S_MB_2U_LIB.S9S_MB_2U(SCH_1):PAGE173_I110@PURE_QUANTA.EMMITSBURG_REV0P9(CHIPS)':
 'DMI_4_SATA_19_PCIE3_19_TXP': CDS_PINID='DMI_4_SATA_19_PCIE3_19_TXP';
NET_NAME
'DMI_CPU0_PCH_RX_DP<5>'
 '@S9S_MB_2U_LIB.S9S_MB_2U(SCH_1):DMI_CPU0_PCH_RX_DP'<5>:
 C_SIGNAL='@s9s_mb_2u_lib.s9s_mb_2u(sch_1):dmi_cpu0_pch_rx_dp(5)';
NODE_NAME     C160 2
 '@S9S_MB_2U_LIB.S9S_MB_2U(SCH_1):PAGE169_I118@PURE_QUANTA.Q_CAP_DIFFBUS(CHIPS)':
 '2': CDS_PINID='\2\';
NODE_NAME     U4 H34
 '@S9S_MB_2U_LIB.S9S_MB_2U(SCH_1):PAGE173_I110@PURE_QUANTA.EMMITSBURG_REV0P9(CHIPS)':
 'DMI_5_SATA_18_PCIE3_18_TXP': CDS_PINID='DMI_5_SATA_18_PCIE3_18_TXP';
NET_NAME
'DMI_CPU0_PCH_RX_DP<6>'
 '@S9S_MB_2U_LIB.S9S_MB_2U(SCH_1):DMI_CPU0_PCH_RX_DP'<6>:
 C_SIGNAL='@s9s_mb_2u_lib.s9s_mb_2u(sch_1):dmi_cpu0_pch_rx_dp(6)';
NODE_NAME     C158 2
 '@S9S_MB_2U_LIB.S9S_MB_2U(SCH_1):PAGE169_I116@PURE_QUANTA.Q_CAP_DIFFBUS(CHIPS)':
 '2': CDS_PINID='\2\';
NODE_NAME     U4 J36
 '@S9S_MB_2U_LIB.S9S_MB_2U(SCH_1):PAGE173_I110@PURE_QUANTA.EMMITSBURG_REV0P9(CHIPS)':
 'DMI_6_SATA_17_PCIE3_17_TXP': CDS_PINID='DMI_6_SATA_17_PCIE3_17_TXP';
NET_NAME
'DMI_CPU0_PCH_RX_DP<7>'
 '@S9S_MB_2U_LIB.S9S_MB_2U(SCH_1):DMI_CPU0_PCH_RX_DP'<7>:
 C_SIGNAL='@s9s_mb_2u_lib.s9s_mb_2u(sch_1):dmi_cpu0_pch_rx_dp(7)';
NODE_NAME     C156 2
 '@S9S_MB_2U_LIB.S9S_MB_2U(SCH_1):PAGE169_I114@PURE_QUANTA.Q_CAP_DIFFBUS(CHIPS)':
 '2': CDS_PINID='\2\';
NODE_NAME     U4 H37
 '@S9S_MB_2U_LIB.S9S_MB_2U(SCH_1):PAGE173_I110@PURE_QUANTA.EMMITSBURG_REV0P9(CHIPS)':
 'DMI_7_SATA_16_PCIE3_16_TXP': CDS_PINID='DMI_7_SATA_16_PCIE3_16_TXP';
NET_NAME
'DMI_CPU0_PCH_TX_C_DN<0>'
 '@S9S_MB_2U_LIB.S9S_MB_2U(SCH_1):DMI_CPU0_PCH_TX_C_DN'<0>:
 C_SIGNAL='@s9s_mb_2u_lib.s9s_mb_2u(sch_1):dmi_cpu0_pch_tx_c_dn(0)';
NODE_NAME     C153 1
 '@S9S_MB_2U_LIB.S9S_MB_2U(SCH_1):PAGE169_I21@PURE_QUANTA.Q_CAP_DIFFBUS(CHIPS)':
 '1': CDS_PINID='\1\';
NODE_NAME     U4 A30
 '@S9S_MB_2U_LIB.S9S_MB_2U(SCH_1):PAGE173_I110@PURE_QUANTA.EMMITSBURG_REV0P9(CHIPS)':
 'DMI_0_RXN': CDS_PINID='DMI_0_RXN';
NET_NAME
'DMI_CPU0_PCH_TX_C_DN<1>'
 '@S9S_MB_2U_LIB.S9S_MB_2U(SCH_1):DMI_CPU0_PCH_TX_C_DN'<1>:
 C_SIGNAL='@s9s_mb_2u_lib.s9s_mb_2u(sch_1):dmi_cpu0_pch_tx_c_dn(1)';
NODE_NAME     C151 1
 '@S9S_MB_2U_LIB.S9S_MB_2U(SCH_1):PAGE169_I24@PURE_QUANTA.Q_CAP_DIFFBUS(CHIPS)':
 '1': CDS_PINID='\1\';
NODE_NAME     U4 B31
 '@S9S_MB_2U_LIB.S9S_MB_2U(SCH_1):PAGE173_I110@PURE_QUANTA.EMMITSBURG_REV0P9(CHIPS)':
 'DMI_1_RXN': CDS_PINID='DMI_1_RXN';
NET_NAME
'DMI_CPU0_PCH_TX_C_DN<2>'
 '@S9S_MB_2U_LIB.S9S_MB_2U(SCH_1):DMI_CPU0_PCH_TX_C_DN'<2>:
 C_SIGNAL='@s9s_mb_2u_lib.s9s_mb_2u(sch_1):dmi_cpu0_pch_tx_c_dn(2)';
NODE_NAME     C149 1
 '@S9S_MB_2U_LIB.S9S_MB_2U(SCH_1):PAGE169_I25@PURE_QUANTA.Q_CAP_DIFFBUS(CHIPS)':
 '1': CDS_PINID='\1\';
NODE_NAME     U4 A32
 '@S9S_MB_2U_LIB.S9S_MB_2U(SCH_1):PAGE173_I110@PURE_QUANTA.EMMITSBURG_REV0P9(CHIPS)':
 'DMI_2_RXN': CDS_PINID='DMI_2_RXN';
NET_NAME
'DMI_CPU0_PCH_TX_C_DN<3>'
 '@S9S_MB_2U_LIB.S9S_MB_2U(SCH_1):DMI_CPU0_PCH_TX_C_DN'<3>:
 C_SIGNAL='@s9s_mb_2u_lib.s9s_mb_2u(sch_1):dmi_cpu0_pch_tx_c_dn(3)';
NODE_NAME     C147 1
 '@S9S_MB_2U_LIB.S9S_MB_2U(SCH_1):PAGE169_I28@PURE_QUANTA.Q_CAP_DIFFBUS(CHIPS)':
 '1': CDS_PINID='\1\';
NODE_NAME     U4 B33
 '@S9S_MB_2U_LIB.S9S_MB_2U(SCH_1):PAGE173_I110@PURE_QUANTA.EMMITSBURG_REV0P9(CHIPS)':
 'DMI_3_RXN': CDS_PINID='DMI_3_RXN';
NET_NAME
'DMI_CPU0_PCH_TX_C_DN<4>'
 '@S9S_MB_2U_LIB.S9S_MB_2U(SCH_1):DMI_CPU0_PCH_TX_C_DN'<4>:
 C_SIGNAL='@s9s_mb_2u_lib.s9s_mb_2u(sch_1):dmi_cpu0_pch_tx_c_dn(4)';
NODE_NAME     C145 1
 '@S9S_MB_2U_LIB.S9S_MB_2U(SCH_1):PAGE169_I30@PURE_QUANTA.Q_CAP_DIFFBUS(CHIPS)':
 '1': CDS_PINID='\1\';
NODE_NAME     U4 A34
 '@S9S_MB_2U_LIB.S9S_MB_2U(SCH_1):PAGE173_I110@PURE_QUANTA.EMMITSBURG_REV0P9(CHIPS)':
 'DMI_4_SATA_19_PCIE3_19_RXN': CDS_PINID='DMI_4_SATA_19_PCIE3_19_RXN';
NET_NAME
'DMI_CPU0_PCH_TX_C_DN<5>'
 '@S9S_MB_2U_LIB.S9S_MB_2U(SCH_1):DMI_CPU0_PCH_TX_C_DN'<5>:
 C_SIGNAL='@s9s_mb_2u_lib.s9s_mb_2u(sch_1):dmi_cpu0_pch_tx_c_dn(5)';
NODE_NAME     C143 1
 '@S9S_MB_2U_LIB.S9S_MB_2U(SCH_1):PAGE169_I32@PURE_QUANTA.Q_CAP_DIFFBUS(CHIPS)':
 '1': CDS_PINID='\1\';
NODE_NAME     U4 B35
 '@S9S_MB_2U_LIB.S9S_MB_2U(SCH_1):PAGE173_I110@PURE_QUANTA.EMMITSBURG_REV0P9(CHIPS)':
 'DMI_5_SATA_18_PCIE3_18_RXN': CDS_PINID='DMI_5_SATA_18_PCIE3_18_RXN';
NET_NAME
'DMI_CPU0_PCH_TX_C_DN<6>'
 '@S9S_MB_2U_LIB.S9S_MB_2U(SCH_1):DMI_CPU0_PCH_TX_C_DN'<6>:
 C_SIGNAL='@s9s_mb_2u_lib.s9s_mb_2u(sch_1):dmi_cpu0_pch_tx_c_dn(6)';
NODE_NAME     C141 1
 '@S9S_MB_2U_LIB.S9S_MB_2U(SCH_1):PAGE169_I34@PURE_QUANTA.Q_CAP_DIFFBUS(CHIPS)':
 '1': CDS_PINID='\1\';
NODE_NAME     U4 A36
 '@S9S_MB_2U_LIB.S9S_MB_2U(SCH_1):PAGE173_I110@PURE_QUANTA.EMMITSBURG_REV0P9(CHIPS)':
 'DMI_6_SATA_17_PCIE3_17_RXN': CDS_PINID='DMI_6_SATA_17_PCIE3_17_RXN';
NET_NAME
'DMI_CPU0_PCH_TX_C_DN<7>'
 '@S9S_MB_2U_LIB.S9S_MB_2U(SCH_1):DMI_CPU0_PCH_TX_C_DN'<7>:
 C_SIGNAL='@s9s_mb_2u_lib.s9s_mb_2u(sch_1):dmi_cpu0_pch_tx_c_dn(7)';
NODE_NAME     C139 1
 '@S9S_MB_2U_LIB.S9S_MB_2U(SCH_1):PAGE169_I35@PURE_QUANTA.Q_CAP_DIFFBUS(CHIPS)':
 '1': CDS_PINID='\1\';
NODE_NAME     U4 B37
 '@S9S_MB_2U_LIB.S9S_MB_2U(SCH_1):PAGE173_I110@PURE_QUANTA.EMMITSBURG_REV0P9(CHIPS)':
 'DMI_7_SATA_16_PCIE3_16_RXN': CDS_PINID='DMI_7_SATA_16_PCIE3_16_RXN';
NET_NAME
'DMI_CPU0_PCH_TX_C_DP<0>'
 '@S9S_MB_2U_LIB.S9S_MB_2U(SCH_1):DMI_CPU0_PCH_TX_C_DP'<0>:
 C_SIGNAL='@s9s_mb_2u_lib.s9s_mb_2u(sch_1):dmi_cpu0_pch_tx_c_dp(0)';
NODE_NAME     C154 1
 '@S9S_MB_2U_LIB.S9S_MB_2U(SCH_1):PAGE169_I22@PURE_QUANTA.Q_CAP_DIFFBUS(CHIPS)':
 '1': CDS_PINID='\1\';
NODE_NAME     U4 C30
 '@S9S_MB_2U_LIB.S9S_MB_2U(SCH_1):PAGE173_I110@PURE_QUANTA.EMMITSBURG_REV0P9(CHIPS)':
 'DMI_0_RXP': CDS_PINID='DMI_0_RXP';
NET_NAME
'DMI_CPU0_PCH_TX_C_DP<1>'
 '@S9S_MB_2U_LIB.S9S_MB_2U(SCH_1):DMI_CPU0_PCH_TX_C_DP'<1>:
 C_SIGNAL='@s9s_mb_2u_lib.s9s_mb_2u(sch_1):dmi_cpu0_pch_tx_c_dp(1)';
NODE_NAME     C152 1
 '@S9S_MB_2U_LIB.S9S_MB_2U(SCH_1):PAGE169_I23@PURE_QUANTA.Q_CAP_DIFFBUS(CHIPS)':
 '1': CDS_PINID='\1\';
NODE_NAME     U4 D31
 '@S9S_MB_2U_LIB.S9S_MB_2U(SCH_1):PAGE173_I110@PURE_QUANTA.EMMITSBURG_REV0P9(CHIPS)':
 'DMI_1_RXP': CDS_PINID='DMI_1_RXP';
NET_NAME
'DMI_CPU0_PCH_TX_C_DP<2>'
 '@S9S_MB_2U_LIB.S9S_MB_2U(SCH_1):DMI_CPU0_PCH_TX_C_DP'<2>:
 C_SIGNAL='@s9s_mb_2u_lib.s9s_mb_2u(sch_1):dmi_cpu0_pch_tx_c_dp(2)';
NODE_NAME     C150 1
 '@S9S_MB_2U_LIB.S9S_MB_2U(SCH_1):PAGE169_I26@PURE_QUANTA.Q_CAP_DIFFBUS(CHIPS)':
 '1': CDS_PINID='\1\';
NODE_NAME     U4 C32
 '@S9S_MB_2U_LIB.S9S_MB_2U(SCH_1):PAGE173_I110@PURE_QUANTA.EMMITSBURG_REV0P9(CHIPS)':
 'DMI_2_RXP': CDS_PINID='DMI_2_RXP';
NET_NAME
'DMI_CPU0_PCH_TX_C_DP<3>'
 '@S9S_MB_2U_LIB.S9S_MB_2U(SCH_1):DMI_CPU0_PCH_TX_C_DP'<3>:
 C_SIGNAL='@s9s_mb_2u_lib.s9s_mb_2u(sch_1):dmi_cpu0_pch_tx_c_dp(3)';
NODE_NAME     C148 1
 '@S9S_MB_2U_LIB.S9S_MB_2U(SCH_1):PAGE169_I27@PURE_QUANTA.Q_CAP_DIFFBUS(CHIPS)':
 '1': CDS_PINID='\1\';
NODE_NAME     U4 D33
 '@S9S_MB_2U_LIB.S9S_MB_2U(SCH_1):PAGE173_I110@PURE_QUANTA.EMMITSBURG_REV0P9(CHIPS)':
 'DMI_3_RXP': CDS_PINID='DMI_3_RXP';
NET_NAME
'DMI_CPU0_PCH_TX_C_DP<4>'
 '@S9S_MB_2U_LIB.S9S_MB_2U(SCH_1):DMI_CPU0_PCH_TX_C_DP'<4>:
 C_SIGNAL='@s9s_mb_2u_lib.s9s_mb_2u(sch_1):dmi_cpu0_pch_tx_c_dp(4)';
NODE_NAME     C146 1
 '@S9S_MB_2U_LIB.S9S_MB_2U(SCH_1):PAGE169_I29@PURE_QUANTA.Q_CAP_DIFFBUS(CHIPS)':
 '1': CDS_PINID='\1\';
NODE_NAME     U4 C34
 '@S9S_MB_2U_LIB.S9S_MB_2U(SCH_1):PAGE173_I110@PURE_QUANTA.EMMITSBURG_REV0P9(CHIPS)':
 'DMI_4_SATA_19_PCIE3_19_RXP': CDS_PINID='DMI_4_SATA_19_PCIE3_19_RXP';
NET_NAME
'DMI_CPU0_PCH_TX_C_DP<5>'
 '@S9S_MB_2U_LIB.S9S_MB_2U(SCH_1):DMI_CPU0_PCH_TX_C_DP'<5>:
 C_SIGNAL='@s9s_mb_2u_lib.s9s_mb_2u(sch_1):dmi_cpu0_pch_tx_c_dp(5)';
NODE_NAME     C144 1
 '@S9S_MB_2U_LIB.S9S_MB_2U(SCH_1):PAGE169_I31@PURE_QUANTA.Q_CAP_DIFFBUS(CHIPS)':
 '1': CDS_PINID='\1\';
NODE_NAME     U4 D35
 '@S9S_MB_2U_LIB.S9S_MB_2U(SCH_1):PAGE173_I110@PURE_QUANTA.EMMITSBURG_REV0P9(CHIPS)':
 'DMI_5_SATA_18_PCIE3_18_RXP': CDS_PINID='DMI_5_SATA_18_PCIE3_18_RXP';
NET_NAME
'DMI_CPU0_PCH_TX_C_DP<6>'
 '@S9S_MB_2U_LIB.S9S_MB_2U(SCH_1):DMI_CPU0_PCH_TX_C_DP'<6>:
 C_SIGNAL='@s9s_mb_2u_lib.s9s_mb_2u(sch_1):dmi_cpu0_pch_tx_c_dp(6)';
NODE_NAME     C142 1
 '@S9S_MB_2U_LIB.S9S_MB_2U(SCH_1):PAGE169_I33@PURE_QUANTA.Q_CAP_DIFFBUS(CHIPS)':
 '1': CDS_PINID='\1\';
NODE_NAME     U4 C36
 '@S9S_MB_2U_LIB.S9S_MB_2U(SCH_1):PAGE173_I110@PURE_QUANTA.EMMITSBURG_REV0P9(CHIPS)':
 'DMI_6_SATA_17_PCIE3_17_RXP': CDS_PINID='DMI_6_SATA_17_PCIE3_17_RXP';
NET_NAME
'DMI_CPU0_PCH_TX_C_DP<7>'
 '@S9S_MB_2U_LIB.S9S_MB_2U(SCH_1):DMI_CPU0_PCH_TX_C_DP'<7>:
 C_SIGNAL='@s9s_mb_2u_lib.s9s_mb_2u(sch_1):dmi_cpu0_pch_tx_c_dp(7)';
NODE_NAME     C1791 1
 '@S9S_MB_2U_LIB.S9S_MB_2U(SCH_1):PAGE169_I36@PURE_QUANTA.Q_CAP_DIFFBUS(CHIPS)':
 '1': CDS_PINID='\1\';
NODE_NAME     U4 D37
 '@S9S_MB_2U_LIB.S9S_MB_2U(SCH_1):PAGE173_I110@PURE_QUANTA.EMMITSBURG_REV0P9(CHIPS)':
 'DMI_7_SATA_16_PCIE3_16_RXP': CDS_PINID='DMI_7_SATA_16_PCIE3_16_RXP';
NET_NAME
'DMI_CPU0_PCH_TX_DN<0>'
 '@S9S_MB_2U_LIB.S9S_MB_2U(SCH_1):DMI_CPU0_PCH_TX_DN'<0>:
 C_SIGNAL='@s9s_mb_2u_lib.s9s_mb_2u(sch_1):dmi_cpu0_pch_tx_dn(0)';
NODE_NAME     U2 CA19
 '@S9S_MB_2U_LIB.S9S_MB_2U(SCH_1):PAGE28_I169@PURE_QUANTA.SOCKET4677_AZIF0045P001C01CS(CHIPS)':
 'DMI_TX_DP0': CDS_PINID='DMI_TX_DP0';
NODE_NAME     C153 2
 '@S9S_MB_2U_LIB.S9S_MB_2U(SCH_1):PAGE169_I21@PURE_QUANTA.Q_CAP_DIFFBUS(CHIPS)':
 '2': CDS_PINID='\2\';
NET_NAME
'DMI_CPU0_PCH_TX_DN<1>'
 '@S9S_MB_2U_LIB.S9S_MB_2U(SCH_1):DMI_CPU0_PCH_TX_DN'<1>:
 C_SIGNAL='@s9s_mb_2u_lib.s9s_mb_2u(sch_1):dmi_cpu0_pch_tx_dn(1)';
NODE_NAME     U2 BY18
 '@S9S_MB_2U_LIB.S9S_MB_2U(SCH_1):PAGE28_I169@PURE_QUANTA.SOCKET4677_AZIF0045P001C01CS(CHIPS)':
 'DMI_TX_DP1': CDS_PINID='DMI_TX_DP1';
NODE_NAME     C151 2
 '@S9S_MB_2U_LIB.S9S_MB_2U(SCH_1):PAGE169_I24@PURE_QUANTA.Q_CAP_DIFFBUS(CHIPS)':
 '2': CDS_PINID='\2\';
NET_NAME
'DMI_CPU0_PCH_TX_DN<2>'
 '@S9S_MB_2U_LIB.S9S_MB_2U(SCH_1):DMI_CPU0_PCH_TX_DN'<2>:
 C_SIGNAL='@s9s_mb_2u_lib.s9s_mb_2u(sch_1):dmi_cpu0_pch_tx_dn(2)';
NODE_NAME     U2 CC19
 '@S9S_MB_2U_LIB.S9S_MB_2U(SCH_1):PAGE28_I169@PURE_QUANTA.SOCKET4677_AZIF0045P001C01CS(CHIPS)':
 'DMI_TX_DP2': CDS_PINID='DMI_TX_DP2';
NODE_NAME     C149 2
 '@S9S_MB_2U_LIB.S9S_MB_2U(SCH_1):PAGE169_I25@PURE_QUANTA.Q_CAP_DIFFBUS(CHIPS)':
 '2': CDS_PINID='\2\';
NET_NAME
'DMI_CPU0_PCH_TX_DN<3>'
 '@S9S_MB_2U_LIB.S9S_MB_2U(SCH_1):DMI_CPU0_PCH_TX_DN'<3>:
 C_SIGNAL='@s9s_mb_2u_lib.s9s_mb_2u(sch_1):dmi_cpu0_pch_tx_dn(3)';
NODE_NAME     U2 CD18
 '@S9S_MB_2U_LIB.S9S_MB_2U(SCH_1):PAGE28_I169@PURE_QUANTA.SOCKET4677_AZIF0045P001C01CS(CHIPS)':
 'DMI_TX_DP3': CDS_PINID='DMI_TX_DP3';
NODE_NAME     C147 2
 '@S9S_MB_2U_LIB.S9S_MB_2U(SCH_1):PAGE169_I28@PURE_QUANTA.Q_CAP_DIFFBUS(CHIPS)':
 '2': CDS_PINID='\2\';
NET_NAME
'DMI_CPU0_PCH_TX_DN<4>'
 '@S9S_MB_2U_LIB.S9S_MB_2U(SCH_1):DMI_CPU0_PCH_TX_DN'<4>:
 C_SIGNAL='@s9s_mb_2u_lib.s9s_mb_2u(sch_1):dmi_cpu0_pch_tx_dn(4)';
NODE_NAME     U2 CF18
 '@S9S_MB_2U_LIB.S9S_MB_2U(SCH_1):PAGE28_I169@PURE_QUANTA.SOCKET4677_AZIF0045P001C01CS(CHIPS)':
 'DMI_TX_DN4': CDS_PINID='DMI_TX_DN4';
NODE_NAME     C145 2
 '@S9S_MB_2U_LIB.S9S_MB_2U(SCH_1):PAGE169_I30@PURE_QUANTA.Q_CAP_DIFFBUS(CHIPS)':
 '2': CDS_PINID='\2\';
NET_NAME
'DMI_CPU0_PCH_TX_DN<5>'
 '@S9S_MB_2U_LIB.S9S_MB_2U(SCH_1):DMI_CPU0_PCH_TX_DN'<5>:
 C_SIGNAL='@s9s_mb_2u_lib.s9s_mb_2u(sch_1):dmi_cpu0_pch_tx_dn(5)';
NODE_NAME     U2 CJ17
 '@S9S_MB_2U_LIB.S9S_MB_2U(SCH_1):PAGE28_I169@PURE_QUANTA.SOCKET4677_AZIF0045P001C01CS(CHIPS)':
 'DMI_TX_DN5': CDS_PINID='DMI_TX_DN5';
NODE_NAME     C143 2
 '@S9S_MB_2U_LIB.S9S_MB_2U(SCH_1):PAGE169_I32@PURE_QUANTA.Q_CAP_DIFFBUS(CHIPS)':
 '2': CDS_PINID='\2\';
NET_NAME
'DMI_CPU0_PCH_TX_DN<6>'
 '@S9S_MB_2U_LIB.S9S_MB_2U(SCH_1):DMI_CPU0_PCH_TX_DN'<6>:
 C_SIGNAL='@s9s_mb_2u_lib.s9s_mb_2u(sch_1):dmi_cpu0_pch_tx_dn(6)';
NODE_NAME     U2 CK18
 '@S9S_MB_2U_LIB.S9S_MB_2U(SCH_1):PAGE28_I169@PURE_QUANTA.SOCKET4677_AZIF0045P001C01CS(CHIPS)':
 'DMI_TX_DN6': CDS_PINID='DMI_TX_DN6';
NODE_NAME     C141 2
 '@S9S_MB_2U_LIB.S9S_MB_2U(SCH_1):PAGE169_I34@PURE_QUANTA.Q_CAP_DIFFBUS(CHIPS)':
 '2': CDS_PINID='\2\';
NET_NAME
'DMI_CPU0_PCH_TX_DN<7>'
 '@S9S_MB_2U_LIB.S9S_MB_2U(SCH_1):DMI_CPU0_PCH_TX_DN'<7>:
 C_SIGNAL='@s9s_mb_2u_lib.s9s_mb_2u(sch_1):dmi_cpu0_pch_tx_dn(7)';
NODE_NAME     U2 CM18
 '@S9S_MB_2U_LIB.S9S_MB_2U(SCH_1):PAGE28_I169@PURE_QUANTA.SOCKET4677_AZIF0045P001C01CS(CHIPS)':
 'DMI_TX_DP7': CDS_PINID='DMI_TX_DP7';
NODE_NAME     C139 2
 '@S9S_MB_2U_LIB.S9S_MB_2U(SCH_1):PAGE169_I35@PURE_QUANTA.Q_CAP_DIFFBUS(CHIPS)':
 '2': CDS_PINID='\2\';
NET_NAME
'DMI_CPU0_PCH_TX_DP<0>'
 '@S9S_MB_2U_LIB.S9S_MB_2U(SCH_1):DMI_CPU0_PCH_TX_DP'<0>:
 C_SIGNAL='@s9s_mb_2u_lib.s9s_mb_2u(sch_1):dmi_cpu0_pch_tx_dp(0)';
NODE_NAME     U2 BW19
 '@S9S_MB_2U_LIB.S9S_MB_2U(SCH_1):PAGE28_I169@PURE_QUANTA.SOCKET4677_AZIF0045P001C01CS(CHIPS)':
 'DMI_TX_DN0': CDS_PINID='DMI_TX_DN0';
NODE_NAME     C154 2
 '@S9S_MB_2U_LIB.S9S_MB_2U(SCH_1):PAGE169_I22@PURE_QUANTA.Q_CAP_DIFFBUS(CHIPS)':
 '2': CDS_PINID='\2\';
NET_NAME
'DMI_CPU0_PCH_TX_DP<1>'
 '@S9S_MB_2U_LIB.S9S_MB_2U(SCH_1):DMI_CPU0_PCH_TX_DP'<1>:
 C_SIGNAL='@s9s_mb_2u_lib.s9s_mb_2u(sch_1):dmi_cpu0_pch_tx_dp(1)';
NODE_NAME     U2 CA17
 '@S9S_MB_2U_LIB.S9S_MB_2U(SCH_1):PAGE28_I169@PURE_QUANTA.SOCKET4677_AZIF0045P001C01CS(CHIPS)':
 'DMI_TX_DN1': CDS_PINID='DMI_TX_DN1';
NODE_NAME     C152 2
 '@S9S_MB_2U_LIB.S9S_MB_2U(SCH_1):PAGE169_I23@PURE_QUANTA.Q_CAP_DIFFBUS(CHIPS)':
 '2': CDS_PINID='\2\';
NET_NAME
'DMI_CPU0_PCH_TX_DP<2>'
 '@S9S_MB_2U_LIB.S9S_MB_2U(SCH_1):DMI_CPU0_PCH_TX_DP'<2>:
 C_SIGNAL='@s9s_mb_2u_lib.s9s_mb_2u(sch_1):dmi_cpu0_pch_tx_dp(2)';
NODE_NAME     U2 CB18
 '@S9S_MB_2U_LIB.S9S_MB_2U(SCH_1):PAGE28_I169@PURE_QUANTA.SOCKET4677_AZIF0045P001C01CS(CHIPS)':
 'DMI_TX_DN2': CDS_PINID='DMI_TX_DN2';
NODE_NAME     C150 2
 '@S9S_MB_2U_LIB.S9S_MB_2U(SCH_1):PAGE169_I26@PURE_QUANTA.Q_CAP_DIFFBUS(CHIPS)':
 '2': CDS_PINID='\2\';
NET_NAME
'DMI_CPU0_PCH_TX_DP<3>'
 '@S9S_MB_2U_LIB.S9S_MB_2U(SCH_1):DMI_CPU0_PCH_TX_DP'<3>:
 C_SIGNAL='@s9s_mb_2u_lib.s9s_mb_2u(sch_1):dmi_cpu0_pch_tx_dp(3)';
NODE_NAME     U2 CE17
 '@S9S_MB_2U_LIB.S9S_MB_2U(SCH_1):PAGE28_I169@PURE_QUANTA.SOCKET4677_AZIF0045P001C01CS(CHIPS)':
 'DMI_TX_DN3': CDS_PINID='DMI_TX_DN3';
NODE_NAME     C148 2
 '@S9S_MB_2U_LIB.S9S_MB_2U(SCH_1):PAGE169_I27@PURE_QUANTA.Q_CAP_DIFFBUS(CHIPS)':
 '2': CDS_PINID='\2\';
NET_NAME
'DMI_CPU0_PCH_TX_DP<4>'
 '@S9S_MB_2U_LIB.S9S_MB_2U(SCH_1):DMI_CPU0_PCH_TX_DP'<4>:
 C_SIGNAL='@s9s_mb_2u_lib.s9s_mb_2u(sch_1):dmi_cpu0_pch_tx_dp(4)';
NODE_NAME     U2 CG19
 '@S9S_MB_2U_LIB.S9S_MB_2U(SCH_1):PAGE28_I169@PURE_QUANTA.SOCKET4677_AZIF0045P001C01CS(CHIPS)':
 'DMI_TX_DP4': CDS_PINID='DMI_TX_DP4';
NODE_NAME     C146 2
 '@S9S_MB_2U_LIB.S9S_MB_2U(SCH_1):PAGE169_I29@PURE_QUANTA.Q_CAP_DIFFBUS(CHIPS)':
 '2': CDS_PINID='\2\';
NET_NAME
'DMI_CPU0_PCH_TX_DP<5>'
 '@S9S_MB_2U_LIB.S9S_MB_2U(SCH_1):DMI_CPU0_PCH_TX_DP'<5>:
 C_SIGNAL='@s9s_mb_2u_lib.s9s_mb_2u(sch_1):dmi_cpu0_pch_tx_dp(5)';
NODE_NAME     U2 CH18
 '@S9S_MB_2U_LIB.S9S_MB_2U(SCH_1):PAGE28_I169@PURE_QUANTA.SOCKET4677_AZIF0045P001C01CS(CHIPS)':
 'DMI_TX_DP5': CDS_PINID='DMI_TX_DP5';
NODE_NAME     C144 2
 '@S9S_MB_2U_LIB.S9S_MB_2U(SCH_1):PAGE169_I31@PURE_QUANTA.Q_CAP_DIFFBUS(CHIPS)':
 '2': CDS_PINID='\2\';
NET_NAME
'DMI_CPU0_PCH_TX_DP<6>'
 '@S9S_MB_2U_LIB.S9S_MB_2U(SCH_1):DMI_CPU0_PCH_TX_DP'<6>:
 C_SIGNAL='@s9s_mb_2u_lib.s9s_mb_2u(sch_1):dmi_cpu0_pch_tx_dp(6)';
NODE_NAME     U2 CL19
 '@S9S_MB_2U_LIB.S9S_MB_2U(SCH_1):PAGE28_I169@PURE_QUANTA.SOCKET4677_AZIF0045P001C01CS(CHIPS)':
 'DMI_TX_DP6': CDS_PINID='DMI_TX_DP6';
NODE_NAME     C142 2
 '@S9S_MB_2U_LIB.S9S_MB_2U(SCH_1):PAGE169_I33@PURE_QUANTA.Q_CAP_DIFFBUS(CHIPS)':
 '2': CDS_PINID='\2\';
NET_NAME
'DMI_CPU0_PCH_TX_DP<7>'
 '@S9S_MB_2U_LIB.S9S_MB_2U(SCH_1):DMI_CPU0_PCH_TX_DP'<7>:
 C_SIGNAL='@s9s_mb_2u_lib.s9s_mb_2u(sch_1):dmi_cpu0_pch_tx_dp(7)';
NODE_NAME     U2 CN17
 '@S9S_MB_2U_LIB.S9S_MB_2U(SCH_1):PAGE28_I169@PURE_QUANTA.SOCKET4677_AZIF0045P001C01CS(CHIPS)':
 'DMI_TX_DN7': CDS_PINID='DMI_TX_DN7';
NODE_NAME     C1791 2
 '@S9S_MB_2U_LIB.S9S_MB_2U(SCH_1):PAGE169_I36@PURE_QUANTA.Q_CAP_DIFFBUS(CHIPS)':
 '2': CDS_PINID='\2\';
NET_NAME
'DSW_PWROK_P2V5_COMP'
 '@S9S_MB_2U_LIB.S9S_MB_2U(SCH_1):DSW_PWROK_P2V5_COMP':
 C_SIGNAL='@s9s_mb_2u_lib.s9s_mb_2u(sch_1):dsw_pwrok_p2v5_comp';
NODE_NAME     U342 1
 '@S9S_MB_2U_LIB.S9S_MB_2U(SCH_1):PAGE329_I45@PURE_QUANTA.AP331AWG7(CHIPS)':
 'IN-': CDS_PINID='\in-\';
NODE_NAME     C2385 1
 '@S9S_MB_2U_LIB.S9S_MB_2U(SCH_1):PAGE329_I57@PURE_QUANTA.Q_CAP(CHIPS)':
 'A': CDS_PINID='A';
NODE_NAME     U341 1
 '@S9S_MB_2U_LIB.S9S_MB_2U(SCH_1):PAGE329_I63@PURE_QUANTA.LM4040AIM3X25NOPB(CHIPS)':
 '1+': CDS_PINID='\1+\';
NODE_NAME     R4786 2
 '@S9S_MB_2U_LIB.S9S_MB_2U(SCH_1):PAGE329_I65@PURE_QUANTA.Q_RES(CHIPS)':
 'B': CDS_PINID='B';
NET_NAME
'E1S_0_CLKREQ_N'
 '@S9S_MB_2U_LIB.S9S_MB_2U(SCH_1):E1S_0_CLKREQ_N':
 C_SIGNAL='@s9s_mb_2u_lib.s9s_mb_2u(sch_1):e1s_0_clkreq_n';
NODE_NAME     U4 BG18
 '@S9S_MB_2U_LIB.S9S_MB_2U(SCH_1):PAGE175_I93@PURE_QUANTA.EMMITSBURG_REV0P9(CHIPS)':
 'GPPC_A_11_SRCCLKREQ_N_1': CDS_PINID='GPPC_A_11_SRCCLKREQ_N_1';
NODE_NAME     R4084 2
 '@S9S_MB_2U_LIB.S9S_MB_2U(SCH_1):PAGE175_I275@PURE_QUANTA.Q_RES(CHIPS)':
 'B': CDS_PINID='B';
NODE_NAME     R4083 2
 '@S9S_MB_2U_LIB.S9S_MB_2U(SCH_1):PAGE175_I274@PURE_QUANTA.Q_RES(CHIPS)':
 'B': CDS_PINID='B';
NODE_NAME     R4766 2
 '@S9S_MB_2U_LIB.S9S_MB_2U(SCH_1):PAGE175_I314@PURE_QUANTA.Q_RES(CHIPS)':
 'B': CDS_PINID='B';
NET_NAME
'E1S_0_CLK_OE_N'
 '@S9S_MB_2U_LIB.S9S_MB_2U(SCH_1):E1S_0_CLK_OE_N':
 C_SIGNAL='@s9s_mb_2u_lib.s9s_mb_2u(sch_1):e1s_0_clk_oe_n';
NODE_NAME     U249 L6
 '@S9S_MB_2U_LIB.S9S_MB_2U(SCH_1):PAGE311_I33@PURE_QUANTA.LCMXO3LF9400C5BG484C(CHIPS)':
 'PL14C': CDS_PINID='PL14C';
NODE_NAME     R4766 1
 '@S9S_MB_2U_LIB.S9S_MB_2U(SCH_1):PAGE175_I314@PURE_QUANTA.Q_RES(CHIPS)':
 'A': CDS_PINID='A';
NODE_NAME     R4768 1
 '@S9S_MB_2U_LIB.S9S_MB_2U(SCH_1):PAGE175_I315@PURE_QUANTA.Q_RES(CHIPS)':
 'A': CDS_PINID='A';
NET_NAME
'E1S_0_EN'
 '@S9S_MB_2U_LIB.S9S_MB_2U(SCH_1):E1S_0_EN':
 C_SIGNAL='@s9s_mb_2u_lib.s9s_mb_2u(sch_1):e1s_0_en';
NODE_NAME     U145 4
 '@S9S_MB_2U_LIB.S9S_MB_2U(SCH_1):PAGE297_I163@PURE_QUANTA.74LVC1G126SE7(CHIPS)':
 'Y': CDS_PINID='Y';
NODE_NAME     R2457 1
 '@S9S_MB_2U_LIB.S9S_MB_2U(SCH_1):PAGE297_I165@PURE_QUANTA.Q_RES(CHIPS)':
 'A': CDS_PINID='A';
NODE_NAME     R4064 1
 '@S9S_MB_2U_LIB.S9S_MB_2U(SCH_1):PAGE324_I21@PURE_QUANTA.Q_RES(CHIPS)':
 'A': CDS_PINID='A';
NODE_NAME     R3943 1
 '@S9S_MB_2U_LIB.S9S_MB_2U(SCH_1):PAGE323_I45@PURE_QUANTA.Q_RES(CHIPS)':
 'A': CDS_PINID='A';
NODE_NAME     R4063 1
 '@S9S_MB_2U_LIB.S9S_MB_2U(SCH_1):PAGE324_I1@PURE_QUANTA.Q_RES(CHIPS)':
 'A': CDS_PINID='A';
NODE_NAME     R3946 1
 '@S9S_MB_2U_LIB.S9S_MB_2U(SCH_1):PAGE323_I5@PURE_QUANTA.Q_RES(CHIPS)':
 'A': CDS_PINID='A';
NET_NAME
'E1S_0_LED_ACT_N'
 '@S9S_MB_2U_LIB.S9S_MB_2U(SCH_1):E1S_0_LED_ACT_N':
 C_SIGNAL='@s9s_mb_2u_lib.s9s_mb_2u(sch_1):e1s_0_led_act_n';
NODE_NAME     J90 A10
 '@S9S_MB_2U_LIB.S9S_MB_2U(SCH_1):PAGE297_I318@PURE_QUANTA.SCONN56_123276793(CHIPS)':
 'LED#_ACTIVITY': CDS_PINID='\led#_activity\';
NODE_NAME     R4606 2
 '@S9S_MB_2U_LIB.S9S_MB_2U(SCH_1):PAGE313_I180@PURE_QUANTA.Q_RES(CHIPS)':
 'B': CDS_PINID='B';
NET_NAME
'E1S_0_LED_ACT_R_N'
 '@S9S_MB_2U_LIB.S9S_MB_2U(SCH_1):E1S_0_LED_ACT_R_N':
 C_SIGNAL='@s9s_mb_2u_lib.s9s_mb_2u(sch_1):e1s_0_led_act_r_n';
NODE_NAME     U249 U18
 '@S9S_MB_2U_LIB.S9S_MB_2U(SCH_1):PAGE313_I1@PURE_QUANTA.LCMXO3LF9400C5BG484C(CHIPS)':
 'PR28D': CDS_PINID='PR28D';
NODE_NAME     R4606 1
 '@S9S_MB_2U_LIB.S9S_MB_2U(SCH_1):PAGE313_I180@PURE_QUANTA.Q_RES(CHIPS)':
 'A': CDS_PINID='A';
NET_NAME
'E1S_0_P3V3_ADC_ALERT'
 '@S9S_MB_2U_LIB.S9S_MB_2U(SCH_1):E1S_0_P3V3_ADC_ALERT':
 C_SIGNAL='@s9s_mb_2u_lib.s9s_mb_2u(sch_1):e1s_0_p3v3_adc_alert';
NODE_NAME     U249 J20
 '@S9S_MB_2U_LIB.S9S_MB_2U(SCH_1):PAGE313_I1@PURE_QUANTA.LCMXO3LF9400C5BG484C(CHIPS)':
 'PR12C': CDS_PINID='PR12C';
NODE_NAME     R3752 2
 '@S9S_MB_2U_LIB.S9S_MB_2U(SCH_1):PAGE295_I122@PURE_QUANTA.Q_RES(CHIPS)':
 'B': CDS_PINID='B';
NET_NAME
'E1S_0_P3V3_ADC_ALERT_R'
 '@S9S_MB_2U_LIB.S9S_MB_2U(SCH_1):E1S_0_P3V3_ADC_ALERT_R':
 C_SIGNAL='@s9s_mb_2u_lib.s9s_mb_2u(sch_1):e1s_0_p3v3_adc_alert_r';
NODE_NAME     R3752 1
 '@S9S_MB_2U_LIB.S9S_MB_2U(SCH_1):PAGE295_I122@PURE_QUANTA.Q_RES(CHIPS)':
 'A': CDS_PINID='A';
NODE_NAME     U276 3
 '@S9S_MB_2U_LIB.S9S_MB_2U(SCH_1):PAGE295_I129@PURE_QUANTA.INA230AIRGTR(CHIPS)':
 'ALERT': CDS_PINID='ALERT';
NODE_NAME     R4093 2
 '@S9S_MB_2U_LIB.S9S_MB_2U(SCH_1):PAGE295_I149@PURE_QUANTA.Q_RES(CHIPS)':
 'B': CDS_PINID='B';
NET_NAME
'E1S_0_PERST1_CLKREQ_N'
 '@S9S_MB_2U_LIB.S9S_MB_2U(SCH_1):E1S_0_PERST1_CLKREQ_N':
 C_SIGNAL='@s9s_mb_2u_lib.s9s_mb_2u(sch_1):e1s_0_perst1_clkreq_n';
NODE_NAME     R2426 1
 '@S9S_MB_2U_LIB.S9S_MB_2U(SCH_1):PAGE297_I311@PURE_QUANTA.Q_RES(CHIPS)':
 'A': CDS_PINID='A';
NODE_NAME     R2287 2
 '@S9S_MB_2U_LIB.S9S_MB_2U(SCH_1):PAGE297_I313@PURE_QUANTA.Q_RES(CHIPS)':
 'B': CDS_PINID='B';
NODE_NAME     R4083 1
 '@S9S_MB_2U_LIB.S9S_MB_2U(SCH_1):PAGE175_I274@PURE_QUANTA.Q_RES(CHIPS)':
 'A': CDS_PINID='A';
NODE_NAME     J90 A11
 '@S9S_MB_2U_LIB.S9S_MB_2U(SCH_1):PAGE297_I318@PURE_QUANTA.SCONN56_123276793(CHIPS)':
 'PERST1#_CLKREQ#': CDS_PINID='\perst1#_clkreq#\';
NET_NAME
'E1S_0_PRSNT'
 '@S9S_MB_2U_LIB.S9S_MB_2U(SCH_1):E1S_0_PRSNT':
 C_SIGNAL='@s9s_mb_2u_lib.s9s_mb_2u(sch_1):e1s_0_prsnt';
NODE_NAME     U145 2
 '@S9S_MB_2U_LIB.S9S_MB_2U(SCH_1):PAGE297_I163@PURE_QUANTA.74LVC1G126SE7(CHIPS)':
 'A': CDS_PINID='A';
NODE_NAME     R2282 2
 '@S9S_MB_2U_LIB.S9S_MB_2U(SCH_1):PAGE297_I169@PURE_QUANTA.Q_RES(CHIPS)':
 'B': CDS_PINID='B';
NODE_NAME     Q46 D
 '@S9S_MB_2U_LIB.S9S_MB_2U(SCH_1):PAGE297_I316@PURE_QUANTA.MOSFET_NCH_GDS_ESD_PROTECTED(CHIPS)':
 'D': CDS_PINID='D';
NET_NAME
'E1S_0_PRSNT_N'
 '@S9S_MB_2U_LIB.S9S_MB_2U(SCH_1):E1S_0_PRSNT_N':
 C_SIGNAL='@s9s_mb_2u_lib.s9s_mb_2u(sch_1):e1s_0_prsnt_n';
NODE_NAME     U249 V10
 '@S9S_MB_2U_LIB.S9S_MB_2U(SCH_1):PAGE312_I1@PURE_QUANTA.LCMXO3LF9400C5BG484C(CHIPS)':
 'PB21A': CDS_PINID='PB21A';
NODE_NAME     R2304 2
 '@S9S_MB_2U_LIB.S9S_MB_2U(SCH_1):PAGE297_I159@PURE_QUANTA.Q_RES(CHIPS)':
 'B': CDS_PINID='B';
NODE_NAME     Q46 G
 '@S9S_MB_2U_LIB.S9S_MB_2U(SCH_1):PAGE297_I316@PURE_QUANTA.MOSFET_NCH_GDS_ESD_PROTECTED(CHIPS)':
 'G': CDS_PINID='G';
NODE_NAME     R4084 1
 '@S9S_MB_2U_LIB.S9S_MB_2U(SCH_1):PAGE175_I275@PURE_QUANTA.Q_RES(CHIPS)':
 'A': CDS_PINID='A';
NODE_NAME     J90 A12
 '@S9S_MB_2U_LIB.S9S_MB_2U(SCH_1):PAGE297_I318@PURE_QUANTA.SCONN56_123276793(CHIPS)':
 'PRSNT0#': CDS_PINID='\prsnt0#\';
NET_NAME
'E1S_0_PWRDIS'
 '@S9S_MB_2U_LIB.S9S_MB_2U(SCH_1):E1S_0_PWRDIS':
 C_SIGNAL='@s9s_mb_2u_lib.s9s_mb_2u(sch_1):e1s_0_pwrdis';
NODE_NAME     R3771 2
 '@S9S_MB_2U_LIB.S9S_MB_2U(SCH_1):PAGE297_I291@PURE_QUANTA.Q_RES(CHIPS)':
 'B': CDS_PINID='B';
NODE_NAME     R2296 1
 '@S9S_MB_2U_LIB.S9S_MB_2U(SCH_1):PAGE297_I293@PURE_QUANTA.Q_RES(CHIPS)':
 'A': CDS_PINID='A';
NODE_NAME     J90 B12
 '@S9S_MB_2U_LIB.S9S_MB_2U(SCH_1):PAGE297_I318@PURE_QUANTA.SCONN56_123276793(CHIPS)':
 'PWRDIS': CDS_PINID='PWRDIS';
NET_NAME
'ESPI_ALERT1_N_LPC_RCIN_N'
 '@S9S_MB_2U_LIB.S9S_MB_2U(SCH_1):ESPI_ALERT1_N_LPC_RCIN_N':
 C_SIGNAL='@s9s_mb_2u_lib.s9s_mb_2u(sch_1):espi_alert1_n_lpc_rcin_n';
NODE_NAME     U4 BD15
 '@S9S_MB_2U_LIB.S9S_MB_2U(SCH_1):PAGE175_I93@PURE_QUANTA.EMMITSBURG_REV0P9(CHIPS)':
 'GPPC_A_1_ESPI_ALERT1_N': CDS_PINID='GPPC_A_1_ESPI_ALERT1_N';
NODE_NAME     R1255 2
 '@S9S_MB_2U_LIB.S9S_MB_2U(SCH_1):PAGE192_I26@PURE_QUANTA.Q_RES(CHIPS)':
 'B': CDS_PINID='B';
NET_NAME
'ESPI_BMC_LPC_RST_N'
 '@S9S_MB_2U_LIB.S9S_MB_2U(SCH_1):ESPI_BMC_LPC_RST_N':
 C_SIGNAL='@s9s_mb_2u_lib.s9s_mb_2u(sch_1):espi_bmc_lpc_rst_n';
NODE_NAME     U61 4
 '@S9S_MB_2U_LIB.S9S_MB_2U(SCH_1):PAGE190_I39@PURE_QUANTA.NC7SB3157(CHIPS)':
 'A': CDS_PINID='A';
NODE_NAME     J41 B4
 '@S9S_MB_2U_LIB.S9S_MB_2U(SCH_1):PAGE227_I173@PURE_QUANTA.SCONN168_ME1016810202011(CHIPS)':
 '+12V_EDGE_B4': CDS_PINID='\+12v_edge_b4\';
NET_NAME
'ESPI_HOST_LPC_BMC_CLK'
 '@S9S_MB_2U_LIB.S9S_MB_2U(SCH_1):ESPI_HOST_LPC_BMC_CLK':
 C_SIGNAL='@s9s_mb_2u_lib.s9s_mb_2u(sch_1):espi_host_lpc_bmc_clk';
NODE_NAME     R1872 2
 '@S9S_MB_2U_LIB.S9S_MB_2U(SCH_1):PAGE190_I100@PURE_QUANTA.Q_RES(CHIPS)':
 'B': CDS_PINID='B';
NODE_NAME     J41 B1
 '@S9S_MB_2U_LIB.S9S_MB_2U(SCH_1):PAGE227_I173@PURE_QUANTA.SCONN168_ME1016810202011(CHIPS)':
 '+12V_EDGE_B1': CDS_PINID='\+12v_edge_b1\';
NET_NAME
'ESPI_HOST_LPC_BMC_LFRAME_N'
 '@S9S_MB_2U_LIB.S9S_MB_2U(SCH_1):ESPI_HOST_LPC_BMC_LFRAME_N':
 C_SIGNAL='@s9s_mb_2u_lib.s9s_mb_2u(sch_1):espi_host_lpc_bmc_lframe_n';
NODE_NAME     R1479 2
 '@S9S_MB_2U_LIB.S9S_MB_2U(SCH_1):PAGE190_I102@PURE_QUANTA.Q_RES(CHIPS)':
 'B': CDS_PINID='B';
NODE_NAME     J41 B2
 '@S9S_MB_2U_LIB.S9S_MB_2U(SCH_1):PAGE227_I173@PURE_QUANTA.SCONN168_ME1016810202011(CHIPS)':
 '+12V_EDGE_B2': CDS_PINID='\+12v_edge_b2\';
NET_NAME
'ESPI_LAD0_DATA_IO0'
 '@S9S_MB_2U_LIB.S9S_MB_2U(SCH_1):ESPI_LAD0_DATA_IO0':
 C_SIGNAL='@s9s_mb_2u_lib.s9s_mb_2u(sch_1):espi_lad0_data_io0';
NODE_NAME     U4 BG12
 '@S9S_MB_2U_LIB.S9S_MB_2U(SCH_1):PAGE175_I93@PURE_QUANTA.EMMITSBURG_REV0P9(CHIPS)':
 'GPPC_A_2_ESPI_IO_0': CDS_PINID='GPPC_A_2_ESPI_IO_0';
NODE_NAME     R1871 1
 '@S9S_MB_2U_LIB.S9S_MB_2U(SCH_1):PAGE190_I99@PURE_QUANTA.Q_RES(CHIPS)':
 'A': CDS_PINID='A';
NET_NAME
'ESPI_LAD0_DATA_IO1'
 '@S9S_MB_2U_LIB.S9S_MB_2U(SCH_1):ESPI_LAD0_DATA_IO1':
 C_SIGNAL='@s9s_mb_2u_lib.s9s_mb_2u(sch_1):espi_lad0_data_io1';
NODE_NAME     U4 BF19
 '@S9S_MB_2U_LIB.S9S_MB_2U(SCH_1):PAGE175_I93@PURE_QUANTA.EMMITSBURG_REV0P9(CHIPS)':
 'GPPC_A_3_ESPI_IO_1': CDS_PINID='GPPC_A_3_ESPI_IO_1';
NODE_NAME     R1870 1
 '@S9S_MB_2U_LIB.S9S_MB_2U(SCH_1):PAGE190_I98@PURE_QUANTA.Q_RES(CHIPS)':
 'A': CDS_PINID='A';
NET_NAME
'ESPI_LAD0_DATA_IO2'
 '@S9S_MB_2U_LIB.S9S_MB_2U(SCH_1):ESPI_LAD0_DATA_IO2':
 C_SIGNAL='@s9s_mb_2u_lib.s9s_mb_2u(sch_1):espi_lad0_data_io2';
NODE_NAME     U4 BE18
 '@S9S_MB_2U_LIB.S9S_MB_2U(SCH_1):PAGE175_I93@PURE_QUANTA.EMMITSBURG_REV0P9(CHIPS)':
 'GPPC_A_4_ESPI_IO_2': CDS_PINID='GPPC_A_4_ESPI_IO_2';
NODE_NAME     R1869 1
 '@S9S_MB_2U_LIB.S9S_MB_2U(SCH_1):PAGE190_I97@PURE_QUANTA.Q_RES(CHIPS)':
 'A': CDS_PINID='A';
NET_NAME
'ESPI_LAD0_DATA_IO3'
 '@S9S_MB_2U_LIB.S9S_MB_2U(SCH_1):ESPI_LAD0_DATA_IO3':
 C_SIGNAL='@s9s_mb_2u_lib.s9s_mb_2u(sch_1):espi_lad0_data_io3';
NODE_NAME     U4 BD19
 '@S9S_MB_2U_LIB.S9S_MB_2U(SCH_1):PAGE175_I93@PURE_QUANTA.EMMITSBURG_REV0P9(CHIPS)':
 'GPPC_A_5_ESPI_IO_3': CDS_PINID='GPPC_A_5_ESPI_IO_3';
NODE_NAME     R1868 1
 '@S9S_MB_2U_LIB.S9S_MB_2U(SCH_1):PAGE190_I96@PURE_QUANTA.Q_RES(CHIPS)':
 'A': CDS_PINID='A';
NET_NAME
'ESPI_LFRAME_N_BMC_CS0_N'
 '@S9S_MB_2U_LIB.S9S_MB_2U(SCH_1):ESPI_LFRAME_N_BMC_CS0_N':
 C_SIGNAL='@s9s_mb_2u_lib.s9s_mb_2u(sch_1):espi_lframe_n_bmc_cs0_n';
NODE_NAME     U4 BE20
 '@S9S_MB_2U_LIB.S9S_MB_2U(SCH_1):PAGE175_I93@PURE_QUANTA.EMMITSBURG_REV0P9(CHIPS)':
 'GPPC_A_6_ESPI_CS0_N': CDS_PINID='GPPC_A_6_ESPI_CS0_N';
NODE_NAME     R1961 2
 '@S9S_MB_2U_LIB.S9S_MB_2U(SCH_1):PAGE190_I70@PURE_QUANTA.Q_RES(CHIPS)':
 'B': CDS_PINID='B';
NODE_NAME     R1479 1
 '@S9S_MB_2U_LIB.S9S_MB_2U(SCH_1):PAGE190_I102@PURE_QUANTA.Q_RES(CHIPS)':
 'A': CDS_PINID='A';
NET_NAME
'ESPI_LPC_LAD0_IO0'
 '@S9S_MB_2U_LIB.S9S_MB_2U(SCH_1):ESPI_LPC_LAD0_IO0':
 C_SIGNAL='@s9s_mb_2u_lib.s9s_mb_2u(sch_1):espi_lpc_lad0_io0';
NODE_NAME     R1871 2
 '@S9S_MB_2U_LIB.S9S_MB_2U(SCH_1):PAGE190_I99@PURE_QUANTA.Q_RES(CHIPS)':
 'B': CDS_PINID='B';
NODE_NAME     J41 B5
 '@S9S_MB_2U_LIB.S9S_MB_2U(SCH_1):PAGE227_I173@PURE_QUANTA.SCONN168_ME1016810202011(CHIPS)':
 '+12V_EDGE_B5': CDS_PINID='\+12v_edge_b5\';
NET_NAME
'ESPI_LPC_LAD0_IO1'
 '@S9S_MB_2U_LIB.S9S_MB_2U(SCH_1):ESPI_LPC_LAD0_IO1':
 C_SIGNAL='@s9s_mb_2u_lib.s9s_mb_2u(sch_1):espi_lpc_lad0_io1';
NODE_NAME     R1870 2
 '@S9S_MB_2U_LIB.S9S_MB_2U(SCH_1):PAGE190_I98@PURE_QUANTA.Q_RES(CHIPS)':
 'B': CDS_PINID='B';
NODE_NAME     J41 B6
 '@S9S_MB_2U_LIB.S9S_MB_2U(SCH_1):PAGE227_I173@PURE_QUANTA.SCONN168_ME1016810202011(CHIPS)':
 '+12V_EDGE_B6': CDS_PINID='\+12v_edge_b6\';
NET_NAME
'ESPI_LPC_LAD0_IO2'
 '@S9S_MB_2U_LIB.S9S_MB_2U(SCH_1):ESPI_LPC_LAD0_IO2':
 C_SIGNAL='@s9s_mb_2u_lib.s9s_mb_2u(sch_1):espi_lpc_lad0_io2';
NODE_NAME     R1869 2
 '@S9S_MB_2U_LIB.S9S_MB_2U(SCH_1):PAGE190_I97@PURE_QUANTA.Q_RES(CHIPS)':
 'B': CDS_PINID='B';
NODE_NAME     J41 B7
 '@S9S_MB_2U_LIB.S9S_MB_2U(SCH_1):PAGE227_I173@PURE_QUANTA.SCONN168_ME1016810202011(CHIPS)':
 'BIF0#': CDS_PINID='\bif0#\';
NET_NAME
'ESPI_LPC_LAD0_IO3'
 '@S9S_MB_2U_LIB.S9S_MB_2U(SCH_1):ESPI_LPC_LAD0_IO3':
 C_SIGNAL='@s9s_mb_2u_lib.s9s_mb_2u(sch_1):espi_lpc_lad0_io3';
NODE_NAME     R1868 2
 '@S9S_MB_2U_LIB.S9S_MB_2U(SCH_1):PAGE190_I96@PURE_QUANTA.Q_RES(CHIPS)':
 'B': CDS_PINID='B';
NODE_NAME     J41 B8
 '@S9S_MB_2U_LIB.S9S_MB_2U(SCH_1):PAGE227_I173@PURE_QUANTA.SCONN168_ME1016810202011(CHIPS)':
 'BIF1#': CDS_PINID='\bif1#\';
NET_NAME
'FAB_BMC_REV_ID0'
 '@S9S_MB_2U_LIB.S9S_MB_2U(SCH_1):FAB_BMC_REV_ID0':
 C_SIGNAL='@s9s_mb_2u_lib.s9s_mb_2u(sch_1):fab_bmc_rev_id0';
NODE_NAME     U249 K6
 '@S9S_MB_2U_LIB.S9S_MB_2U(SCH_1):PAGE311_I33@PURE_QUANTA.LCMXO3LF9400C5BG484C(CHIPS)':
 'PL12D': CDS_PINID='PL12D';
NODE_NAME     R4596 1
 '@S9S_MB_2U_LIB.S9S_MB_2U(SCH_1):PAGE184_I61@PURE_QUANTA.Q_RES(CHIPS)':
 'A': CDS_PINID='A';
NODE_NAME     R4579 2
 '@S9S_MB_2U_LIB.S9S_MB_2U(SCH_1):PAGE184_I67@PURE_QUANTA.Q_RES(CHIPS)':
 'B': CDS_PINID='B';
NET_NAME
'FAB_BMC_REV_ID1'
 '@S9S_MB_2U_LIB.S9S_MB_2U(SCH_1):FAB_BMC_REV_ID1':
 C_SIGNAL='@s9s_mb_2u_lib.s9s_mb_2u(sch_1):fab_bmc_rev_id1';
NODE_NAME     U249 K7
 '@S9S_MB_2U_LIB.S9S_MB_2U(SCH_1):PAGE311_I33@PURE_QUANTA.LCMXO3LF9400C5BG484C(CHIPS)':
 'PL12C': CDS_PINID='PL12C';
NODE_NAME     R4590 1
 '@S9S_MB_2U_LIB.S9S_MB_2U(SCH_1):PAGE184_I59@PURE_QUANTA.Q_RES(CHIPS)':
 'A': CDS_PINID='A';
NODE_NAME     R4589 2
 '@S9S_MB_2U_LIB.S9S_MB_2U(SCH_1):PAGE184_I63@PURE_QUANTA.Q_RES(CHIPS)':
 'B': CDS_PINID='B';
NET_NAME
'FAB_BMC_REV_ID2'
 '@S9S_MB_2U_LIB.S9S_MB_2U(SCH_1):FAB_BMC_REV_ID2':
 C_SIGNAL='@s9s_mb_2u_lib.s9s_mb_2u(sch_1):fab_bmc_rev_id2';
NODE_NAME     U249 J1
 '@S9S_MB_2U_LIB.S9S_MB_2U(SCH_1):PAGE311_I33@PURE_QUANTA.LCMXO3LF9400C5BG484C(CHIPS)':
 'PL12B': CDS_PINID='PL12B';
NODE_NAME     R4588 1
 '@S9S_MB_2U_LIB.S9S_MB_2U(SCH_1):PAGE184_I58@PURE_QUANTA.Q_RES(CHIPS)':
 'A': CDS_PINID='A';
NODE_NAME     R4586 2
 '@S9S_MB_2U_LIB.S9S_MB_2U(SCH_1):PAGE184_I62@PURE_QUANTA.Q_RES(CHIPS)':
 'B': CDS_PINID='B';
NET_NAME
'FAB_REV_ID0'
 '@S9S_MB_2U_LIB.S9S_MB_2U(SCH_1):FAB_REV_ID0':
 C_SIGNAL='@s9s_mb_2u_lib.s9s_mb_2u(sch_1):fab_rev_id0';
NODE_NAME     U4 N7
 '@S9S_MB_2U_LIB.S9S_MB_2U(SCH_1):PAGE176_I22@PURE_QUANTA.EMMITSBURG_REV0P9(CHIPS)':
 'GPP_M_0': CDS_PINID='GPP_M_0';
NODE_NAME     R2978 1
 '@S9S_MB_2U_LIB.S9S_MB_2U(SCH_1):PAGE184_I74@PURE_QUANTA.Q_RES(CHIPS)':
 'A': CDS_PINID='A';
NODE_NAME     R2232 2
 '@S9S_MB_2U_LIB.S9S_MB_2U(SCH_1):PAGE184_I75@PURE_QUANTA.Q_RES(CHIPS)':
 'B': CDS_PINID='B';
NET_NAME
'FAB_REV_ID1'
 '@S9S_MB_2U_LIB.S9S_MB_2U(SCH_1):FAB_REV_ID1':
 C_SIGNAL='@s9s_mb_2u_lib.s9s_mb_2u(sch_1):fab_rev_id1';
NODE_NAME     U4 AA13
 '@S9S_MB_2U_LIB.S9S_MB_2U(SCH_1):PAGE176_I22@PURE_QUANTA.EMMITSBURG_REV0P9(CHIPS)':
 'GPP_M_1': CDS_PINID='GPP_M_1';
NODE_NAME     R2975 1
 '@S9S_MB_2U_LIB.S9S_MB_2U(SCH_1):PAGE184_I70@PURE_QUANTA.Q_RES(CHIPS)':
 'A': CDS_PINID='A';
NODE_NAME     R2974 2
 '@S9S_MB_2U_LIB.S9S_MB_2U(SCH_1):PAGE184_I72@PURE_QUANTA.Q_RES(CHIPS)':
 'B': CDS_PINID='B';
NET_NAME
'FAB_REV_ID2'
 '@S9S_MB_2U_LIB.S9S_MB_2U(SCH_1):FAB_REV_ID2':
 C_SIGNAL='@s9s_mb_2u_lib.s9s_mb_2u(sch_1):fab_rev_id2';
NODE_NAME     U4 AA7
 '@S9S_MB_2U_LIB.S9S_MB_2U(SCH_1):PAGE176_I22@PURE_QUANTA.EMMITSBURG_REV0P9(CHIPS)':
 'GPP_M_2': CDS_PINID='GPP_M_2';
NODE_NAME     R2973 1
 '@S9S_MB_2U_LIB.S9S_MB_2U(SCH_1):PAGE184_I69@PURE_QUANTA.Q_RES(CHIPS)':
 'A': CDS_PINID='A';
NODE_NAME     R2972 2
 '@S9S_MB_2U_LIB.S9S_MB_2U(SCH_1):PAGE184_I71@PURE_QUANTA.Q_RES(CHIPS)':
 'B': CDS_PINID='B';
NET_NAME
'FB_BMC_ISOLATE'
 '@S9S_MB_2U_LIB.S9S_MB_2U(SCH_1):FB_BMC_ISOLATE':
 C_SIGNAL='@s9s_mb_2u_lib.s9s_mb_2u(sch_1):fb_bmc_isolate';
NODE_NAME     U320 4
 '@S9S_MB_2U_LIB.S9S_MB_2U(SCH_1):PAGE152_I92@PURE_QUANTA.74LVC1G66GV(CHIPS)':
 'E': CDS_PINID='E';
NODE_NAME     R2474 2
 '@S9S_MB_2U_LIB.S9S_MB_2U(SCH_1):PAGE151_I19@PURE_QUANTA.Q_RES(CHIPS)':
 'B': CDS_PINID='B';
NODE_NAME     R1289 1
 '@S9S_MB_2U_LIB.S9S_MB_2U(SCH_1):PAGE151_I21@PURE_QUANTA.Q_RES(CHIPS)':
 'A': CDS_PINID='A';
NODE_NAME     U68 1
 '@S9S_MB_2U_LIB.S9S_MB_2U(SCH_1):PAGE151_I30@PURE_QUANTA.74CBTLV3126PW(CHIPS)':
 '1OE': CDS_PINID='\1oe\';
NODE_NAME     U68 4
 '@S9S_MB_2U_LIB.S9S_MB_2U(SCH_1):PAGE151_I30@PURE_QUANTA.74CBTLV3126PW(CHIPS)':
 '2OE': CDS_PINID='\2oe\';
NODE_NAME     U68 10
 '@S9S_MB_2U_LIB.S9S_MB_2U(SCH_1):PAGE151_I30@PURE_QUANTA.74CBTLV3126PW(CHIPS)':
 '3OE': CDS_PINID='\3oe\';
NODE_NAME     U68 13
 '@S9S_MB_2U_LIB.S9S_MB_2U(SCH_1):PAGE151_I30@PURE_QUANTA.74CBTLV3126PW(CHIPS)':
 '4OE': CDS_PINID='\4oe\';
NODE_NAME     U67 1
 '@S9S_MB_2U_LIB.S9S_MB_2U(SCH_1):PAGE151_I39@PURE_QUANTA.74CBTLV3126PW(CHIPS)':
 '1OE': CDS_PINID='\1oe\';
NODE_NAME     U67 4
 '@S9S_MB_2U_LIB.S9S_MB_2U(SCH_1):PAGE151_I39@PURE_QUANTA.74CBTLV3126PW(CHIPS)':
 '2OE': CDS_PINID='\2oe\';
NODE_NAME     U67 10
 '@S9S_MB_2U_LIB.S9S_MB_2U(SCH_1):PAGE151_I39@PURE_QUANTA.74CBTLV3126PW(CHIPS)':
 '3OE': CDS_PINID='\3oe\';
NODE_NAME     U67 13
 '@S9S_MB_2U_LIB.S9S_MB_2U(SCH_1):PAGE151_I39@PURE_QUANTA.74CBTLV3126PW(CHIPS)':
 '4OE': CDS_PINID='\4oe\';
NODE_NAME     R2473 2
 '@S9S_MB_2U_LIB.S9S_MB_2U(SCH_1):PAGE151_I83@PURE_QUANTA.Q_RES(CHIPS)':
 'B': CDS_PINID='B';
NET_NAME
'FB_BMC_ISOLATE1'
 '@S9S_MB_2U_LIB.S9S_MB_2U(SCH_1):FB_BMC_ISOLATE1':
 C_SIGNAL='@s9s_mb_2u_lib.s9s_mb_2u(sch_1):fb_bmc_isolate1';
NODE_NAME     R3206 2
 '@S9S_MB_2U_LIB.S9S_MB_2U(SCH_1):PAGE307_I12@PURE_QUANTA.Q_RES(CHIPS)':
 'B': CDS_PINID='B';
NODE_NAME     R3207 1
 '@S9S_MB_2U_LIB.S9S_MB_2U(SCH_1):PAGE307_I15@PURE_QUANTA.Q_RES(CHIPS)':
 'A': CDS_PINID='A';
NODE_NAME     U222 1
 '@S9S_MB_2U_LIB.S9S_MB_2U(SCH_1):PAGE307_I32@PURE_QUANTA.74CBTLV3126PW(CHIPS)':
 '1OE': CDS_PINID='\1oe\';
NODE_NAME     U222 4
 '@S9S_MB_2U_LIB.S9S_MB_2U(SCH_1):PAGE307_I32@PURE_QUANTA.74CBTLV3126PW(CHIPS)':
 '2OE': CDS_PINID='\2oe\';
NODE_NAME     U222 10
 '@S9S_MB_2U_LIB.S9S_MB_2U(SCH_1):PAGE307_I32@PURE_QUANTA.74CBTLV3126PW(CHIPS)':
 '3OE': CDS_PINID='\3oe\';
NODE_NAME     U222 13
 '@S9S_MB_2U_LIB.S9S_MB_2U(SCH_1):PAGE307_I32@PURE_QUANTA.74CBTLV3126PW(CHIPS)':
 '4OE': CDS_PINID='\4oe\';
NODE_NAME     U223 1
 '@S9S_MB_2U_LIB.S9S_MB_2U(SCH_1):PAGE307_I78@PURE_QUANTA.74CBTLV3126PW(CHIPS)':
 '1OE': CDS_PINID='\1oe\';
NODE_NAME     U223 4
 '@S9S_MB_2U_LIB.S9S_MB_2U(SCH_1):PAGE307_I78@PURE_QUANTA.74CBTLV3126PW(CHIPS)':
 '2OE': CDS_PINID='\2oe\';
NODE_NAME     U223 10
 '@S9S_MB_2U_LIB.S9S_MB_2U(SCH_1):PAGE307_I78@PURE_QUANTA.74CBTLV3126PW(CHIPS)':
 '3OE': CDS_PINID='\3oe\';
NODE_NAME     U223 13
 '@S9S_MB_2U_LIB.S9S_MB_2U(SCH_1):PAGE307_I78@PURE_QUANTA.74CBTLV3126PW(CHIPS)':
 '4OE': CDS_PINID='\4oe\';
NODE_NAME     U321 4
 '@S9S_MB_2U_LIB.S9S_MB_2U(SCH_1):PAGE156_I92@PURE_QUANTA.74LVC1G66GV(CHIPS)':
 'E': CDS_PINID='E';
NODE_NAME     R3205 2
 '@S9S_MB_2U_LIB.S9S_MB_2U(SCH_1):PAGE307_I85@PURE_QUANTA.Q_RES(CHIPS)':
 'B': CDS_PINID='B';
NET_NAME
'FB_BMC_ISOLATE_R1'
 '@S9S_MB_2U_LIB.S9S_MB_2U(SCH_1):FB_BMC_ISOLATE_R1':
 C_SIGNAL='@s9s_mb_2u_lib.s9s_mb_2u(sch_1):fb_bmc_isolate_r1';
NODE_NAME     U66 4
 '@S9S_MB_2U_LIB.S9S_MB_2U(SCH_1):PAGE151_I15@PURE_QUANTA.74LVC1G126SE7(CHIPS)':
 'Y': CDS_PINID='Y';
NODE_NAME     R2473 1
 '@S9S_MB_2U_LIB.S9S_MB_2U(SCH_1):PAGE151_I83@PURE_QUANTA.Q_RES(CHIPS)':
 'A': CDS_PINID='A';
NET_NAME
'FB_BMC_ISOLATE_R2'
 '@S9S_MB_2U_LIB.S9S_MB_2U(SCH_1):FB_BMC_ISOLATE_R2':
 C_SIGNAL='@s9s_mb_2u_lib.s9s_mb_2u(sch_1):fb_bmc_isolate_r2';
NODE_NAME     U286 4
 '@S9S_MB_2U_LIB.S9S_MB_2U(SCH_1):PAGE307_I80@PURE_QUANTA.74LVC1G126SE7(CHIPS)':
 'Y': CDS_PINID='Y';
NODE_NAME     R3205 1
 '@S9S_MB_2U_LIB.S9S_MB_2U(SCH_1):PAGE307_I85@PURE_QUANTA.Q_RES(CHIPS)':
 'A': CDS_PINID='A';
NET_NAME
'FG_SS_EN'
 '@S9S_MB_2U_LIB.S9S_MB_2U(SCH_1):FG_SS_EN':
 C_SIGNAL='@s9s_mb_2u_lib.s9s_mb_2u(sch_1):fg_ss_en';
NODE_NAME     R4078 2
 '@S9S_MB_2U_LIB.S9S_MB_2U(SCH_1):PAGE201_I127@PURE_QUANTA.Q_RES(CHIPS)':
 'B': CDS_PINID='B';
NODE_NAME     R4079 1
 '@S9S_MB_2U_LIB.S9S_MB_2U(SCH_1):PAGE201_I128@PURE_QUANTA.Q_RES(CHIPS)':
 'A': CDS_PINID='A';
NODE_NAME     U247 23
 '@S9S_MB_2U_LIB.S9S_MB_2U(SCH_1):PAGE201_I167@PURE_QUANTA.9FGL0251DKILFT(CHIPS)':
 '^VSS_EN_TRI': CDS_PINID='\^vss_en_tri\';
NET_NAME
'FM_9ZXL045_0_OE_N'
 '@S9S_MB_2U_LIB.S9S_MB_2U(SCH_1):FM_9ZXL045_0_OE_N':
 C_SIGNAL='@s9s_mb_2u_lib.s9s_mb_2u(sch_1):fm_9zxl045_0_oe_n';
NODE_NAME     U314 15
 '@S9S_MB_2U_LIB.S9S_MB_2U(SCH_1):PAGE200_I1@PURE_QUANTA.9ZXL0451EKILFT(CHIPS)':
 'VOE0#': CDS_PINID='\voe0#\';
NODE_NAME     R4477 1
 '@S9S_MB_2U_LIB.S9S_MB_2U(SCH_1):PAGE200_I74@PURE_QUANTA.Q_RES(CHIPS)':
 'A': CDS_PINID='A';
NET_NAME
'FM_9ZXL045_1_OE_N'
 '@S9S_MB_2U_LIB.S9S_MB_2U(SCH_1):FM_9ZXL045_1_OE_N':
 C_SIGNAL='@s9s_mb_2u_lib.s9s_mb_2u(sch_1):fm_9zxl045_1_oe_n';
NODE_NAME     U314 18
 '@S9S_MB_2U_LIB.S9S_MB_2U(SCH_1):PAGE200_I1@PURE_QUANTA.9ZXL0451EKILFT(CHIPS)':
 'VOE1#': CDS_PINID='\voe1#\';
NODE_NAME     R4478 1
 '@S9S_MB_2U_LIB.S9S_MB_2U(SCH_1):PAGE200_I75@PURE_QUANTA.Q_RES(CHIPS)':
 'A': CDS_PINID='A';
NET_NAME
'FM_9ZXL045_2_OE_N'
 '@S9S_MB_2U_LIB.S9S_MB_2U(SCH_1):FM_9ZXL045_2_OE_N':
 C_SIGNAL='@s9s_mb_2u_lib.s9s_mb_2u(sch_1):fm_9zxl045_2_oe_n';
NODE_NAME     U314 24
 '@S9S_MB_2U_LIB.S9S_MB_2U(SCH_1):PAGE200_I1@PURE_QUANTA.9ZXL0451EKILFT(CHIPS)':
 'VOE2#': CDS_PINID='\voe2#\';
NODE_NAME     R4479 1
 '@S9S_MB_2U_LIB.S9S_MB_2U(SCH_1):PAGE200_I76@PURE_QUANTA.Q_RES(CHIPS)':
 'A': CDS_PINID='A';
NET_NAME
'FM_9ZXL045_3_OE_N'
 '@S9S_MB_2U_LIB.S9S_MB_2U(SCH_1):FM_9ZXL045_3_OE_N':
 C_SIGNAL='@s9s_mb_2u_lib.s9s_mb_2u(sch_1):fm_9zxl045_3_oe_n';
NODE_NAME     U314 26
 '@S9S_MB_2U_LIB.S9S_MB_2U(SCH_1):PAGE200_I1@PURE_QUANTA.9ZXL0451EKILFT(CHIPS)':
 'VOE3#': CDS_PINID='\voe3#\';
NODE_NAME     R4494 1
 '@S9S_MB_2U_LIB.S9S_MB_2U(SCH_1):PAGE200_I69@PURE_QUANTA.Q_RES(CHIPS)':
 'A': CDS_PINID='A';
NET_NAME
'FM_9ZXL045_DEV_EN'
 '@S9S_MB_2U_LIB.S9S_MB_2U(SCH_1):FM_9ZXL045_DEV_EN':
 C_SIGNAL='@s9s_mb_2u_lib.s9s_mb_2u(sch_1):fm_9zxl045_dev_en';
NODE_NAME     U314 1
 '@S9S_MB_2U_LIB.S9S_MB_2U(SCH_1):PAGE200_I1@PURE_QUANTA.9ZXL0451EKILFT(CHIPS)':
 '^CKPWRGD_PD#': CDS_PINID='\^ckpwrgd_pd#\';
NODE_NAME     R4476 2
 '@S9S_MB_2U_LIB.S9S_MB_2U(SCH_1):PAGE200_I39@PURE_QUANTA.Q_RES(CHIPS)':
 'B': CDS_PINID='B';
NET_NAME
'FM_AC_PWR_BTN_N'
 '@S9S_MB_2U_LIB.S9S_MB_2U(SCH_1):FM_AC_PWR_BTN_N':
 C_SIGNAL='@s9s_mb_2u_lib.s9s_mb_2u(sch_1):fm_ac_pwr_btn_n';
NODE_NAME     R4720 1
 '@S9S_MB_2U_LIB.S9S_MB_2U(SCH_1):PAGE227_I57@PURE_QUANTA.Q_RES(CHIPS)':
 'A': CDS_PINID='A';
NODE_NAME     J41 B42
 '@S9S_MB_2U_LIB.S9S_MB_2U(SCH_1):PAGE227_I173@PURE_QUANTA.SCONN168_ME1016810202011(CHIPS)':
 'PRSNTB0#': CDS_PINID='\prsntb0#\';
NET_NAME
'FM_AC_PWR_BTN_PDB_N'
 '@S9S_MB_2U_LIB.S9S_MB_2U(SCH_1):FM_AC_PWR_BTN_PDB_N':
 C_SIGNAL='@s9s_mb_2u_lib.s9s_mb_2u(sch_1):fm_ac_pwr_btn_pdb_n';
NODE_NAME     J45 A2
 '@S9S_MB_2U_LIB.S9S_MB_2U(SCH_1):PAGE233_I12@PURE_QUANTA.CONN60_101062636003K02LF(CHIPS)':
 'A2': CDS_PINID='A2';
NODE_NAME     R4721 2
 '@S9S_MB_2U_LIB.S9S_MB_2U(SCH_1):PAGE233_I35@PURE_QUANTA.Q_RES(CHIPS)':
 'B': CDS_PINID='B';
NODE_NAME     C2371 1
 '@S9S_MB_2U_LIB.S9S_MB_2U(SCH_1):PAGE233_I51@PURE_QUANTA.Q_CAP(CHIPS)':
 'A': CDS_PINID='A';
NET_NAME
'FM_AC_PWR_BTN_PLD_ISO_N'
 '@S9S_MB_2U_LIB.S9S_MB_2U(SCH_1):FM_AC_PWR_BTN_PLD_ISO_N':
 C_SIGNAL='@s9s_mb_2u_lib.s9s_mb_2u(sch_1):fm_ac_pwr_btn_pld_iso_n';
NODE_NAME     U249 T16
 '@S9S_MB_2U_LIB.S9S_MB_2U(SCH_1):PAGE312_I1@PURE_QUANTA.LCMXO3LF9400C5BG484C(CHIPS)':
 'PB46D': CDS_PINID='PB46D';
NODE_NAME     R4719 2
 '@S9S_MB_2U_LIB.S9S_MB_2U(SCH_1):PAGE213_I32@PURE_QUANTA.Q_RES(CHIPS)':
 'B': CDS_PINID='B';
NODE_NAME     R4718 2
 '@S9S_MB_2U_LIB.S9S_MB_2U(SCH_1):PAGE213_I33@PURE_QUANTA.Q_RES(CHIPS)':
 'B': CDS_PINID='B';
NET_NAME
'FM_AC_PWR_BTN_PLD_ISO_R_N'
 '@S9S_MB_2U_LIB.S9S_MB_2U(SCH_1):FM_AC_PWR_BTN_PLD_ISO_R_N':
 C_SIGNAL='@s9s_mb_2u_lib.s9s_mb_2u(sch_1):fm_ac_pwr_btn_pld_iso_r_n';
NODE_NAME     R4718 1
 '@S9S_MB_2U_LIB.S9S_MB_2U(SCH_1):PAGE213_I33@PURE_QUANTA.Q_RES(CHIPS)':
 'A': CDS_PINID='A';
NODE_NAME     U332 6
 '@S9S_MB_2U_LIB.S9S_MB_2U(SCH_1):PAGE213_I37@PURE_QUANTA.74LVC2G07DW7(CHIPS)':
 '1Y': CDS_PINID='\1y\';
NET_NAME
'FM_AC_PWR_BTN_PLD_N'
 '@S9S_MB_2U_LIB.S9S_MB_2U(SCH_1):FM_AC_PWR_BTN_PLD_N':
 C_SIGNAL='@s9s_mb_2u_lib.s9s_mb_2u(sch_1):fm_ac_pwr_btn_pld_n';
NODE_NAME     U332 1
 '@S9S_MB_2U_LIB.S9S_MB_2U(SCH_1):PAGE213_I37@PURE_QUANTA.74LVC2G07DW7(CHIPS)':
 '1A': CDS_PINID='\1a\';
NODE_NAME     R4717 2
 '@S9S_MB_2U_LIB.S9S_MB_2U(SCH_1):PAGE213_I41@PURE_QUANTA.Q_RES(CHIPS)':
 'B': CDS_PINID='B';
NET_NAME
'FM_AC_PWR_BTN_R_N'
 '@S9S_MB_2U_LIB.S9S_MB_2U(SCH_1):FM_AC_PWR_BTN_R_N':
 C_SIGNAL='@s9s_mb_2u_lib.s9s_mb_2u(sch_1):fm_ac_pwr_btn_r_n';
NODE_NAME     R4716 2
 '@S9S_MB_2U_LIB.S9S_MB_2U(SCH_1):PAGE213_I40@PURE_QUANTA.Q_RES(CHIPS)':
 'B': CDS_PINID='B';
NODE_NAME     R4717 1
 '@S9S_MB_2U_LIB.S9S_MB_2U(SCH_1):PAGE213_I41@PURE_QUANTA.Q_RES(CHIPS)':
 'A': CDS_PINID='A';
NODE_NAME     C2369 1
 '@S9S_MB_2U_LIB.S9S_MB_2U(SCH_1):PAGE213_I42@PURE_QUANTA.Q_CAP(CHIPS)':
 'A': CDS_PINID='A';
NODE_NAME     R4721 1
 '@S9S_MB_2U_LIB.S9S_MB_2U(SCH_1):PAGE233_I35@PURE_QUANTA.Q_RES(CHIPS)':
 'A': CDS_PINID='A';
NODE_NAME     R4720 2
 '@S9S_MB_2U_LIB.S9S_MB_2U(SCH_1):PAGE227_I57@PURE_QUANTA.Q_RES(CHIPS)':
 'B': CDS_PINID='B';
NET_NAME
'FM_ADR_ACK'
 '@S9S_MB_2U_LIB.S9S_MB_2U(SCH_1):FM_ADR_ACK':
 C_SIGNAL='@s9s_mb_2u_lib.s9s_mb_2u(sch_1):fm_adr_ack';
NODE_NAME     U4 AD4
 '@S9S_MB_2U_LIB.S9S_MB_2U(SCH_1):PAGE175_I93@PURE_QUANTA.EMMITSBURG_REV0P9(CHIPS)':
 'GPP_D_16_ADR_ACK': CDS_PINID='GPP_D_16_ADR_ACK';
NODE_NAME     R369 2
 '@S9S_MB_2U_LIB.S9S_MB_2U(SCH_1):PAGE186_I16@PURE_QUANTA.Q_RES(CHIPS)':
 'B': CDS_PINID='B';
NODE_NAME     R700 2
 '@S9S_MB_2U_LIB.S9S_MB_2U(SCH_1):PAGE312_I169@PURE_QUANTA.Q_RES(CHIPS)':
 'B': CDS_PINID='B';
NET_NAME
'FM_ADR_ACK_R'
 '@S9S_MB_2U_LIB.S9S_MB_2U(SCH_1):FM_ADR_ACK_R':
 C_SIGNAL='@s9s_mb_2u_lib.s9s_mb_2u(sch_1):fm_adr_ack_r';
NODE_NAME     U249 AA2
 '@S9S_MB_2U_LIB.S9S_MB_2U(SCH_1):PAGE312_I1@PURE_QUANTA.LCMXO3LF9400C5BG484C(CHIPS)':
 'PB5A': CDS_PINID='PB5A';
NODE_NAME     R700 1
 '@S9S_MB_2U_LIB.S9S_MB_2U(SCH_1):PAGE312_I169@PURE_QUANTA.Q_RES(CHIPS)':
 'A': CDS_PINID='A';
NET_NAME
'FM_ADR_COMPLETE'
 '@S9S_MB_2U_LIB.S9S_MB_2U(SCH_1):FM_ADR_COMPLETE':
 C_SIGNAL='@s9s_mb_2u_lib.s9s_mb_2u(sch_1):fm_adr_complete';
NODE_NAME     U4 AC1
 '@S9S_MB_2U_LIB.S9S_MB_2U(SCH_1):PAGE175_I93@PURE_QUANTA.EMMITSBURG_REV0P9(CHIPS)':
 'GPP_D_13_ADR_COMPLETE': CDS_PINID='GPP_D_13_ADR_COMPLETE';
NODE_NAME     R1341 1
 '@S9S_MB_2U_LIB.S9S_MB_2U(SCH_1):PAGE189_I106@PURE_QUANTA.Q_RES(CHIPS)':
 'A': CDS_PINID='A';
NODE_NAME     U249 U6
 '@S9S_MB_2U_LIB.S9S_MB_2U(SCH_1):PAGE312_I1@PURE_QUANTA.LCMXO3LF9400C5BG484C(CHIPS)':
 'PB5D': CDS_PINID='PB5D';
NODE_NAME     J104 6
 '@S9S_MB_2U_LIB.S9S_MB_2U(SCH_1):PAGE189_I134@PURE_QUANTA.CONN14_210HP207GBR1(CHIPS)':
 '6': CDS_PINID='\6\';
NET_NAME
'FM_ADR_MODE0'
 '@S9S_MB_2U_LIB.S9S_MB_2U(SCH_1):FM_ADR_MODE0':
 C_SIGNAL='@s9s_mb_2u_lib.s9s_mb_2u(sch_1):fm_adr_mode0';
NODE_NAME     R773 2
 '@S9S_MB_2U_LIB.S9S_MB_2U(SCH_1):PAGE133_I124@PURE_QUANTA.Q_RES(CHIPS)':
 'B': CDS_PINID='B';
NODE_NAME     U4 AV11
 '@S9S_MB_2U_LIB.S9S_MB_2U(SCH_1):PAGE177_I27@PURE_QUANTA.EMMITSBURG_REV0P9(CHIPS)':
 'GPPC_S_3_CPU_GP_1': CDS_PINID='GPPC_S_3_CPU_GP_1';
NODE_NAME     R1810 1
 '@S9S_MB_2U_LIB.S9S_MB_2U(SCH_1):PAGE186_I88@PURE_QUANTA.Q_RES(CHIPS)':
 'A': CDS_PINID='A';
NODE_NAME     R1809 2
 '@S9S_MB_2U_LIB.S9S_MB_2U(SCH_1):PAGE186_I89@PURE_QUANTA.Q_RES(CHIPS)':
 'B': CDS_PINID='B';
NODE_NAME     R1455 2
 '@S9S_MB_2U_LIB.S9S_MB_2U(SCH_1):PAGE193_I27@PURE_QUANTA.Q_RES(CHIPS)':
 'B': CDS_PINID='B';
NET_NAME
'FM_ADR_MODE0_R'
 '@S9S_MB_2U_LIB.S9S_MB_2U(SCH_1):FM_ADR_MODE0_R':
 C_SIGNAL='@s9s_mb_2u_lib.s9s_mb_2u(sch_1):fm_adr_mode0_r';
NODE_NAME     R1455 1
 '@S9S_MB_2U_LIB.S9S_MB_2U(SCH_1):PAGE193_I27@PURE_QUANTA.Q_RES(CHIPS)':
 'A': CDS_PINID='A';
NODE_NAME     U249 AA3
 '@S9S_MB_2U_LIB.S9S_MB_2U(SCH_1):PAGE312_I1@PURE_QUANTA.LCMXO3LF9400C5BG484C(CHIPS)':
 'PB7A||CSSPIN': CDS_PINID='\pb7a||csspin\';
NET_NAME
'FM_ADR_MODE1'
 '@S9S_MB_2U_LIB.S9S_MB_2U(SCH_1):FM_ADR_MODE1':
 C_SIGNAL='@s9s_mb_2u_lib.s9s_mb_2u(sch_1):fm_adr_mode1';
NODE_NAME     U4 AL5
 '@S9S_MB_2U_LIB.S9S_MB_2U(SCH_1):PAGE175_I93@PURE_QUANTA.EMMITSBURG_REV0P9(CHIPS)':
 'GPPC_C_18': CDS_PINID='GPPC_C_18';
NODE_NAME     R379 1
 '@S9S_MB_2U_LIB.S9S_MB_2U(SCH_1):PAGE186_I76@PURE_QUANTA.Q_RES(CHIPS)':
 'A': CDS_PINID='A';
NODE_NAME     R378 2
 '@S9S_MB_2U_LIB.S9S_MB_2U(SCH_1):PAGE186_I77@PURE_QUANTA.Q_RES(CHIPS)':
 'B': CDS_PINID='B';
NODE_NAME     R269 1
 '@S9S_MB_2U_LIB.S9S_MB_2U(SCH_1):PAGE212_I91@PURE_QUANTA.Q_RES(CHIPS)':
 'A': CDS_PINID='A';
NET_NAME
'FM_ADR_MODE1_R'
 '@S9S_MB_2U_LIB.S9S_MB_2U(SCH_1):FM_ADR_MODE1_R':
 C_SIGNAL='@s9s_mb_2u_lib.s9s_mb_2u(sch_1):fm_adr_mode1_r';
NODE_NAME     R269 2
 '@S9S_MB_2U_LIB.S9S_MB_2U(SCH_1):PAGE212_I91@PURE_QUANTA.Q_RES(CHIPS)':
 'B': CDS_PINID='B';
NODE_NAME     U249 AB3
 '@S9S_MB_2U_LIB.S9S_MB_2U(SCH_1):PAGE312_I1@PURE_QUANTA.LCMXO3LF9400C5BG484C(CHIPS)':
 'PB7B': CDS_PINID='PB7B';
NET_NAME
'FM_ADR_TRIGGER_N'
 '@S9S_MB_2U_LIB.S9S_MB_2U(SCH_1):FM_ADR_TRIGGER_N':
 C_SIGNAL='@s9s_mb_2u_lib.s9s_mb_2u(sch_1):fm_adr_trigger_n';
NODE_NAME     R698 2
 '@S9S_MB_2U_LIB.S9S_MB_2U(SCH_1):PAGE193_I32@PURE_QUANTA.Q_RES(CHIPS)':
 'B': CDS_PINID='B';
NODE_NAME     U249 V6
 '@S9S_MB_2U_LIB.S9S_MB_2U(SCH_1):PAGE312_I1@PURE_QUANTA.LCMXO3LF9400C5BG484C(CHIPS)':
 'PB5C': CDS_PINID='PB5C';
NODE_NAME     R1435 1
 '@S9S_MB_2U_LIB.S9S_MB_2U(SCH_1):PAGE209_I43@PURE_QUANTA.Q_RES(CHIPS)':
 'A': CDS_PINID='A';
NET_NAME
'FM_ADR_TRIGGER_R_N'
 '@S9S_MB_2U_LIB.S9S_MB_2U(SCH_1):FM_ADR_TRIGGER_R_N':
 C_SIGNAL='@s9s_mb_2u_lib.s9s_mb_2u(sch_1):fm_adr_trigger_r_n';
NODE_NAME     U4 AH4
 '@S9S_MB_2U_LIB.S9S_MB_2U(SCH_1):PAGE175_I93@PURE_QUANTA.EMMITSBURG_REV0P9(CHIPS)':
 'GPP_D_14_ADR_TRIGGER_N': CDS_PINID='GPP_D_14_ADR_TRIGGER_N';
NODE_NAME     R698 1
 '@S9S_MB_2U_LIB.S9S_MB_2U(SCH_1):PAGE193_I32@PURE_QUANTA.Q_RES(CHIPS)':
 'A': CDS_PINID='A';
NET_NAME
'FM_AUX_SW_EN'
 '@S9S_MB_2U_LIB.S9S_MB_2U(SCH_1):FM_AUX_SW_EN':
 C_SIGNAL='@s9s_mb_2u_lib.s9s_mb_2u(sch_1):fm_aux_sw_en';
NODE_NAME     R991 1
 '@S9S_MB_2U_LIB.S9S_MB_2U(SCH_1):PAGE208_I20@PURE_QUANTA.Q_RES(CHIPS)':
 'A': CDS_PINID='A';
NODE_NAME     U249 F18
 '@S9S_MB_2U_LIB.S9S_MB_2U(SCH_1):PAGE313_I1@PURE_QUANTA.LCMXO3LF9400C5BG484C(CHIPS)':
 'PR5C': CDS_PINID='PR5C';
NET_NAME
'FM_BIOS_ADV_FUNCTIONS'
 '@S9S_MB_2U_LIB.S9S_MB_2U(SCH_1):FM_BIOS_ADV_FUNCTIONS':
 C_SIGNAL='@s9s_mb_2u_lib.s9s_mb_2u(sch_1):fm_bios_adv_functions';
NODE_NAME     U4 AF11
 '@S9S_MB_2U_LIB.S9S_MB_2U(SCH_1):PAGE176_I22@PURE_QUANTA.EMMITSBURG_REV0P9(CHIPS)':
 'GPP_L_3': CDS_PINID='GPP_L_3';
NODE_NAME     R1498 2
 '@S9S_MB_2U_LIB.S9S_MB_2U(SCH_1):PAGE188_I76@PURE_QUANTA.Q_RES(CHIPS)':
 'B': CDS_PINID='B';
NODE_NAME     R1499 1
 '@S9S_MB_2U_LIB.S9S_MB_2U(SCH_1):PAGE188_I77@PURE_QUANTA.Q_RES(CHIPS)':
 'A': CDS_PINID='A';
NET_NAME
'FM_BIOS_DEBUG_EN_N'
 '@S9S_MB_2U_LIB.S9S_MB_2U(SCH_1):FM_BIOS_DEBUG_EN_N':
 C_SIGNAL='@s9s_mb_2u_lib.s9s_mb_2u(sch_1):fm_bios_debug_en_n';
NODE_NAME     R2971 1
 '@S9S_MB_2U_LIB.S9S_MB_2U(SCH_1):PAGE175_I253@PURE_QUANTA.Q_RES(CHIPS)':
 'A': CDS_PINID='A';
NODE_NAME     U249 W14
 '@S9S_MB_2U_LIB.S9S_MB_2U(SCH_1):PAGE312_I1@PURE_QUANTA.LCMXO3LF9400C5BG484C(CHIPS)':
 'PB33D': CDS_PINID='PB33D';
NET_NAME
'FM_BIOS_DEBUG_EN_R_N'
 '@S9S_MB_2U_LIB.S9S_MB_2U(SCH_1):FM_BIOS_DEBUG_EN_R_N':
 C_SIGNAL='@s9s_mb_2u_lib.s9s_mb_2u(sch_1):fm_bios_debug_en_r_n';
NODE_NAME     U4 AA3
 '@S9S_MB_2U_LIB.S9S_MB_2U(SCH_1):PAGE175_I93@PURE_QUANTA.EMMITSBURG_REV0P9(CHIPS)':
 'GPP_D_22_USB2_OCB_7': CDS_PINID='GPP_D_22_USB2_OCB_7';
NODE_NAME     R2971 2
 '@S9S_MB_2U_LIB.S9S_MB_2U(SCH_1):PAGE175_I253@PURE_QUANTA.Q_RES(CHIPS)':
 'B': CDS_PINID='B';
NET_NAME
'FM_BIOS_IMAGE_SWAP_N'
 '@S9S_MB_2U_LIB.S9S_MB_2U(SCH_1):FM_BIOS_IMAGE_SWAP_N':
 C_SIGNAL='@s9s_mb_2u_lib.s9s_mb_2u(sch_1):fm_bios_image_swap_n';
NODE_NAME     U4 Y4
 '@S9S_MB_2U_LIB.S9S_MB_2U(SCH_1):PAGE175_I93@PURE_QUANTA.EMMITSBURG_REV0P9(CHIPS)':
 'GPP_D_19_MSMI_N': CDS_PINID='GPP_D_19_MSMI_N';
NODE_NAME     R1339 2
 '@S9S_MB_2U_LIB.S9S_MB_2U(SCH_1):PAGE189_I100@PURE_QUANTA.Q_RES(CHIPS)':
 'B': CDS_PINID='B';
NODE_NAME     J104 8
 '@S9S_MB_2U_LIB.S9S_MB_2U(SCH_1):PAGE189_I134@PURE_QUANTA.CONN14_210HP207GBR1(CHIPS)':
 '8': CDS_PINID='\8\';
NET_NAME
'FM_BIOS_POST_CMPLT_BMC_N'
 '@S9S_MB_2U_LIB.S9S_MB_2U(SCH_1):FM_BIOS_POST_CMPLT_BMC_N':
 C_SIGNAL='@s9s_mb_2u_lib.s9s_mb_2u(sch_1):fm_bios_post_cmplt_bmc_n';
NODE_NAME     R1300 2
 '@S9S_MB_2U_LIB.S9S_MB_2U(SCH_1):PAGE193_I5@PURE_QUANTA.Q_RES(CHIPS)':
 'B': CDS_PINID='B';
NODE_NAME     U249 T9
 '@S9S_MB_2U_LIB.S9S_MB_2U(SCH_1):PAGE312_I1@PURE_QUANTA.LCMXO3LF9400C5BG484C(CHIPS)':
 'PB16A||MCLK||CCLK': CDS_PINID='\pb16a||mclk||cclk\';
NET_NAME
'FM_BIOS_POST_CMPLT_HDR_N'
 '@S9S_MB_2U_LIB.S9S_MB_2U(SCH_1):FM_BIOS_POST_CMPLT_HDR_N':
 C_SIGNAL='@s9s_mb_2u_lib.s9s_mb_2u(sch_1):fm_bios_post_cmplt_hdr_n';
NODE_NAME     R3065 2
 '@S9S_MB_2U_LIB.S9S_MB_2U(SCH_1):PAGE193_I40@PURE_QUANTA.Q_RES(CHIPS)':
 'B': CDS_PINID='B';
NODE_NAME     J100 19
 '@S9S_MB_2U_LIB.S9S_MB_2U(SCH_1):PAGE215_I32@PURE_QUANTA.SCONN20_513860200CV01(CHIPS)':
 '19': CDS_PINID='\19\';
NET_NAME
'FM_BIOS_POST_CMPLT_N'
 '@S9S_MB_2U_LIB.S9S_MB_2U(SCH_1):FM_BIOS_POST_CMPLT_N':
 C_SIGNAL='@s9s_mb_2u_lib.s9s_mb_2u(sch_1):fm_bios_post_cmplt_n';
NODE_NAME     U4 AL3
 '@S9S_MB_2U_LIB.S9S_MB_2U(SCH_1):PAGE175_I93@PURE_QUANTA.EMMITSBURG_REV0P9(CHIPS)':
 'GPPC_C_17_ME_SML4ALERT_N': CDS_PINID='GPPC_C_17_ME_SML4ALERT_N';
NODE_NAME     R1449 2
 '@S9S_MB_2U_LIB.S9S_MB_2U(SCH_1):PAGE192_I41@PURE_QUANTA.Q_RES(CHIPS)':
 'B': CDS_PINID='B';
NODE_NAME     R1300 1
 '@S9S_MB_2U_LIB.S9S_MB_2U(SCH_1):PAGE193_I5@PURE_QUANTA.Q_RES(CHIPS)':
 'A': CDS_PINID='A';
NODE_NAME     R3065 1
 '@S9S_MB_2U_LIB.S9S_MB_2U(SCH_1):PAGE193_I40@PURE_QUANTA.Q_RES(CHIPS)':
 'A': CDS_PINID='A';
NET_NAME
'FM_BMC_CPU_FBRK_OUT_N'
 '@S9S_MB_2U_LIB.S9S_MB_2U(SCH_1):FM_BMC_CPU_FBRK_OUT_N':
 C_SIGNAL='@s9s_mb_2u_lib.s9s_mb_2u(sch_1):fm_bmc_cpu_fbrk_out_n';
NODE_NAME     R1381 2
 '@S9S_MB_2U_LIB.S9S_MB_2U(SCH_1):PAGE226_I7@PURE_QUANTA.Q_RES(CHIPS)':
 'B': CDS_PINID='B';
NODE_NAME     U84 12
 '@S9S_MB_2U_LIB.S9S_MB_2U(SCH_1):PAGE226_I18@PURE_QUANTA.GTL2014PW(CHIPS)':
 'A1': CDS_PINID='A1';
NODE_NAME     R4611 2
 '@S9S_MB_2U_LIB.S9S_MB_2U(SCH_1):PAGE313_I206@PURE_QUANTA.Q_RES(CHIPS)':
 'B': CDS_PINID='B';
NET_NAME
'FM_BMC_CPU_FBRK_OUT_R_N'
 '@S9S_MB_2U_LIB.S9S_MB_2U(SCH_1):FM_BMC_CPU_FBRK_OUT_R_N':
 C_SIGNAL='@s9s_mb_2u_lib.s9s_mb_2u(sch_1):fm_bmc_cpu_fbrk_out_r_n';
NODE_NAME     U249 V18
 '@S9S_MB_2U_LIB.S9S_MB_2U(SCH_1):PAGE313_I1@PURE_QUANTA.LCMXO3LF9400C5BG484C(CHIPS)':
 'PR30A': CDS_PINID='PR30A';
NODE_NAME     R4611 1
 '@S9S_MB_2U_LIB.S9S_MB_2U(SCH_1):PAGE313_I206@PURE_QUANTA.Q_RES(CHIPS)':
 'A': CDS_PINID='A';
NET_NAME
'FM_BMC_DBP_PRESENT_R_N'
 '@S9S_MB_2U_LIB.S9S_MB_2U(SCH_1):FM_BMC_DBP_PRESENT_R_N':
 C_SIGNAL='@s9s_mb_2u_lib.s9s_mb_2u(sch_1):fm_bmc_dbp_present_r_n';
NODE_NAME     R1472 2
 '@S9S_MB_2U_LIB.S9S_MB_2U(SCH_1):PAGE133_I144@PURE_QUANTA.Q_RES(CHIPS)':
 'B': CDS_PINID='B';
NODE_NAME     U249 U8
 '@S9S_MB_2U_LIB.S9S_MB_2U(SCH_1):PAGE312_I1@PURE_QUANTA.LCMXO3LF9400C5BG484C(CHIPS)':
 'PB13D': CDS_PINID='PB13D';
NET_NAME
'FM_BMC_EN_DET'
 '@S9S_MB_2U_LIB.S9S_MB_2U(SCH_1):FM_BMC_EN_DET':
 C_SIGNAL='@s9s_mb_2u_lib.s9s_mb_2u(sch_1):fm_bmc_en_det';
NODE_NAME     U86 2
 '@S9S_MB_2U_LIB.S9S_MB_2U(SCH_1):PAGE137_I84@PURE_QUANTA.74CBTLV3126PW(CHIPS)':
 '1A': CDS_PINID='\1a\';
NODE_NAME     U86 5
 '@S9S_MB_2U_LIB.S9S_MB_2U(SCH_1):PAGE137_I84@PURE_QUANTA.74CBTLV3126PW(CHIPS)':
 '2A': CDS_PINID='\2a\';
NODE_NAME     U86 9
 '@S9S_MB_2U_LIB.S9S_MB_2U(SCH_1):PAGE137_I84@PURE_QUANTA.74CBTLV3126PW(CHIPS)':
 '3A': CDS_PINID='\3a\';
NODE_NAME     U86 12
 '@S9S_MB_2U_LIB.S9S_MB_2U(SCH_1):PAGE137_I84@PURE_QUANTA.74CBTLV3126PW(CHIPS)':
 '4A': CDS_PINID='\4a\';
NODE_NAME     C1293 1
 '@S9S_MB_2U_LIB.S9S_MB_2U(SCH_1):PAGE137_I95@PURE_QUANTA.Q_CAP(CHIPS)':
 'A': CDS_PINID='A';
NODE_NAME     U87 S
 '@S9S_MB_2U_LIB.S9S_MB_2U(SCH_1):PAGE137_I96@PURE_QUANTA.MOSFET_N(CHIPS)':
 'SOURCE': CDS_PINID='SOURCE';
NODE_NAME     R1375 1
 '@S9S_MB_2U_LIB.S9S_MB_2U(SCH_1):PAGE137_I97@PURE_QUANTA.Q_RES(CHIPS)':
 'A': CDS_PINID='A';
NET_NAME
'FM_BMC_INTRUDER_N'
 '@S9S_MB_2U_LIB.S9S_MB_2U(SCH_1):FM_BMC_INTRUDER_N':
 C_SIGNAL='@s9s_mb_2u_lib.s9s_mb_2u(sch_1):fm_bmc_intruder_n';
NODE_NAME     R4809 1
 '@S9S_MB_2U_LIB.S9S_MB_2U(SCH_1):PAGE227_I2@PURE_QUANTA.Q_RES(CHIPS)':
 'A': CDS_PINID='A';
NODE_NAME     J41 A54
 '@S9S_MB_2U_LIB.S9S_MB_2U(SCH_1):PAGE227_I173@PURE_QUANTA.SCONN168_ME1016810202011(CHIPS)':
 'PERP11': CDS_PINID='PERP11';
NET_NAME
'FM_BMC_PWRBTN_N'
 '@S9S_MB_2U_LIB.S9S_MB_2U(SCH_1):FM_BMC_PWRBTN_N':
 C_SIGNAL='@s9s_mb_2u_lib.s9s_mb_2u(sch_1):fm_bmc_pwrbtn_n';
NODE_NAME     U4 AR10
 '@S9S_MB_2U_LIB.S9S_MB_2U(SCH_1):PAGE174_I36@PURE_QUANTA.EMMITSBURG_REV0P9(CHIPS)':
 'PWRBTN_N': CDS_PINID='PWRBTN_N';
NODE_NAME     R1744 2
 '@S9S_MB_2U_LIB.S9S_MB_2U(SCH_1):PAGE212_I94@PURE_QUANTA.Q_RES(CHIPS)':
 'B': CDS_PINID='B';
NODE_NAME     R139 1
 '@S9S_MB_2U_LIB.S9S_MB_2U(SCH_1):PAGE209_I40@PURE_QUANTA.Q_RES(CHIPS)':
 'A': CDS_PINID='A';
NET_NAME
'FM_BMC_PWRBTN_OUT_N'
 '@S9S_MB_2U_LIB.S9S_MB_2U(SCH_1):FM_BMC_PWRBTN_OUT_N':
 C_SIGNAL='@s9s_mb_2u_lib.s9s_mb_2u(sch_1):fm_bmc_pwrbtn_out_n';
NODE_NAME     R1744 1
 '@S9S_MB_2U_LIB.S9S_MB_2U(SCH_1):PAGE212_I94@PURE_QUANTA.Q_RES(CHIPS)':
 'A': CDS_PINID='A';
NODE_NAME     R1815 1
 '@S9S_MB_2U_LIB.S9S_MB_2U(SCH_1):PAGE227_I26@PURE_QUANTA.Q_RES(CHIPS)':
 'A': CDS_PINID='A';
NET_NAME
'FM_BMC_PWRBTN_OUT_R_N'
 '@S9S_MB_2U_LIB.S9S_MB_2U(SCH_1):FM_BMC_PWRBTN_OUT_R_N':
 C_SIGNAL='@s9s_mb_2u_lib.s9s_mb_2u(sch_1):fm_bmc_pwrbtn_out_r_n';
NODE_NAME     R1815 2
 '@S9S_MB_2U_LIB.S9S_MB_2U(SCH_1):PAGE227_I26@PURE_QUANTA.Q_RES(CHIPS)':
 'B': CDS_PINID='B';
NODE_NAME     J41 A47
 '@S9S_MB_2U_LIB.S9S_MB_2U(SCH_1):PAGE227_I173@PURE_QUANTA.SCONN168_ME1016810202011(CHIPS)':
 'PERN9': CDS_PINID='PERN9';
NET_NAME
'FM_BMC_READY_R_N'
 '@S9S_MB_2U_LIB.S9S_MB_2U(SCH_1):FM_BMC_READY_R_N':
 C_SIGNAL='@s9s_mb_2u_lib.s9s_mb_2u(sch_1):fm_bmc_ready_r_n';
NODE_NAME     U4 BF15
 '@S9S_MB_2U_LIB.S9S_MB_2U(SCH_1):PAGE175_I93@PURE_QUANTA.EMMITSBURG_REV0P9(CHIPS)':
 'GPPC_A_13_SRCCLKREQ_N_3': CDS_PINID='GPPC_A_13_SRCCLKREQ_N_3';
NODE_NAME     R2155 2
 '@S9S_MB_2U_LIB.S9S_MB_2U(SCH_1):PAGE312_I177@PURE_QUANTA.Q_RES(CHIPS)':
 'B': CDS_PINID='B';
NET_NAME
'FM_BMC_READY_R_PLD_N'
 '@S9S_MB_2U_LIB.S9S_MB_2U(SCH_1):FM_BMC_READY_R_PLD_N':
 C_SIGNAL='@s9s_mb_2u_lib.s9s_mb_2u(sch_1):fm_bmc_ready_r_pld_n';
NODE_NAME     U249 AA17
 '@S9S_MB_2U_LIB.S9S_MB_2U(SCH_1):PAGE312_I1@PURE_QUANTA.LCMXO3LF9400C5BG484C(CHIPS)':
 'PB40B': CDS_PINID='PB40B';
NODE_NAME     R2155 1
 '@S9S_MB_2U_LIB.S9S_MB_2U(SCH_1):PAGE312_I177@PURE_QUANTA.Q_RES(CHIPS)':
 'A': CDS_PINID='A';
NET_NAME
'FM_BMC_RSTBTN_OUT_N'
 '@S9S_MB_2U_LIB.S9S_MB_2U(SCH_1):FM_BMC_RSTBTN_OUT_N':
 C_SIGNAL='@s9s_mb_2u_lib.s9s_mb_2u(sch_1):fm_bmc_rstbtn_out_n';
NODE_NAME     R697 1
 '@S9S_MB_2U_LIB.S9S_MB_2U(SCH_1):PAGE174_I66@PURE_QUANTA.Q_RES(CHIPS)':
 'A': CDS_PINID='A';
NODE_NAME     U249 U9
 '@S9S_MB_2U_LIB.S9S_MB_2U(SCH_1):PAGE312_I1@PURE_QUANTA.LCMXO3LF9400C5BG484C(CHIPS)':
 'PB16B||SO||SPISO': CDS_PINID='\pb16b||so||spiso\';
NET_NAME
'FM_BMC_SUSACK_R_N'
 '@S9S_MB_2U_LIB.S9S_MB_2U(SCH_1):FM_BMC_SUSACK_R_N':
 C_SIGNAL='@s9s_mb_2u_lib.s9s_mb_2u(sch_1):fm_bmc_susack_r_n';
NODE_NAME     R2071 1
 '@S9S_MB_2U_LIB.S9S_MB_2U(SCH_1):PAGE314_I137@PURE_QUANTA.Q_RES(CHIPS)':
 'A': CDS_PINID='A';
NODE_NAME     U249 C5
 '@S9S_MB_2U_LIB.S9S_MB_2U(SCH_1):PAGE314_I188@PURE_QUANTA.LCMXO3LF9400C5BG484C(CHIPS)':
 'PT12D': CDS_PINID='PT12D';
NET_NAME
'FM_BOARD_BMC_SKU_ID0'
 '@S9S_MB_2U_LIB.S9S_MB_2U(SCH_1):FM_BOARD_BMC_SKU_ID0':
 C_SIGNAL='@s9s_mb_2u_lib.s9s_mb_2u(sch_1):fm_board_bmc_sku_id0';
NODE_NAME     U249 J2
 '@S9S_MB_2U_LIB.S9S_MB_2U(SCH_1):PAGE311_I33@PURE_QUANTA.LCMXO3LF9400C5BG484C(CHIPS)':
 'PL12A': CDS_PINID='PL12A';
NODE_NAME     R4585 1
 '@S9S_MB_2U_LIB.S9S_MB_2U(SCH_1):PAGE184_I20@PURE_QUANTA.Q_RES(CHIPS)':
 'A': CDS_PINID='A';
NODE_NAME     R4584 2
 '@S9S_MB_2U_LIB.S9S_MB_2U(SCH_1):PAGE184_I24@PURE_QUANTA.Q_RES(CHIPS)':
 'B': CDS_PINID='B';
NET_NAME
'FM_BOARD_BMC_SKU_ID1'
 '@S9S_MB_2U_LIB.S9S_MB_2U(SCH_1):FM_BOARD_BMC_SKU_ID1':
 C_SIGNAL='@s9s_mb_2u_lib.s9s_mb_2u(sch_1):fm_board_bmc_sku_id1';
NODE_NAME     U249 J3
 '@S9S_MB_2U_LIB.S9S_MB_2U(SCH_1):PAGE311_I33@PURE_QUANTA.LCMXO3LF9400C5BG484C(CHIPS)':
 'PL11D': CDS_PINID='PL11D';
NODE_NAME     R4583 1
 '@S9S_MB_2U_LIB.S9S_MB_2U(SCH_1):PAGE184_I18@PURE_QUANTA.Q_RES(CHIPS)':
 'A': CDS_PINID='A';
NODE_NAME     R4582 2
 '@S9S_MB_2U_LIB.S9S_MB_2U(SCH_1):PAGE184_I23@PURE_QUANTA.Q_RES(CHIPS)':
 'B': CDS_PINID='B';
NET_NAME
'FM_BOARD_BMC_SKU_ID2'
 '@S9S_MB_2U_LIB.S9S_MB_2U(SCH_1):FM_BOARD_BMC_SKU_ID2':
 C_SIGNAL='@s9s_mb_2u_lib.s9s_mb_2u(sch_1):fm_board_bmc_sku_id2';
NODE_NAME     U249 J4
 '@S9S_MB_2U_LIB.S9S_MB_2U(SCH_1):PAGE311_I33@PURE_QUANTA.LCMXO3LF9400C5BG484C(CHIPS)':
 'PL11C': CDS_PINID='PL11C';
NODE_NAME     R4597 2
 '@S9S_MB_2U_LIB.S9S_MB_2U(SCH_1):PAGE184_I22@PURE_QUANTA.Q_RES(CHIPS)':
 'B': CDS_PINID='B';
NODE_NAME     R4598 1
 '@S9S_MB_2U_LIB.S9S_MB_2U(SCH_1):PAGE184_I16@PURE_QUANTA.Q_RES(CHIPS)':
 'A': CDS_PINID='A';
NET_NAME
'FM_BOARD_BMC_SKU_ID3'
 '@S9S_MB_2U_LIB.S9S_MB_2U(SCH_1):FM_BOARD_BMC_SKU_ID3':
 C_SIGNAL='@s9s_mb_2u_lib.s9s_mb_2u(sch_1):fm_board_bmc_sku_id3';
NODE_NAME     U249 J5
 '@S9S_MB_2U_LIB.S9S_MB_2U(SCH_1):PAGE311_I33@PURE_QUANTA.LCMXO3LF9400C5BG484C(CHIPS)':
 'PL11B': CDS_PINID='PL11B';
NODE_NAME     R4592 1
 '@S9S_MB_2U_LIB.S9S_MB_2U(SCH_1):PAGE184_I4@PURE_QUANTA.Q_RES(CHIPS)':
 'A': CDS_PINID='A';
NODE_NAME     R4591 2
 '@S9S_MB_2U_LIB.S9S_MB_2U(SCH_1):PAGE184_I6@PURE_QUANTA.Q_RES(CHIPS)':
 'B': CDS_PINID='B';
NET_NAME
'FM_BOARD_BMC_SKU_ID4'
 '@S9S_MB_2U_LIB.S9S_MB_2U(SCH_1):FM_BOARD_BMC_SKU_ID4':
 C_SIGNAL='@s9s_mb_2u_lib.s9s_mb_2u(sch_1):fm_board_bmc_sku_id4';
NODE_NAME     U249 H5
 '@S9S_MB_2U_LIB.S9S_MB_2U(SCH_1):PAGE311_I33@PURE_QUANTA.LCMXO3LF9400C5BG484C(CHIPS)':
 'PL11A': CDS_PINID='PL11A';
NODE_NAME     R4581 1
 '@S9S_MB_2U_LIB.S9S_MB_2U(SCH_1):PAGE184_I1@PURE_QUANTA.Q_RES(CHIPS)':
 'A': CDS_PINID='A';
NODE_NAME     R4580 2
 '@S9S_MB_2U_LIB.S9S_MB_2U(SCH_1):PAGE184_I5@PURE_QUANTA.Q_RES(CHIPS)':
 'B': CDS_PINID='B';
NET_NAME
'FM_BOARD_SKU_ID0'
 '@S9S_MB_2U_LIB.S9S_MB_2U(SCH_1):FM_BOARD_SKU_ID0':
 C_SIGNAL='@s9s_mb_2u_lib.s9s_mb_2u(sch_1):fm_board_sku_id0';
NODE_NAME     U4 AA10
 '@S9S_MB_2U_LIB.S9S_MB_2U(SCH_1):PAGE176_I22@PURE_QUANTA.EMMITSBURG_REV0P9(CHIPS)':
 'GPP_M_3': CDS_PINID='GPP_M_3';
NODE_NAME     R2243 1
 '@S9S_MB_2U_LIB.S9S_MB_2U(SCH_1):PAGE184_I30@PURE_QUANTA.Q_RES(CHIPS)':
 'A': CDS_PINID='A';
NODE_NAME     R2242 2
 '@S9S_MB_2U_LIB.S9S_MB_2U(SCH_1):PAGE184_I50@PURE_QUANTA.Q_RES(CHIPS)':
 'B': CDS_PINID='B';
NET_NAME
'FM_BOARD_SKU_ID1'
 '@S9S_MB_2U_LIB.S9S_MB_2U(SCH_1):FM_BOARD_SKU_ID1':
 C_SIGNAL='@s9s_mb_2u_lib.s9s_mb_2u(sch_1):fm_board_sku_id1';
NODE_NAME     U4 W7
 '@S9S_MB_2U_LIB.S9S_MB_2U(SCH_1):PAGE176_I22@PURE_QUANTA.EMMITSBURG_REV0P9(CHIPS)':
 'GPP_M_4': CDS_PINID='GPP_M_4';
NODE_NAME     R2241 1
 '@S9S_MB_2U_LIB.S9S_MB_2U(SCH_1):PAGE184_I28@PURE_QUANTA.Q_RES(CHIPS)':
 'A': CDS_PINID='A';
NODE_NAME     R2240 2
 '@S9S_MB_2U_LIB.S9S_MB_2U(SCH_1):PAGE184_I49@PURE_QUANTA.Q_RES(CHIPS)':
 'B': CDS_PINID='B';
NET_NAME
'FM_BOARD_SKU_ID2'
 '@S9S_MB_2U_LIB.S9S_MB_2U(SCH_1):FM_BOARD_SKU_ID2':
 C_SIGNAL='@s9s_mb_2u_lib.s9s_mb_2u(sch_1):fm_board_sku_id2';
NODE_NAME     U4 V8
 '@S9S_MB_2U_LIB.S9S_MB_2U(SCH_1):PAGE176_I22@PURE_QUANTA.EMMITSBURG_REV0P9(CHIPS)':
 'GPP_M_5': CDS_PINID='GPP_M_5';
NODE_NAME     R2980 1
 '@S9S_MB_2U_LIB.S9S_MB_2U(SCH_1):PAGE184_I26@PURE_QUANTA.Q_RES(CHIPS)':
 'A': CDS_PINID='A';
NODE_NAME     R2979 2
 '@S9S_MB_2U_LIB.S9S_MB_2U(SCH_1):PAGE184_I48@PURE_QUANTA.Q_RES(CHIPS)':
 'B': CDS_PINID='B';
NET_NAME
'FM_BOARD_SKU_ID3'
 '@S9S_MB_2U_LIB.S9S_MB_2U(SCH_1):FM_BOARD_SKU_ID3':
 C_SIGNAL='@s9s_mb_2u_lib.s9s_mb_2u(sch_1):fm_board_sku_id3';
NODE_NAME     U4 R10
 '@S9S_MB_2U_LIB.S9S_MB_2U(SCH_1):PAGE176_I22@PURE_QUANTA.EMMITSBURG_REV0P9(CHIPS)':
 'GPP_M_6': CDS_PINID='GPP_M_6';
NODE_NAME     R2977 1
 '@S9S_MB_2U_LIB.S9S_MB_2U(SCH_1):PAGE184_I11@PURE_QUANTA.Q_RES(CHIPS)':
 'A': CDS_PINID='A';
NODE_NAME     R2976 2
 '@S9S_MB_2U_LIB.S9S_MB_2U(SCH_1):PAGE184_I13@PURE_QUANTA.Q_RES(CHIPS)':
 'B': CDS_PINID='B';
NET_NAME
'FM_BOARD_SKU_ID4'
 '@S9S_MB_2U_LIB.S9S_MB_2U(SCH_1):FM_BOARD_SKU_ID4':
 C_SIGNAL='@s9s_mb_2u_lib.s9s_mb_2u(sch_1):fm_board_sku_id4';
NODE_NAME     U4 AB11
 '@S9S_MB_2U_LIB.S9S_MB_2U(SCH_1):PAGE176_I22@PURE_QUANTA.EMMITSBURG_REV0P9(CHIPS)':
 'GPP_M_7': CDS_PINID='GPP_M_7';
NODE_NAME     R2235 1
 '@S9S_MB_2U_LIB.S9S_MB_2U(SCH_1):PAGE184_I9@PURE_QUANTA.Q_RES(CHIPS)':
 'A': CDS_PINID='A';
NODE_NAME     R2234 2
 '@S9S_MB_2U_LIB.S9S_MB_2U(SCH_1):PAGE184_I12@PURE_QUANTA.Q_RES(CHIPS)':
 'B': CDS_PINID='B';
NET_NAME
'FM_CK440Q_DEV_25M_EN'
 '@S9S_MB_2U_LIB.S9S_MB_2U(SCH_1):FM_CK440Q_DEV_25M_EN':
 C_SIGNAL='@s9s_mb_2u_lib.s9s_mb_2u(sch_1):fm_ck440q_dev_25m_en';
NODE_NAME     U13 A1
 '@S9S_MB_2U_LIB.S9S_MB_2U(SCH_1):PAGE197_I180@PURE_QUANTA.9SQ440NQQI8(CHIPS)':
 '25MPG': CDS_PINID='\25mpg\';
NODE_NAME     R1680 2
 '@S9S_MB_2U_LIB.S9S_MB_2U(SCH_1):PAGE197_I252@PURE_QUANTA.Q_RES(CHIPS)':
 'B': CDS_PINID='B';
NODE_NAME     R1483 2
 '@S9S_MB_2U_LIB.S9S_MB_2U(SCH_1):PAGE197_I265@PURE_QUANTA.Q_RES(CHIPS)':
 'B': CDS_PINID='B';
NODE_NAME     R1484 1
 '@S9S_MB_2U_LIB.S9S_MB_2U(SCH_1):PAGE197_I268@PURE_QUANTA.Q_RES(CHIPS)':
 'A': CDS_PINID='A';
NODE_NAME     C1324 1
 '@S9S_MB_2U_LIB.S9S_MB_2U(SCH_1):PAGE197_I286@PURE_QUANTA.Q_CAP(CHIPS)':
 'A': CDS_PINID='A';
NET_NAME
'FM_CK440_MXCK_25M_100M'
 '@S9S_MB_2U_LIB.S9S_MB_2U(SCH_1):FM_CK440_MXCK_25M_100M':
 C_SIGNAL='@s9s_mb_2u_lib.s9s_mb_2u(sch_1):fm_ck440_mxck_25m_100m';
NODE_NAME     U13 B38
 '@S9S_MB_2U_LIB.S9S_MB_2U(SCH_1):PAGE197_I180@PURE_QUANTA.9SQ440NQQI8(CHIPS)':
 'MXCK_SEL_100M#': CDS_PINID='\mxck_sel_100m#\';
NODE_NAME     R1194 2
 '@S9S_MB_2U_LIB.S9S_MB_2U(SCH_1):PAGE197_I277@PURE_QUANTA.Q_RES(CHIPS)':
 'B': CDS_PINID='B';
NODE_NAME     R1196 1
 '@S9S_MB_2U_LIB.S9S_MB_2U(SCH_1):PAGE197_I281@PURE_QUANTA.Q_RES(CHIPS)':
 'A': CDS_PINID='A';
NET_NAME
'FM_CLK_CK440_SS_EN'
 '@S9S_MB_2U_LIB.S9S_MB_2U(SCH_1):FM_CLK_CK440_SS_EN':
 C_SIGNAL='@s9s_mb_2u_lib.s9s_mb_2u(sch_1):fm_clk_ck440_ss_en';
NODE_NAME     U13 A16
 '@S9S_MB_2U_LIB.S9S_MB_2U(SCH_1):PAGE197_I180@PURE_QUANTA.9SQ440NQQI8(CHIPS)':
 'SS_EN_TRI': CDS_PINID='SS_EN_TRI';
NODE_NAME     R1471 2
 '@S9S_MB_2U_LIB.S9S_MB_2U(SCH_1):PAGE197_I267@PURE_QUANTA.Q_RES(CHIPS)':
 'B': CDS_PINID='B';
NODE_NAME     R1502 1
 '@S9S_MB_2U_LIB.S9S_MB_2U(SCH_1):PAGE197_I270@PURE_QUANTA.Q_RES(CHIPS)':
 'A': CDS_PINID='A';
NET_NAME
'FM_CLK_GEN1_OE0_N'
 '@S9S_MB_2U_LIB.S9S_MB_2U(SCH_1):FM_CLK_GEN1_OE0_N':
 C_SIGNAL='@s9s_mb_2u_lib.s9s_mb_2u(sch_1):fm_clk_gen1_oe0_n';
NODE_NAME     U13 B27
 '@S9S_MB_2U_LIB.S9S_MB_2U(SCH_1):PAGE197_I180@PURE_QUANTA.9SQ440NQQI8(CHIPS)':
 'OE0#': CDS_PINID='\oe0#\';
NODE_NAME     R1527 1
 '@S9S_MB_2U_LIB.S9S_MB_2U(SCH_1):PAGE197_I269@PURE_QUANTA.Q_RES(CHIPS)':
 'A': CDS_PINID='A';
NET_NAME
'FM_COMP_P3V3_AUX_ENIN'
 '@S9S_MB_2U_LIB.S9S_MB_2U(SCH_1):FM_COMP_P3V3_AUX_ENIN':
 C_SIGNAL='@s9s_mb_2u_lib.s9s_mb_2u(sch_1):fm_comp_p3v3_aux_enin';
NODE_NAME     R1745 1
 '@S9S_MB_2U_LIB.S9S_MB_2U(SCH_1):PAGE232_I21@PURE_QUANTA.Q_RES(CHIPS)':
 'A': CDS_PINID='A';
NODE_NAME     R1690 2
 '@S9S_MB_2U_LIB.S9S_MB_2U(SCH_1):PAGE232_I22@PURE_QUANTA.Q_RES(CHIPS)':
 'B': CDS_PINID='B';
NODE_NAME     U117 1
 '@S9S_MB_2U_LIB.S9S_MB_2U(SCH_1):PAGE232_I26@PURE_QUANTA.TPS3895ADRYR(CHIPS)':
 'ENABLE': CDS_PINID='ENABLE';
NODE_NAME     U94 1
 '@S9S_MB_2U_LIB.S9S_MB_2U(SCH_1):PAGE232_I27@PURE_QUANTA.ADM1086AKSZREEL7(CHIPS)':
 'ENIN': CDS_PINID='ENIN';
NET_NAME
'FM_COMP_P3V3_AUX_VIN'
 '@S9S_MB_2U_LIB.S9S_MB_2U(SCH_1):FM_COMP_P3V3_AUX_VIN':
 C_SIGNAL='@s9s_mb_2u_lib.s9s_mb_2u(sch_1):fm_comp_p3v3_aux_vin';
NODE_NAME     R1689 1
 '@S9S_MB_2U_LIB.S9S_MB_2U(SCH_1):PAGE232_I16@PURE_QUANTA.Q_RES(CHIPS)':
 'A': CDS_PINID='A';
NODE_NAME     R1688 2
 '@S9S_MB_2U_LIB.S9S_MB_2U(SCH_1):PAGE232_I18@PURE_QUANTA.Q_RES(CHIPS)':
 'B': CDS_PINID='B';
NODE_NAME     R1950 1
 '@S9S_MB_2U_LIB.S9S_MB_2U(SCH_1):PAGE232_I20@PURE_QUANTA.Q_RES(CHIPS)':
 'A': CDS_PINID='A';
NODE_NAME     U117 3
 '@S9S_MB_2U_LIB.S9S_MB_2U(SCH_1):PAGE232_I26@PURE_QUANTA.TPS3895ADRYR(CHIPS)':
 'SENSE': CDS_PINID='SENSE';
NODE_NAME     U94 3
 '@S9S_MB_2U_LIB.S9S_MB_2U(SCH_1):PAGE232_I27@PURE_QUANTA.ADM1086AKSZREEL7(CHIPS)':
 'VIN': CDS_PINID='VIN';
NET_NAME
'FM_COMP_P3V3_AUX_VIN_R'
 '@S9S_MB_2U_LIB.S9S_MB_2U(SCH_1):FM_COMP_P3V3_AUX_VIN_R':
 C_SIGNAL='@s9s_mb_2u_lib.s9s_mb_2u(sch_1):fm_comp_p3v3_aux_vin_r';
NODE_NAME     Q52 D
 '@S9S_MB_2U_LIB.S9S_MB_2U(SCH_1):PAGE232_I14@PURE_QUANTA.MOSFET_NCH_GDS_ESD_PROTECTED(CHIPS)':
 'D': CDS_PINID='D';
NODE_NAME     R1950 2
 '@S9S_MB_2U_LIB.S9S_MB_2U(SCH_1):PAGE232_I20@PURE_QUANTA.Q_RES(CHIPS)':
 'B': CDS_PINID='B';
NET_NAME
'FM_COMP_P3V3_STBY_CEXT'
 '@S9S_MB_2U_LIB.S9S_MB_2U(SCH_1):FM_COMP_P3V3_STBY_CEXT':
 C_SIGNAL='@s9s_mb_2u_lib.s9s_mb_2u(sch_1):fm_comp_p3v3_stby_cext';
NODE_NAME     C1316 1
 '@S9S_MB_2U_LIB.S9S_MB_2U(SCH_1):PAGE232_I47@PURE_QUANTA.Q_CAP(CHIPS)':
 'A': CDS_PINID='A';
NODE_NAME     U117 5
 '@S9S_MB_2U_LIB.S9S_MB_2U(SCH_1):PAGE232_I26@PURE_QUANTA.TPS3895ADRYR(CHIPS)':
 'CT': CDS_PINID='CT';
NODE_NAME     U94 5
 '@S9S_MB_2U_LIB.S9S_MB_2U(SCH_1):PAGE232_I27@PURE_QUANTA.ADM1086AKSZREEL7(CHIPS)':
 'CEXT': CDS_PINID='CEXT';
NET_NAME
'FM_CPU0_PKGID0'
 '@S9S_MB_2U_LIB.S9S_MB_2U(SCH_1):FM_CPU0_PKGID0':
 C_SIGNAL='@s9s_mb_2u_lib.s9s_mb_2u(sch_1):fm_cpu0_pkgid0';
NODE_NAME     U2 BL64
 '@S9S_MB_2U_LIB.S9S_MB_2U(SCH_1):PAGE13_I57@PURE_QUANTA.SOCKET4677_AZIF0045P001C01CS(CHIPS)':
 'PKG_ID0': CDS_PINID='PKG_ID0';
NODE_NAME     R283 2
 '@S9S_MB_2U_LIB.S9S_MB_2U(SCH_1):PAGE119_I147@PURE_QUANTA.Q_RES(CHIPS)':
 'B': CDS_PINID='B';
NODE_NAME     U249 N20
 '@S9S_MB_2U_LIB.S9S_MB_2U(SCH_1):PAGE313_I1@PURE_QUANTA.LCMXO3LF9400C5BG484C(CHIPS)':
 'PR19C': CDS_PINID='PR19C';
NET_NAME
'FM_CPU0_PKGID1'
 '@S9S_MB_2U_LIB.S9S_MB_2U(SCH_1):FM_CPU0_PKGID1':
 C_SIGNAL='@s9s_mb_2u_lib.s9s_mb_2u(sch_1):fm_cpu0_pkgid1';
NODE_NAME     U2 AY63
 '@S9S_MB_2U_LIB.S9S_MB_2U(SCH_1):PAGE13_I57@PURE_QUANTA.SOCKET4677_AZIF0045P001C01CS(CHIPS)':
 'PKG_ID1': CDS_PINID='PKG_ID1';
NODE_NAME     R284 2
 '@S9S_MB_2U_LIB.S9S_MB_2U(SCH_1):PAGE119_I148@PURE_QUANTA.Q_RES(CHIPS)':
 'B': CDS_PINID='B';
NODE_NAME     U249 N19
 '@S9S_MB_2U_LIB.S9S_MB_2U(SCH_1):PAGE313_I1@PURE_QUANTA.LCMXO3LF9400C5BG484C(CHIPS)':
 'PR19D': CDS_PINID='PR19D';
NET_NAME
'FM_CPU0_PKGID2'
 '@S9S_MB_2U_LIB.S9S_MB_2U(SCH_1):FM_CPU0_PKGID2':
 C_SIGNAL='@s9s_mb_2u_lib.s9s_mb_2u(sch_1):fm_cpu0_pkgid2';
NODE_NAME     U2 BN64
 '@S9S_MB_2U_LIB.S9S_MB_2U(SCH_1):PAGE13_I57@PURE_QUANTA.SOCKET4677_AZIF0045P001C01CS(CHIPS)':
 'PKG_ID2': CDS_PINID='PKG_ID2';
NODE_NAME     R285 2
 '@S9S_MB_2U_LIB.S9S_MB_2U(SCH_1):PAGE119_I150@PURE_QUANTA.Q_RES(CHIPS)':
 'B': CDS_PINID='B';
NODE_NAME     U249 R22
 '@S9S_MB_2U_LIB.S9S_MB_2U(SCH_1):PAGE313_I1@PURE_QUANTA.LCMXO3LF9400C5BG484C(CHIPS)':
 'PR20A': CDS_PINID='PR20A';
NET_NAME
'FM_CPU0_PROC_ID0'
 '@S9S_MB_2U_LIB.S9S_MB_2U(SCH_1):FM_CPU0_PROC_ID0':
 C_SIGNAL='@s9s_mb_2u_lib.s9s_mb_2u(sch_1):fm_cpu0_proc_id0';
NODE_NAME     U2 BG72
 '@S9S_MB_2U_LIB.S9S_MB_2U(SCH_1):PAGE13_I57@PURE_QUANTA.SOCKET4677_AZIF0045P001C01CS(CHIPS)':
 'PROC_ID0': CDS_PINID='PROC_ID0';
NODE_NAME     R286 2
 '@S9S_MB_2U_LIB.S9S_MB_2U(SCH_1):PAGE119_I151@PURE_QUANTA.Q_RES(CHIPS)':
 'B': CDS_PINID='B';
NODE_NAME     U249 N17
 '@S9S_MB_2U_LIB.S9S_MB_2U(SCH_1):PAGE313_I1@PURE_QUANTA.LCMXO3LF9400C5BG484C(CHIPS)':
 'PR18C': CDS_PINID='PR18C';
NET_NAME
'FM_CPU0_PROC_ID1'
 '@S9S_MB_2U_LIB.S9S_MB_2U(SCH_1):FM_CPU0_PROC_ID1':
 C_SIGNAL='@s9s_mb_2u_lib.s9s_mb_2u(sch_1):fm_cpu0_proc_id1';
NODE_NAME     U2 BH71
 '@S9S_MB_2U_LIB.S9S_MB_2U(SCH_1):PAGE13_I57@PURE_QUANTA.SOCKET4677_AZIF0045P001C01CS(CHIPS)':
 'PROC_ID1': CDS_PINID='PROC_ID1';
NODE_NAME     R287 2
 '@S9S_MB_2U_LIB.S9S_MB_2U(SCH_1):PAGE119_I152@PURE_QUANTA.Q_RES(CHIPS)':
 'B': CDS_PINID='B';
NODE_NAME     U249 N18
 '@S9S_MB_2U_LIB.S9S_MB_2U(SCH_1):PAGE313_I1@PURE_QUANTA.LCMXO3LF9400C5BG484C(CHIPS)':
 'PR18D': CDS_PINID='PR18D';
NET_NAME
'FM_CPU0_SKTOCC_LVT3_N'
 '@S9S_MB_2U_LIB.S9S_MB_2U(SCH_1):FM_CPU0_SKTOCC_LVT3_N':
 C_SIGNAL='@s9s_mb_2u_lib.s9s_mb_2u(sch_1):fm_cpu0_sktocc_lvt3_n';
NODE_NAME     U2 CG66
 '@S9S_MB_2U_LIB.S9S_MB_2U(SCH_1):PAGE14_I1@PURE_QUANTA.SOCKET4677_AZIF0045P001C01CS(CHIPS)':
 'SKTOCC_N': CDS_PINID='SKTOCC_N';
NODE_NAME     R738 1
 '@S9S_MB_2U_LIB.S9S_MB_2U(SCH_1):PAGE135_I110@PURE_QUANTA.Q_RES(CHIPS)':
 'A': CDS_PINID='A';
NODE_NAME     R1447 1
 '@S9S_MB_2U_LIB.S9S_MB_2U(SCH_1):PAGE211_I68@PURE_QUANTA.Q_RES(CHIPS)':
 'A': CDS_PINID='A';
NET_NAME
'FM_CPU0_SKTOCC_LVT3_PLD_N'
 '@S9S_MB_2U_LIB.S9S_MB_2U(SCH_1):FM_CPU0_SKTOCC_LVT3_PLD_N':
 C_SIGNAL='@s9s_mb_2u_lib.s9s_mb_2u(sch_1):fm_cpu0_sktocc_lvt3_pld_n';
NODE_NAME     R1447 2
 '@S9S_MB_2U_LIB.S9S_MB_2U(SCH_1):PAGE211_I68@PURE_QUANTA.Q_RES(CHIPS)':
 'B': CDS_PINID='B';
NODE_NAME     U249 M16
 '@S9S_MB_2U_LIB.S9S_MB_2U(SCH_1):PAGE313_I1@PURE_QUANTA.LCMXO3LF9400C5BG484C(CHIPS)':
 'PR18A': CDS_PINID='PR18A';
NET_NAME
'FM_CPU0_SKTOCC_N'
 '@S9S_MB_2U_LIB.S9S_MB_2U(SCH_1):FM_CPU0_SKTOCC_N':
 C_SIGNAL='@s9s_mb_2u_lib.s9s_mb_2u(sch_1):fm_cpu0_sktocc_n';
NODE_NAME     U21 6
 '@S9S_MB_2U_LIB.S9S_MB_2U(SCH_1):PAGE135_I58@PURE_QUANTA.NC7SB3157(CHIPS)':
 'S': CDS_PINID='S';
NODE_NAME     U23 2
 '@S9S_MB_2U_LIB.S9S_MB_2U(SCH_1):PAGE135_I96@PURE_QUANTA.74LVC1G02GW(CHIPS)':
 'A': CDS_PINID='A';
NODE_NAME     R740 2
 '@S9S_MB_2U_LIB.S9S_MB_2U(SCH_1):PAGE135_I107@PURE_QUANTA.Q_RES(CHIPS)':
 'B': CDS_PINID='B';
NODE_NAME     R738 2
 '@S9S_MB_2U_LIB.S9S_MB_2U(SCH_1):PAGE135_I110@PURE_QUANTA.Q_RES(CHIPS)':
 'B': CDS_PINID='B';
NET_NAME
'FM_CPU1_PKGID0'
 '@S9S_MB_2U_LIB.S9S_MB_2U(SCH_1):FM_CPU1_PKGID0':
 C_SIGNAL='@s9s_mb_2u_lib.s9s_mb_2u(sch_1):fm_cpu1_pkgid0';
NODE_NAME     U1 BL64
 '@S9S_MB_2U_LIB.S9S_MB_2U(SCH_1):PAGE44_I51@PURE_QUANTA.SOCKET4677_AZIF0045P001C01CS(CHIPS)':
 'PKG_ID0': CDS_PINID='PKG_ID0';
NODE_NAME     R270 2
 '@S9S_MB_2U_LIB.S9S_MB_2U(SCH_1):PAGE119_I93@PURE_QUANTA.Q_RES(CHIPS)':
 'B': CDS_PINID='B';
NODE_NAME     U249 R21
 '@S9S_MB_2U_LIB.S9S_MB_2U(SCH_1):PAGE313_I1@PURE_QUANTA.LCMXO3LF9400C5BG484C(CHIPS)':
 'PR20B': CDS_PINID='PR20B';
NET_NAME
'FM_CPU1_PKGID1'
 '@S9S_MB_2U_LIB.S9S_MB_2U(SCH_1):FM_CPU1_PKGID1':
 C_SIGNAL='@s9s_mb_2u_lib.s9s_mb_2u(sch_1):fm_cpu1_pkgid1';
NODE_NAME     U1 AY63
 '@S9S_MB_2U_LIB.S9S_MB_2U(SCH_1):PAGE44_I51@PURE_QUANTA.SOCKET4677_AZIF0045P001C01CS(CHIPS)':
 'PKG_ID1': CDS_PINID='PKG_ID1';
NODE_NAME     R271 2
 '@S9S_MB_2U_LIB.S9S_MB_2U(SCH_1):PAGE119_I92@PURE_QUANTA.Q_RES(CHIPS)':
 'B': CDS_PINID='B';
NODE_NAME     U249 P22
 '@S9S_MB_2U_LIB.S9S_MB_2U(SCH_1):PAGE313_I1@PURE_QUANTA.LCMXO3LF9400C5BG484C(CHIPS)':
 'PR20C': CDS_PINID='PR20C';
NET_NAME
'FM_CPU1_PKGID2'
 '@S9S_MB_2U_LIB.S9S_MB_2U(SCH_1):FM_CPU1_PKGID2':
 C_SIGNAL='@s9s_mb_2u_lib.s9s_mb_2u(sch_1):fm_cpu1_pkgid2';
NODE_NAME     U1 BN64
 '@S9S_MB_2U_LIB.S9S_MB_2U(SCH_1):PAGE44_I51@PURE_QUANTA.SOCKET4677_AZIF0045P001C01CS(CHIPS)':
 'PKG_ID2': CDS_PINID='PKG_ID2';
NODE_NAME     R272 2
 '@S9S_MB_2U_LIB.S9S_MB_2U(SCH_1):PAGE119_I90@PURE_QUANTA.Q_RES(CHIPS)':
 'B': CDS_PINID='B';
NODE_NAME     U249 P20
 '@S9S_MB_2U_LIB.S9S_MB_2U(SCH_1):PAGE313_I1@PURE_QUANTA.LCMXO3LF9400C5BG484C(CHIPS)':
 'PR20D': CDS_PINID='PR20D';
NET_NAME
'FM_CPU1_PROC_ID0'
 '@S9S_MB_2U_LIB.S9S_MB_2U(SCH_1):FM_CPU1_PROC_ID0':
 C_SIGNAL='@s9s_mb_2u_lib.s9s_mb_2u(sch_1):fm_cpu1_proc_id0';
NODE_NAME     U1 BG72
 '@S9S_MB_2U_LIB.S9S_MB_2U(SCH_1):PAGE44_I51@PURE_QUANTA.SOCKET4677_AZIF0045P001C01CS(CHIPS)':
 'PROC_ID0': CDS_PINID='PROC_ID0';
NODE_NAME     R273 2
 '@S9S_MB_2U_LIB.S9S_MB_2U(SCH_1):PAGE119_I89@PURE_QUANTA.Q_RES(CHIPS)':
 'B': CDS_PINID='B';
NODE_NAME     U249 N22
 '@S9S_MB_2U_LIB.S9S_MB_2U(SCH_1):PAGE313_I1@PURE_QUANTA.LCMXO3LF9400C5BG484C(CHIPS)':
 'PR19A': CDS_PINID='PR19A';
NET_NAME
'FM_CPU1_PROC_ID1'
 '@S9S_MB_2U_LIB.S9S_MB_2U(SCH_1):FM_CPU1_PROC_ID1':
 C_SIGNAL='@s9s_mb_2u_lib.s9s_mb_2u(sch_1):fm_cpu1_proc_id1';
NODE_NAME     U1 BH71
 '@S9S_MB_2U_LIB.S9S_MB_2U(SCH_1):PAGE44_I51@PURE_QUANTA.SOCKET4677_AZIF0045P001C01CS(CHIPS)':
 'PROC_ID1': CDS_PINID='PROC_ID1';
NODE_NAME     R274 2
 '@S9S_MB_2U_LIB.S9S_MB_2U(SCH_1):PAGE119_I88@PURE_QUANTA.Q_RES(CHIPS)':
 'B': CDS_PINID='B';
NODE_NAME     U249 P21
 '@S9S_MB_2U_LIB.S9S_MB_2U(SCH_1):PAGE313_I1@PURE_QUANTA.LCMXO3LF9400C5BG484C(CHIPS)':
 'PR19B': CDS_PINID='PR19B';
NET_NAME
'FM_CPU1_SKTOCC_LVT3_N'
 '@S9S_MB_2U_LIB.S9S_MB_2U(SCH_1):FM_CPU1_SKTOCC_LVT3_N':
 C_SIGNAL='@s9s_mb_2u_lib.s9s_mb_2u(sch_1):fm_cpu1_sktocc_lvt3_n';
NODE_NAME     U1 CG66
 '@S9S_MB_2U_LIB.S9S_MB_2U(SCH_1):PAGE45_I29@PURE_QUANTA.SOCKET4677_AZIF0045P001C01CS(CHIPS)':
 'SKTOCC_N': CDS_PINID='SKTOCC_N';
NODE_NAME     R737 1
 '@S9S_MB_2U_LIB.S9S_MB_2U(SCH_1):PAGE135_I106@PURE_QUANTA.Q_RES(CHIPS)':
 'A': CDS_PINID='A';
NODE_NAME     R1448 1
 '@S9S_MB_2U_LIB.S9S_MB_2U(SCH_1):PAGE211_I62@PURE_QUANTA.Q_RES(CHIPS)':
 'A': CDS_PINID='A';
NET_NAME
'FM_CPU1_SKTOCC_LVT3_PLD_N'
 '@S9S_MB_2U_LIB.S9S_MB_2U(SCH_1):FM_CPU1_SKTOCC_LVT3_PLD_N':
 C_SIGNAL='@s9s_mb_2u_lib.s9s_mb_2u(sch_1):fm_cpu1_sktocc_lvt3_pld_n';
NODE_NAME     R1448 2
 '@S9S_MB_2U_LIB.S9S_MB_2U(SCH_1):PAGE211_I62@PURE_QUANTA.Q_RES(CHIPS)':
 'B': CDS_PINID='B';
NODE_NAME     U249 N16
 '@S9S_MB_2U_LIB.S9S_MB_2U(SCH_1):PAGE313_I1@PURE_QUANTA.LCMXO3LF9400C5BG484C(CHIPS)':
 'PR18B': CDS_PINID='PR18B';
NET_NAME
'FM_CPU1_SKTOCC_N'
 '@S9S_MB_2U_LIB.S9S_MB_2U(SCH_1):FM_CPU1_SKTOCC_N':
 C_SIGNAL='@s9s_mb_2u_lib.s9s_mb_2u(sch_1):fm_cpu1_sktocc_n';
NODE_NAME     U22 6
 '@S9S_MB_2U_LIB.S9S_MB_2U(SCH_1):PAGE135_I71@PURE_QUANTA.NC7SB3157(CHIPS)':
 'S': CDS_PINID='S';
NODE_NAME     U23 1
 '@S9S_MB_2U_LIB.S9S_MB_2U(SCH_1):PAGE135_I96@PURE_QUANTA.74LVC1G02GW(CHIPS)':
 'B': CDS_PINID='B';
NODE_NAME     R737 2
 '@S9S_MB_2U_LIB.S9S_MB_2U(SCH_1):PAGE135_I106@PURE_QUANTA.Q_RES(CHIPS)':
 'B': CDS_PINID='B';
NODE_NAME     R739 2
 '@S9S_MB_2U_LIB.S9S_MB_2U(SCH_1):PAGE135_I109@PURE_QUANTA.Q_RES(CHIPS)':
 'B': CDS_PINID='B';
NET_NAME
'FM_CPU_EN'
 '@S9S_MB_2U_LIB.S9S_MB_2U(SCH_1):FM_CPU_EN':
 C_SIGNAL='@s9s_mb_2u_lib.s9s_mb_2u(sch_1):fm_cpu_en';
NODE_NAME     U23 4
 '@S9S_MB_2U_LIB.S9S_MB_2U(SCH_1):PAGE135_I96@PURE_QUANTA.74LVC1G02GW(CHIPS)':
 'Y': CDS_PINID='Y';
NODE_NAME     R745 1
 '@S9S_MB_2U_LIB.S9S_MB_2U(SCH_1):PAGE135_I97@PURE_QUANTA.Q_RES(CHIPS)':
 'A': CDS_PINID='A';
NET_NAME
'FM_CPU_EN_R'
 '@S9S_MB_2U_LIB.S9S_MB_2U(SCH_1):FM_CPU_EN_R':
 C_SIGNAL='@s9s_mb_2u_lib.s9s_mb_2u(sch_1):fm_cpu_en_r';
NODE_NAME     R745 2
 '@S9S_MB_2U_LIB.S9S_MB_2U(SCH_1):PAGE135_I97@PURE_QUANTA.Q_RES(CHIPS)':
 'B': CDS_PINID='B';
NODE_NAME     U16 4
 '@S9S_MB_2U_LIB.S9S_MB_2U(SCH_1):PAGE135_I115@PURE_QUANTA.74LVC1G66GV(CHIPS)':
 'E': CDS_PINID='E';
NET_NAME
'FM_CPU_FBRK_DEBUG_N'
 '@S9S_MB_2U_LIB.S9S_MB_2U(SCH_1):FM_CPU_FBRK_DEBUG_N':
 C_SIGNAL='@s9s_mb_2u_lib.s9s_mb_2u(sch_1):fm_cpu_fbrk_debug_n';
NODE_NAME     J42 38
 '@S9S_MB_2U_LIB.S9S_MB_2U(SCH_1):PAGE133_I44@PURE_QUANTA.SCONN60_ASP21410801(CHIPS)':
 '38': CDS_PINID='\38\';
NODE_NAME     R780 1
 '@S9S_MB_2U_LIB.S9S_MB_2U(SCH_1):PAGE133_I92@PURE_QUANTA.Q_RES(CHIPS)':
 'A': CDS_PINID='A';
NODE_NAME     R779 2
 '@S9S_MB_2U_LIB.S9S_MB_2U(SCH_1):PAGE133_I95@PURE_QUANTA.Q_RES(CHIPS)':
 'B': CDS_PINID='B';
NODE_NAME     C552 1
 '@S9S_MB_2U_LIB.S9S_MB_2U(SCH_1):PAGE133_I96@PURE_QUANTA.Q_CAP(CHIPS)':
 'A': CDS_PINID='A';
NODE_NAME     R1247 2
 '@S9S_MB_2U_LIB.S9S_MB_2U(SCH_1):PAGE191_I14@PURE_QUANTA.Q_RES(CHIPS)':
 'B': CDS_PINID='B';
NODE_NAME     U84 3
 '@S9S_MB_2U_LIB.S9S_MB_2U(SCH_1):PAGE226_I18@PURE_QUANTA.GTL2014PW(CHIPS)':
 'B1': CDS_PINID='B1';
NET_NAME
'FM_CPU_FBRK_DEBUG_R_N'
 '@S9S_MB_2U_LIB.S9S_MB_2U(SCH_1):FM_CPU_FBRK_DEBUG_R_N':
 C_SIGNAL='@s9s_mb_2u_lib.s9s_mb_2u(sch_1):fm_cpu_fbrk_debug_r_n';
NODE_NAME     U2 AV57
 '@S9S_MB_2U_LIB.S9S_MB_2U(SCH_1):PAGE14_I1@PURE_QUANTA.SOCKET4677_AZIF0045P001C01CS(CHIPS)':
 'FBRK_N': CDS_PINID='FBRK_N';
NODE_NAME     U1 AV57
 '@S9S_MB_2U_LIB.S9S_MB_2U(SCH_1):PAGE45_I29@PURE_QUANTA.SOCKET4677_AZIF0045P001C01CS(CHIPS)':
 'FBRK_N': CDS_PINID='FBRK_N';
NODE_NAME     R780 2
 '@S9S_MB_2U_LIB.S9S_MB_2U(SCH_1):PAGE133_I92@PURE_QUANTA.Q_RES(CHIPS)':
 'B': CDS_PINID='B';
NET_NAME
'FM_CPU_RMCA_CATERR_DLY_LVT3_R_N'
 '@S9S_MB_2U_LIB.S9S_MB_2U(SCH_1):FM_CPU_RMCA_CATERR_DLY_LVT3_R_N':
 C_SIGNAL='@s9s_mb_2u_lib.s9s_mb_2u(sch_1):fm_cpu_rmca_caterr_dly_lvt3_r_n';
NODE_NAME     R1456 1
 '@S9S_MB_2U_LIB.S9S_MB_2U(SCH_1):PAGE193_I28@PURE_QUANTA.Q_RES(CHIPS)':
 'A': CDS_PINID='A';
NODE_NAME     U249 P16
 '@S9S_MB_2U_LIB.S9S_MB_2U(SCH_1):PAGE313_I1@PURE_QUANTA.LCMXO3LF9400C5BG484C(CHIPS)':
 'PR24B': CDS_PINID='PR24B';
NET_NAME
'FM_CPU_RMCA_CATERR_DLY_N'
 '@S9S_MB_2U_LIB.S9S_MB_2U(SCH_1):FM_CPU_RMCA_CATERR_DLY_N':
 C_SIGNAL='@s9s_mb_2u_lib.s9s_mb_2u(sch_1):fm_cpu_rmca_caterr_dly_n';
NODE_NAME     U4 AF4
 '@S9S_MB_2U_LIB.S9S_MB_2U(SCH_1):PAGE175_I93@PURE_QUANTA.EMMITSBURG_REV0P9(CHIPS)':
 'GPP_D_18_MEMTRIP_N': CDS_PINID='GPP_D_18_MEMTRIP_N';
NODE_NAME     R1456 2
 '@S9S_MB_2U_LIB.S9S_MB_2U(SCH_1):PAGE193_I28@PURE_QUANTA.Q_RES(CHIPS)':
 'B': CDS_PINID='B';
NET_NAME
'FM_CPU_RMCA_CATERR_LVT3_R_N'
 '@S9S_MB_2U_LIB.S9S_MB_2U(SCH_1):FM_CPU_RMCA_CATERR_LVT3_R_N':
 C_SIGNAL='@s9s_mb_2u_lib.s9s_mb_2u(sch_1):fm_cpu_rmca_caterr_lvt3_r_n';
NODE_NAME     U249 AA8
 '@S9S_MB_2U_LIB.S9S_MB_2U(SCH_1):PAGE312_I1@PURE_QUANTA.LCMXO3LF9400C5BG484C(CHIPS)':
 'PB18A': CDS_PINID='PB18A';
NODE_NAME     R365 1
 '@S9S_MB_2U_LIB.S9S_MB_2U(SCH_1):PAGE207_I273@PURE_QUANTA.Q_RES(CHIPS)':
 'A': CDS_PINID='A';
NODE_NAME     R1841 2
 '@S9S_MB_2U_LIB.S9S_MB_2U(SCH_1):PAGE207_I275@PURE_QUANTA.Q_RES(CHIPS)':
 'B': CDS_PINID='B';
NODE_NAME     R1558 1
 '@S9S_MB_2U_LIB.S9S_MB_2U(SCH_1):PAGE209_I15@PURE_QUANTA.Q_RES(CHIPS)':
 'A': CDS_PINID='A';
NET_NAME
'FM_DB2000_10_OE_N'
 '@S9S_MB_2U_LIB.S9S_MB_2U(SCH_1):FM_DB2000_10_OE_N':
 C_SIGNAL='@s9s_mb_2u_lib.s9s_mb_2u(sch_1):fm_db2000_10_oe_n';
NODE_NAME     U38 E11
 '@S9S_MB_2U_LIB.S9S_MB_2U(SCH_1):PAGE195_I119@PURE_QUANTA.9QXL2001BNHGI8(CHIPS)':
 'VOE10#||SHFT_LD#': CDS_PINID='\voe10#||shft_ld#\';
NODE_NAME     R2562 2
 '@S9S_MB_2U_LIB.S9S_MB_2U(SCH_1):PAGE195_I535@PURE_QUANTA.Q_RES(CHIPS)':
 'B': CDS_PINID='B';
NET_NAME
'FM_DB2000_11_OE_N'
 '@S9S_MB_2U_LIB.S9S_MB_2U(SCH_1):FM_DB2000_11_OE_N':
 C_SIGNAL='@s9s_mb_2u_lib.s9s_mb_2u(sch_1):fm_db2000_11_oe_n';
NODE_NAME     U38 C11
 '@S9S_MB_2U_LIB.S9S_MB_2U(SCH_1):PAGE195_I119@PURE_QUANTA.9QXL2001BNHGI8(CHIPS)':
 'VOE11#': CDS_PINID='\voe11#\';
NODE_NAME     R3636 2
 '@S9S_MB_2U_LIB.S9S_MB_2U(SCH_1):PAGE195_I536@PURE_QUANTA.Q_RES(CHIPS)':
 'B': CDS_PINID='B';
NET_NAME
'FM_DB2000_12_OE_N'
 '@S9S_MB_2U_LIB.S9S_MB_2U(SCH_1):FM_DB2000_12_OE_N':
 C_SIGNAL='@s9s_mb_2u_lib.s9s_mb_2u(sch_1):fm_db2000_12_oe_n';
NODE_NAME     U38 B10
 '@S9S_MB_2U_LIB.S9S_MB_2U(SCH_1):PAGE195_I119@PURE_QUANTA.9QXL2001BNHGI8(CHIPS)':
 'VOE12#': CDS_PINID='\voe12#\';
NODE_NAME     R3637 2
 '@S9S_MB_2U_LIB.S9S_MB_2U(SCH_1):PAGE195_I537@PURE_QUANTA.Q_RES(CHIPS)':
 'B': CDS_PINID='B';
NET_NAME
'FM_DB2000_1_OE_N'
 '@S9S_MB_2U_LIB.S9S_MB_2U(SCH_1):FM_DB2000_1_OE_N':
 C_SIGNAL='@s9s_mb_2u_lib.s9s_mb_2u(sch_1):fm_db2000_1_oe_n';
NODE_NAME     U38 L8
 '@S9S_MB_2U_LIB.S9S_MB_2U(SCH_1):PAGE195_I119@PURE_QUANTA.9QXL2001BNHGI8(CHIPS)':
 'VOE5#||DATA': CDS_PINID='\voe5#||data\';
NODE_NAME     U38 L10
 '@S9S_MB_2U_LIB.S9S_MB_2U(SCH_1):PAGE195_I119@PURE_QUANTA.9QXL2001BNHGI8(CHIPS)':
 'VOE6#||CLK': CDS_PINID='\voe6#||clk\';
NODE_NAME     U38 K11
 '@S9S_MB_2U_LIB.S9S_MB_2U(SCH_1):PAGE195_I119@PURE_QUANTA.9QXL2001BNHGI8(CHIPS)':
 'VOE7#': CDS_PINID='\voe7#\';
NODE_NAME     R576 2
 '@S9S_MB_2U_LIB.S9S_MB_2U(SCH_1):PAGE195_I156@PURE_QUANTA.Q_RES(CHIPS)':
 'B': CDS_PINID='B';
NET_NAME
'FM_DB2000_8_OE_N'
 '@S9S_MB_2U_LIB.S9S_MB_2U(SCH_1):FM_DB2000_8_OE_N':
 C_SIGNAL='@s9s_mb_2u_lib.s9s_mb_2u(sch_1):fm_db2000_8_oe_n';
NODE_NAME     U38 H11
 '@S9S_MB_2U_LIB.S9S_MB_2U(SCH_1):PAGE195_I119@PURE_QUANTA.9QXL2001BNHGI8(CHIPS)':
 'VOE8#': CDS_PINID='\voe8#\';
NODE_NAME     R4534 2
 '@S9S_MB_2U_LIB.S9S_MB_2U(SCH_1):PAGE195_I487@PURE_QUANTA.Q_RES(CHIPS)':
 'B': CDS_PINID='B';
NET_NAME
'FM_DB2000_9_OE_N'
 '@S9S_MB_2U_LIB.S9S_MB_2U(SCH_1):FM_DB2000_9_OE_N':
 C_SIGNAL='@s9s_mb_2u_lib.s9s_mb_2u(sch_1):fm_db2000_9_oe_n';
NODE_NAME     U38 E12
 '@S9S_MB_2U_LIB.S9S_MB_2U(SCH_1):PAGE195_I119@PURE_QUANTA.9QXL2001BNHGI8(CHIPS)':
 'VOE9#': CDS_PINID='\voe9#\';
NODE_NAME     R1543 2
 '@S9S_MB_2U_LIB.S9S_MB_2U(SCH_1):PAGE195_I534@PURE_QUANTA.Q_RES(CHIPS)':
 'B': CDS_PINID='B';
NET_NAME
'FM_DB2000_DEV_EN'
 '@S9S_MB_2U_LIB.S9S_MB_2U(SCH_1):FM_DB2000_DEV_EN':
 C_SIGNAL='@s9s_mb_2u_lib.s9s_mb_2u(sch_1):fm_db2000_dev_en';
NODE_NAME     U38 M6
 '@S9S_MB_2U_LIB.S9S_MB_2U(SCH_1):PAGE195_I119@PURE_QUANTA.9QXL2001BNHGI8(CHIPS)':
 'VCKPWRGD_PD#': CDS_PINID='\vckpwrgd_pd#\';
NODE_NAME     R575 2
 '@S9S_MB_2U_LIB.S9S_MB_2U(SCH_1):PAGE195_I199@PURE_QUANTA.Q_RES(CHIPS)':
 'B': CDS_PINID='B';
NET_NAME
'FM_DB2000_OE_N'
 '@S9S_MB_2U_LIB.S9S_MB_2U(SCH_1):FM_DB2000_OE_N':
 C_SIGNAL='@s9s_mb_2u_lib.s9s_mb_2u(sch_1):fm_db2000_oe_n';
NODE_NAME     R576 1
 '@S9S_MB_2U_LIB.S9S_MB_2U(SCH_1):PAGE195_I156@PURE_QUANTA.Q_RES(CHIPS)':
 'A': CDS_PINID='A';
NODE_NAME     R113 2
 '@S9S_MB_2U_LIB.S9S_MB_2U(SCH_1):PAGE212_I27@PURE_QUANTA.Q_RES(CHIPS)':
 'B': CDS_PINID='B';
NET_NAME
'FM_DB2000_VSBEN'
 '@S9S_MB_2U_LIB.S9S_MB_2U(SCH_1):FM_DB2000_VSBEN':
 C_SIGNAL='@s9s_mb_2u_lib.s9s_mb_2u(sch_1):fm_db2000_vsben';
NODE_NAME     U38 E2
 '@S9S_MB_2U_LIB.S9S_MB_2U(SCH_1):PAGE195_I119@PURE_QUANTA.9QXL2001BNHGI8(CHIPS)':
 'VSBEN': CDS_PINID='VSBEN';
NODE_NAME     R573 2
 '@S9S_MB_2U_LIB.S9S_MB_2U(SCH_1):PAGE195_I194@PURE_QUANTA.Q_RES(CHIPS)':
 'B': CDS_PINID='B';
NODE_NAME     R574 1
 '@S9S_MB_2U_LIB.S9S_MB_2U(SCH_1):PAGE195_I197@PURE_QUANTA.Q_RES(CHIPS)':
 'A': CDS_PINID='A';
NET_NAME
'FM_DEBUG_PORT_PRSNT_N'
 '@S9S_MB_2U_LIB.S9S_MB_2U(SCH_1):FM_DEBUG_PORT_PRSNT_N':
 C_SIGNAL='@s9s_mb_2u_lib.s9s_mb_2u(sch_1):fm_debug_port_prsnt_n';
NODE_NAME     U249 AB9
 '@S9S_MB_2U_LIB.S9S_MB_2U(SCH_1):PAGE312_I1@PURE_QUANTA.LCMXO3LF9400C5BG484C(CHIPS)':
 'PB19B': CDS_PINID='PB19B';
NODE_NAME     R2348 1
 '@S9S_MB_2U_LIB.S9S_MB_2U(SCH_1):PAGE312_I184@PURE_QUANTA.Q_RES(CHIPS)':
 'A': CDS_PINID='A';
NET_NAME
'FM_DEBUG_PORT_PRSNT_R_N'
 '@S9S_MB_2U_LIB.S9S_MB_2U(SCH_1):FM_DEBUG_PORT_PRSNT_R_N':
 C_SIGNAL='@s9s_mb_2u_lib.s9s_mb_2u(sch_1):fm_debug_port_prsnt_r_n';
NODE_NAME     U4 BA36
 '@S9S_MB_2U_LIB.S9S_MB_2U(SCH_1):PAGE176_I22@PURE_QUANTA.EMMITSBURG_REV0P9(CHIPS)':
 'GPP_E_17_ERR0_N': CDS_PINID='GPP_E_17_ERR0_N';
NODE_NAME     R2342 2
 '@S9S_MB_2U_LIB.S9S_MB_2U(SCH_1):PAGE192_I75@PURE_QUANTA.Q_RES(CHIPS)':
 'B': CDS_PINID='B';
NODE_NAME     R2348 2
 '@S9S_MB_2U_LIB.S9S_MB_2U(SCH_1):PAGE312_I184@PURE_QUANTA.Q_RES(CHIPS)':
 'B': CDS_PINID='B';
NET_NAME
'FM_DIMM_12V_CPS_SX_N'
 '@S9S_MB_2U_LIB.S9S_MB_2U(SCH_1):FM_DIMM_12V_CPS_SX_N':
 C_SIGNAL='@s9s_mb_2u_lib.s9s_mb_2u(sch_1):fm_dimm_12v_cps_sx_n';
NODE_NAME     U249 W15
 '@S9S_MB_2U_LIB.S9S_MB_2U(SCH_1):PAGE312_I1@PURE_QUANTA.LCMXO3LF9400C5BG484C(CHIPS)':
 'PB35D': CDS_PINID='PB35D';
NODE_NAME     R736 1
 '@S9S_MB_2U_LIB.S9S_MB_2U(SCH_1):PAGE209_I11@PURE_QUANTA.Q_RES(CHIPS)':
 'A': CDS_PINID='A';
NODE_NAME     R735 2
 '@S9S_MB_2U_LIB.S9S_MB_2U(SCH_1):PAGE209_I13@PURE_QUANTA.Q_RES(CHIPS)':
 'B': CDS_PINID='B';
NET_NAME
'FM_DIS_PS_PWROK_DLY'
 '@S9S_MB_2U_LIB.S9S_MB_2U(SCH_1):FM_DIS_PS_PWROK_DLY':
 C_SIGNAL='@s9s_mb_2u_lib.s9s_mb_2u(sch_1):fm_dis_ps_pwrok_dly';
NODE_NAME     U249 AA7
 '@S9S_MB_2U_LIB.S9S_MB_2U(SCH_1):PAGE312_I1@PURE_QUANTA.LCMXO3LF9400C5BG484C(CHIPS)':
 'PB13A': CDS_PINID='PB13A';
NODE_NAME     R1494 1
 '@S9S_MB_2U_LIB.S9S_MB_2U(SCH_1):PAGE209_I21@PURE_QUANTA.Q_RES(CHIPS)':
 'A': CDS_PINID='A';
NODE_NAME     R1492 1
 '@S9S_MB_2U_LIB.S9S_MB_2U(SCH_1):PAGE209_I35@PURE_QUANTA.Q_RES(CHIPS)':
 'A': CDS_PINID='A';
NET_NAME
'FM_ESPI_CS_SWIZZLE'
 '@S9S_MB_2U_LIB.S9S_MB_2U(SCH_1):FM_ESPI_CS_SWIZZLE':
 C_SIGNAL='@s9s_mb_2u_lib.s9s_mb_2u(sch_1):fm_espi_cs_swizzle';
NODE_NAME     U4 BB8
 '@S9S_MB_2U_LIB.S9S_MB_2U(SCH_1):PAGE177_I27@PURE_QUANTA.EMMITSBURG_REV0P9(CHIPS)':
 'GPPC_S_11': CDS_PINID='GPPC_S_11';
NODE_NAME     R609 2
 '@S9S_MB_2U_LIB.S9S_MB_2U(SCH_1):PAGE187_I39@PURE_QUANTA.Q_RES(CHIPS)':
 'B': CDS_PINID='B';
NODE_NAME     R610 1
 '@S9S_MB_2U_LIB.S9S_MB_2U(SCH_1):PAGE187_I40@PURE_QUANTA.Q_RES(CHIPS)':
 'A': CDS_PINID='A';
NET_NAME
'FM_ESPI_FLASH_MODE'
 '@S9S_MB_2U_LIB.S9S_MB_2U(SCH_1):FM_ESPI_FLASH_MODE':
 C_SIGNAL='@s9s_mb_2u_lib.s9s_mb_2u(sch_1):fm_espi_flash_mode';
NODE_NAME     U4 AG1
 '@S9S_MB_2U_LIB.S9S_MB_2U(SCH_1):PAGE175_I93@PURE_QUANTA.EMMITSBURG_REV0P9(CHIPS)':
 'GPP_D_7': CDS_PINID='GPP_D_7';
NODE_NAME     R607 2
 '@S9S_MB_2U_LIB.S9S_MB_2U(SCH_1):PAGE187_I21@PURE_QUANTA.Q_RES(CHIPS)':
 'B': CDS_PINID='B';
NODE_NAME     R608 1
 '@S9S_MB_2U_LIB.S9S_MB_2U(SCH_1):PAGE187_I36@PURE_QUANTA.Q_RES(CHIPS)':
 'A': CDS_PINID='A';
NET_NAME
'FM_ESPI_PLD_EN'
 '@S9S_MB_2U_LIB.S9S_MB_2U(SCH_1):FM_ESPI_PLD_EN':
 C_SIGNAL='@s9s_mb_2u_lib.s9s_mb_2u(sch_1):fm_espi_pld_en';
NODE_NAME     U60 6
 '@S9S_MB_2U_LIB.S9S_MB_2U(SCH_1):PAGE190_I34@PURE_QUANTA.NC7SB3157(CHIPS)':
 'S': CDS_PINID='S';
NODE_NAME     U61 6
 '@S9S_MB_2U_LIB.S9S_MB_2U(SCH_1):PAGE190_I39@PURE_QUANTA.NC7SB3157(CHIPS)':
 'S': CDS_PINID='S';
NODE_NAME     R1748 1
 '@S9S_MB_2U_LIB.S9S_MB_2U(SCH_1):PAGE190_I54@PURE_QUANTA.Q_RES(CHIPS)':
 'A': CDS_PINID='A';
NET_NAME
'FM_ESPI_PLD_R1_EN'
 '@S9S_MB_2U_LIB.S9S_MB_2U(SCH_1):FM_ESPI_PLD_R1_EN':
 C_SIGNAL='@s9s_mb_2u_lib.s9s_mb_2u(sch_1):fm_espi_pld_r1_en';
NODE_NAME     R1749 1
 '@S9S_MB_2U_LIB.S9S_MB_2U(SCH_1):PAGE190_I89@PURE_QUANTA.Q_RES(CHIPS)':
 'A': CDS_PINID='A';
NODE_NAME     R2132 2
 '@S9S_MB_2U_LIB.S9S_MB_2U(SCH_1):PAGE190_I91@PURE_QUANTA.Q_RES(CHIPS)':
 'B': CDS_PINID='B';
NODE_NAME     R2451 2
 '@S9S_MB_2U_LIB.S9S_MB_2U(SCH_1):PAGE190_I94@PURE_QUANTA.Q_RES(CHIPS)':
 'B': CDS_PINID='B';
NODE_NAME     R2452 2
 '@S9S_MB_2U_LIB.S9S_MB_2U(SCH_1):PAGE313_I84@PURE_QUANTA.Q_RES(CHIPS)':
 'B': CDS_PINID='B';
NODE_NAME     U154 2
 '@S9S_MB_2U_LIB.S9S_MB_2U(SCH_1):PAGE190_I95@PURE_QUANTA.74LVC1G07SE7(CHIPS)':
 'A': CDS_PINID='A';
NET_NAME
'FM_ESPI_PLD_R_EN'
 '@S9S_MB_2U_LIB.S9S_MB_2U(SCH_1):FM_ESPI_PLD_R_EN':
 C_SIGNAL='@s9s_mb_2u_lib.s9s_mb_2u(sch_1):fm_espi_pld_r_en';
NODE_NAME     U249 G19
 '@S9S_MB_2U_LIB.S9S_MB_2U(SCH_1):PAGE313_I1@PURE_QUANTA.LCMXO3LF9400C5BG484C(CHIPS)':
 'PR6C': CDS_PINID='PR6C';
NODE_NAME     R2452 1
 '@S9S_MB_2U_LIB.S9S_MB_2U(SCH_1):PAGE313_I84@PURE_QUANTA.Q_RES(CHIPS)':
 'A': CDS_PINID='A';
NET_NAME
'FM_ESPI_PLD_R_EN_BUF'
 '@S9S_MB_2U_LIB.S9S_MB_2U(SCH_1):FM_ESPI_PLD_R_EN_BUF':
 C_SIGNAL='@s9s_mb_2u_lib.s9s_mb_2u(sch_1):fm_espi_pld_r_en_buf';
NODE_NAME     R1748 2
 '@S9S_MB_2U_LIB.S9S_MB_2U(SCH_1):PAGE190_I54@PURE_QUANTA.Q_RES(CHIPS)':
 'B': CDS_PINID='B';
NODE_NAME     R1750 2
 '@S9S_MB_2U_LIB.S9S_MB_2U(SCH_1):PAGE190_I87@PURE_QUANTA.Q_RES(CHIPS)':
 'B': CDS_PINID='B';
NODE_NAME     U154 4
 '@S9S_MB_2U_LIB.S9S_MB_2U(SCH_1):PAGE190_I95@PURE_QUANTA.74LVC1G07SE7(CHIPS)':
 'Y': CDS_PINID='Y';
NODE_NAME     R4177 2
 '@S9S_MB_2U_LIB.S9S_MB_2U(SCH_1):PAGE243_I19@PURE_QUANTA.Q_RES(CHIPS)':
 'B': CDS_PINID='B';
NET_NAME
'FM_ESPI_PLD_R_EN_BUF_R'
 '@S9S_MB_2U_LIB.S9S_MB_2U(SCH_1):FM_ESPI_PLD_R_EN_BUF_R':
 C_SIGNAL='@s9s_mb_2u_lib.s9s_mb_2u(sch_1):fm_espi_pld_r_en_buf_r';
NODE_NAME     U307 G
 '@S9S_MB_2U_LIB.S9S_MB_2U(SCH_1):PAGE243_I15@PURE_QUANTA.MOSFET_N(CHIPS)':
 'GATE': CDS_PINID='GATE';
NODE_NAME     R4177 1
 '@S9S_MB_2U_LIB.S9S_MB_2U(SCH_1):PAGE243_I19@PURE_QUANTA.Q_RES(CHIPS)':
 'A': CDS_PINID='A';
NET_NAME
'FM_EUP_LOT6_N'
 '@S9S_MB_2U_LIB.S9S_MB_2U(SCH_1):FM_EUP_LOT6_N':
 C_SIGNAL='@s9s_mb_2u_lib.s9s_mb_2u(sch_1):fm_eup_lot6_n';
NODE_NAME     U4 AR13
 '@S9S_MB_2U_LIB.S9S_MB_2U(SCH_1):PAGE177_I27@PURE_QUANTA.EMMITSBURG_REV0P9(CHIPS)':
 'GPPC_S_6_SUSWARN_N_SUSPWRDNACK': CDS_PINID='GPPC_S_6_SUSWARN_N_SUSPWRDNACK';
NODE_NAME     R1461 1
 '@S9S_MB_2U_LIB.S9S_MB_2U(SCH_1):PAGE177_I80@PURE_QUANTA.Q_RES(CHIPS)':
 'A': CDS_PINID='A';
NET_NAME
'FM_FAN_PWR_EN'
 '@S9S_MB_2U_LIB.S9S_MB_2U(SCH_1):FM_FAN_PWR_EN':
 C_SIGNAL='@s9s_mb_2u_lib.s9s_mb_2u(sch_1):fm_fan_pwr_en';
NODE_NAME     U249 B2
 '@S9S_MB_2U_LIB.S9S_MB_2U(SCH_1):PAGE314_I188@PURE_QUANTA.LCMXO3LF9400C5BG484C(CHIPS)':
 'PT10A': CDS_PINID='PT10A';
NODE_NAME     R2803 2
 '@S9S_MB_2U_LIB.S9S_MB_2U(SCH_1):PAGE233_I38@PURE_QUANTA.Q_RES(CHIPS)':
 'B': CDS_PINID='B';
NODE_NAME     R4701 2
 '@S9S_MB_2U_LIB.S9S_MB_2U(SCH_1):PAGE233_I41@PURE_QUANTA.Q_RES(CHIPS)':
 'B': CDS_PINID='B';
NET_NAME
'FM_FAN_PWR_EN_R'
 '@S9S_MB_2U_LIB.S9S_MB_2U(SCH_1):FM_FAN_PWR_EN_R':
 C_SIGNAL='@s9s_mb_2u_lib.s9s_mb_2u(sch_1):fm_fan_pwr_en_r';
NODE_NAME     J45 D1
 '@S9S_MB_2U_LIB.S9S_MB_2U(SCH_1):PAGE233_I12@PURE_QUANTA.CONN60_101062636003K02LF(CHIPS)':
 'D1': CDS_PINID='D1';
NODE_NAME     R2803 1
 '@S9S_MB_2U_LIB.S9S_MB_2U(SCH_1):PAGE233_I38@PURE_QUANTA.Q_RES(CHIPS)':
 'A': CDS_PINID='A';
NODE_NAME     C2296 1
 '@S9S_MB_2U_LIB.S9S_MB_2U(SCH_1):PAGE233_I53@PURE_QUANTA.Q_CAP(CHIPS)':
 'A': CDS_PINID='A';
NET_NAME
'FM_FLASH_SECURITY_STRAP'
 '@S9S_MB_2U_LIB.S9S_MB_2U(SCH_1):FM_FLASH_SECURITY_STRAP':
 C_SIGNAL='@s9s_mb_2u_lib.s9s_mb_2u(sch_1):fm_flash_security_strap';
NODE_NAME     U4 AJ1
 '@S9S_MB_2U_LIB.S9S_MB_2U(SCH_1):PAGE175_I93@PURE_QUANTA.EMMITSBURG_REV0P9(CHIPS)':
 'GPP_D_6': CDS_PINID='GPP_D_6';
NODE_NAME     R380 2
 '@S9S_MB_2U_LIB.S9S_MB_2U(SCH_1):PAGE186_I78@PURE_QUANTA.Q_RES(CHIPS)':
 'B': CDS_PINID='B';
NODE_NAME     R381 1
 '@S9S_MB_2U_LIB.S9S_MB_2U(SCH_1):PAGE186_I81@PURE_QUANTA.Q_RES(CHIPS)':
 'A': CDS_PINID='A';
NODE_NAME     J104 10
 '@S9S_MB_2U_LIB.S9S_MB_2U(SCH_1):PAGE189_I134@PURE_QUANTA.CONN14_210HP207GBR1(CHIPS)':
 '10': CDS_PINID='\10\';
NET_NAME
'FM_FORCE_PWRON_LVC3'
 '@S9S_MB_2U_LIB.S9S_MB_2U(SCH_1):FM_FORCE_PWRON_LVC3':
 C_SIGNAL='@s9s_mb_2u_lib.s9s_mb_2u(sch_1):fm_force_pwron_lvc3';
NODE_NAME     U249 U10
 '@S9S_MB_2U_LIB.S9S_MB_2U(SCH_1):PAGE312_I1@PURE_QUANTA.LCMXO3LF9400C5BG484C(CHIPS)':
 'PB19D': CDS_PINID='PB19D';
NODE_NAME     JP15 2
 '@S9S_MB_2U_LIB.S9S_MB_2U(SCH_1):PAGE312_I187@PURE_QUANTA.CONN3_210HP1030BR1(CHIPS)':
 '2': CDS_PINID='\2\';
NET_NAME
'FM_G751_0_ALERT_N'
 '@S9S_MB_2U_LIB.S9S_MB_2U(SCH_1):FM_G751_0_ALERT_N':
 C_SIGNAL='@s9s_mb_2u_lib.s9s_mb_2u(sch_1):fm_g751_0_alert_n';
NODE_NAME     R4215 2
 '@S9S_MB_2U_LIB.S9S_MB_2U(SCH_1):PAGE161_I79@PURE_QUANTA.Q_RES(CHIPS)':
 'B': CDS_PINID='B';
NODE_NAME     U270 3
 '@S9S_MB_2U_LIB.S9S_MB_2U(SCH_1):PAGE161_I164@PURE_QUANTA.LM75BD(CHIPS)':
 'OS': CDS_PINID='OS';
NET_NAME
'FM_G751_1_ALERT_N'
 '@S9S_MB_2U_LIB.S9S_MB_2U(SCH_1):FM_G751_1_ALERT_N':
 C_SIGNAL='@s9s_mb_2u_lib.s9s_mb_2u(sch_1):fm_g751_1_alert_n';
NODE_NAME     R4214 2
 '@S9S_MB_2U_LIB.S9S_MB_2U(SCH_1):PAGE161_I108@PURE_QUANTA.Q_RES(CHIPS)':
 'B': CDS_PINID='B';
NODE_NAME     U271 3
 '@S9S_MB_2U_LIB.S9S_MB_2U(SCH_1):PAGE161_I165@PURE_QUANTA.LM75BD(CHIPS)':
 'OS': CDS_PINID='OS';
NET_NAME
'FM_GPU_HSC_EN'
 '@S9S_MB_2U_LIB.S9S_MB_2U(SCH_1):FM_GPU_HSC_EN':
 C_SIGNAL='@s9s_mb_2u_lib.s9s_mb_2u(sch_1):fm_gpu_hsc_en';
NODE_NAME     R2940 2
 '@S9S_MB_2U_LIB.S9S_MB_2U(SCH_1):PAGE230_I28@PURE_QUANTA.Q_RES(CHIPS)':
 'B': CDS_PINID='B';
NODE_NAME     R2941 1
 '@S9S_MB_2U_LIB.S9S_MB_2U(SCH_1):PAGE230_I29@PURE_QUANTA.Q_RES(CHIPS)':
 'A': CDS_PINID='A';
NODE_NAME     U278 1
 '@S9S_MB_2U_LIB.S9S_MB_2U(SCH_1):PAGE230_I31@PURE_QUANTA.74LVC1G08W57(CHIPS)':
 'A': CDS_PINID='A';
NODE_NAME     R2939 2
 '@S9S_MB_2U_LIB.S9S_MB_2U(SCH_1):PAGE314_I106@PURE_QUANTA.Q_RES(CHIPS)':
 'B': CDS_PINID='B';
NET_NAME
'FM_GPU_HSC_EN_BUF'
 '@S9S_MB_2U_LIB.S9S_MB_2U(SCH_1):FM_GPU_HSC_EN_BUF':
 C_SIGNAL='@s9s_mb_2u_lib.s9s_mb_2u(sch_1):fm_gpu_hsc_en_buf';
NODE_NAME     R2944 2
 '@S9S_MB_2U_LIB.S9S_MB_2U(SCH_1):PAGE230_I24@PURE_QUANTA.Q_RES(CHIPS)':
 'B': CDS_PINID='B';
NODE_NAME     R2906 2
 '@S9S_MB_2U_LIB.S9S_MB_2U(SCH_1):PAGE233_I37@PURE_QUANTA.Q_RES(CHIPS)':
 'B': CDS_PINID='B';
NET_NAME
'FM_GPU_HSC_EN_BUF_R'
 '@S9S_MB_2U_LIB.S9S_MB_2U(SCH_1):FM_GPU_HSC_EN_BUF_R':
 C_SIGNAL='@s9s_mb_2u_lib.s9s_mb_2u(sch_1):fm_gpu_hsc_en_buf_r';
NODE_NAME     R2944 1
 '@S9S_MB_2U_LIB.S9S_MB_2U(SCH_1):PAGE230_I24@PURE_QUANTA.Q_RES(CHIPS)':
 'A': CDS_PINID='A';
NODE_NAME     R2946 2
 '@S9S_MB_2U_LIB.S9S_MB_2U(SCH_1):PAGE230_I25@PURE_QUANTA.Q_RES(CHIPS)':
 'B': CDS_PINID='B';
NODE_NAME     R2948 1
 '@S9S_MB_2U_LIB.S9S_MB_2U(SCH_1):PAGE230_I30@PURE_QUANTA.Q_RES(CHIPS)':
 'A': CDS_PINID='A';
NODE_NAME     U278 4
 '@S9S_MB_2U_LIB.S9S_MB_2U(SCH_1):PAGE230_I31@PURE_QUANTA.74LVC1G08W57(CHIPS)':
 'Y': CDS_PINID='Y';
NET_NAME
'FM_GPU_HSC_EN_BUF_R1'
 '@S9S_MB_2U_LIB.S9S_MB_2U(SCH_1):FM_GPU_HSC_EN_BUF_R1':
 C_SIGNAL='@s9s_mb_2u_lib.s9s_mb_2u(sch_1):fm_gpu_hsc_en_buf_r1';
NODE_NAME     J45 D2
 '@S9S_MB_2U_LIB.S9S_MB_2U(SCH_1):PAGE233_I12@PURE_QUANTA.CONN60_101062636003K02LF(CHIPS)':
 'D2': CDS_PINID='D2';
NODE_NAME     R2906 1
 '@S9S_MB_2U_LIB.S9S_MB_2U(SCH_1):PAGE233_I37@PURE_QUANTA.Q_RES(CHIPS)':
 'A': CDS_PINID='A';
NODE_NAME     C2297 1
 '@S9S_MB_2U_LIB.S9S_MB_2U(SCH_1):PAGE233_I52@PURE_QUANTA.Q_CAP(CHIPS)':
 'A': CDS_PINID='A';
NET_NAME
'FM_GPU_HSC_EN_R'
 '@S9S_MB_2U_LIB.S9S_MB_2U(SCH_1):FM_GPU_HSC_EN_R':
 C_SIGNAL='@s9s_mb_2u_lib.s9s_mb_2u(sch_1):fm_gpu_hsc_en_r';
NODE_NAME     R2939 1
 '@S9S_MB_2U_LIB.S9S_MB_2U(SCH_1):PAGE314_I106@PURE_QUANTA.Q_RES(CHIPS)':
 'A': CDS_PINID='A';
NODE_NAME     U249 A3
 '@S9S_MB_2U_LIB.S9S_MB_2U(SCH_1):PAGE314_I188@PURE_QUANTA.LCMXO3LF9400C5BG484C(CHIPS)':
 'PT10B': CDS_PINID='PT10B';
NET_NAME
'FM_GPU_PWRGD'
 '@S9S_MB_2U_LIB.S9S_MB_2U(SCH_1):FM_GPU_PWRGD':
 C_SIGNAL='@s9s_mb_2u_lib.s9s_mb_2u(sch_1):fm_gpu_pwrgd';
NODE_NAME     J111 N6
 '@S9S_MB_2U_LIB.S9S_MB_2U(SCH_1):PAGE148_I74@PURE_QUANTA.CONN112_10137002101LF(CHIPS)':
 'N6': CDS_PINID='N6';
NODE_NAME     Q72 2
 '@S9S_MB_2U_LIB.S9S_MB_2U(SCH_1):PAGE145_I37@PURE_QUANTA.MOSFET_NCH_DUAL(CHIPS)':
 'G1': CDS_PINID='G1';
NODE_NAME     R3513 1
 '@S9S_MB_2U_LIB.S9S_MB_2U(SCH_1):PAGE145_I173@PURE_QUANTA.Q_RES(CHIPS)':
 'A': CDS_PINID='A';
NODE_NAME     R3512 2
 '@S9S_MB_2U_LIB.S9S_MB_2U(SCH_1):PAGE145_I174@PURE_QUANTA.Q_RES(CHIPS)':
 'B': CDS_PINID='B';
NET_NAME
'FM_GPU_PWRGD_ISO'
 '@S9S_MB_2U_LIB.S9S_MB_2U(SCH_1):FM_GPU_PWRGD_ISO':
 C_SIGNAL='@s9s_mb_2u_lib.s9s_mb_2u(sch_1):fm_gpu_pwrgd_iso';
NODE_NAME     C1756 1
 '@S9S_MB_2U_LIB.S9S_MB_2U(SCH_1):PAGE145_I105@PURE_QUANTA.Q_CAP(CHIPS)':
 'A': CDS_PINID='A';
NODE_NAME     R2935 2
 '@S9S_MB_2U_LIB.S9S_MB_2U(SCH_1):PAGE145_I109@PURE_QUANTA.Q_RES(CHIPS)':
 'B': CDS_PINID='B';
NODE_NAME     Q72 3
 '@S9S_MB_2U_LIB.S9S_MB_2U(SCH_1):PAGE145_I119@PURE_QUANTA.MOSFET_NCH_DUAL(CHIPS)':
 'D2': CDS_PINID='D2';
NODE_NAME     R2664 1
 '@S9S_MB_2U_LIB.S9S_MB_2U(SCH_1):PAGE314_I113@PURE_QUANTA.Q_RES(CHIPS)':
 'A': CDS_PINID='A';
NET_NAME
'FM_GPU_PWRGD_ISO_R'
 '@S9S_MB_2U_LIB.S9S_MB_2U(SCH_1):FM_GPU_PWRGD_ISO_R':
 C_SIGNAL='@s9s_mb_2u_lib.s9s_mb_2u(sch_1):fm_gpu_pwrgd_iso_r';
NODE_NAME     R2664 2
 '@S9S_MB_2U_LIB.S9S_MB_2U(SCH_1):PAGE314_I113@PURE_QUANTA.Q_RES(CHIPS)':
 'B': CDS_PINID='B';
NODE_NAME     U249 F7
 '@S9S_MB_2U_LIB.S9S_MB_2U(SCH_1):PAGE314_I188@PURE_QUANTA.LCMXO3LF9400C5BG484C(CHIPS)':
 'PT9D': CDS_PINID='PT9D';
NET_NAME
'FM_GPU_PWRGD_N'
 '@S9S_MB_2U_LIB.S9S_MB_2U(SCH_1):FM_GPU_PWRGD_N':
 C_SIGNAL='@s9s_mb_2u_lib.s9s_mb_2u(sch_1):fm_gpu_pwrgd_n';
NODE_NAME     R2842 2
 '@S9S_MB_2U_LIB.S9S_MB_2U(SCH_1):PAGE145_I30@PURE_QUANTA.Q_RES(CHIPS)':
 'B': CDS_PINID='B';
NODE_NAME     Q72 6
 '@S9S_MB_2U_LIB.S9S_MB_2U(SCH_1):PAGE145_I37@PURE_QUANTA.MOSFET_NCH_DUAL(CHIPS)':
 'D1': CDS_PINID='D1';
NODE_NAME     Q72 5
 '@S9S_MB_2U_LIB.S9S_MB_2U(SCH_1):PAGE145_I119@PURE_QUANTA.MOSFET_NCH_DUAL(CHIPS)':
 'G2': CDS_PINID='G2';
NET_NAME
'FM_GPU_PWR_EN'
 '@S9S_MB_2U_LIB.S9S_MB_2U(SCH_1):FM_GPU_PWR_EN':
 C_SIGNAL='@s9s_mb_2u_lib.s9s_mb_2u(sch_1):fm_gpu_pwr_en';
NODE_NAME     R2662 1
 '@S9S_MB_2U_LIB.S9S_MB_2U(SCH_1):PAGE314_I115@PURE_QUANTA.Q_RES(CHIPS)':
 'A': CDS_PINID='A';
NODE_NAME     U249 A2
 '@S9S_MB_2U_LIB.S9S_MB_2U(SCH_1):PAGE314_I188@PURE_QUANTA.LCMXO3LF9400C5BG484C(CHIPS)':
 'PT9B||L_GPLLC': CDS_PINID='\pt9b||l_gpllc\';
NET_NAME
'FM_GPU_PWR_EN_R'
 '@S9S_MB_2U_LIB.S9S_MB_2U(SCH_1):FM_GPU_PWR_EN_R':
 C_SIGNAL='@s9s_mb_2u_lib.s9s_mb_2u(sch_1):fm_gpu_pwr_en_r';
NODE_NAME     U196 1
 '@S9S_MB_2U_LIB.S9S_MB_2U(SCH_1):PAGE140_I127@PURE_QUANTA.74LVC2G17GW(CHIPS)':
 'A0': CDS_PINID='A0';
NODE_NAME     R2937 1
 '@S9S_MB_2U_LIB.S9S_MB_2U(SCH_1):PAGE140_I160@PURE_QUANTA.Q_RES(CHIPS)':
 'A': CDS_PINID='A';
NODE_NAME     R2936 2
 '@S9S_MB_2U_LIB.S9S_MB_2U(SCH_1):PAGE140_I162@PURE_QUANTA.Q_RES(CHIPS)':
 'B': CDS_PINID='B';
NODE_NAME     R2662 2
 '@S9S_MB_2U_LIB.S9S_MB_2U(SCH_1):PAGE314_I115@PURE_QUANTA.Q_RES(CHIPS)':
 'B': CDS_PINID='B';
NET_NAME
'FM_GPU_PWR_EN_R1'
 '@S9S_MB_2U_LIB.S9S_MB_2U(SCH_1):FM_GPU_PWR_EN_R1':
 C_SIGNAL='@s9s_mb_2u_lib.s9s_mb_2u(sch_1):fm_gpu_pwr_en_r1';
NODE_NAME     U196 6
 '@S9S_MB_2U_LIB.S9S_MB_2U(SCH_1):PAGE140_I127@PURE_QUANTA.74LVC2G17GW(CHIPS)':
 'B0': CDS_PINID='B0';
NODE_NAME     R2912 2
 '@S9S_MB_2U_LIB.S9S_MB_2U(SCH_1):PAGE140_I147@PURE_QUANTA.Q_RES(CHIPS)':
 'B': CDS_PINID='B';
NODE_NAME     R3508 1
 '@S9S_MB_2U_LIB.S9S_MB_2U(SCH_1):PAGE140_I194@PURE_QUANTA.Q_RES(CHIPS)':
 'A': CDS_PINID='A';
NODE_NAME     R2925 1
 '@S9S_MB_2U_LIB.S9S_MB_2U(SCH_1):PAGE140_I204@PURE_QUANTA.Q_RES(CHIPS)':
 'A': CDS_PINID='A';
NET_NAME
'FM_GPU_PWR_EN_R_BUF'
 '@S9S_MB_2U_LIB.S9S_MB_2U(SCH_1):FM_GPU_PWR_EN_R_BUF':
 C_SIGNAL='@s9s_mb_2u_lib.s9s_mb_2u(sch_1):fm_gpu_pwr_en_r_buf';
NODE_NAME     J111 N4
 '@S9S_MB_2U_LIB.S9S_MB_2U(SCH_1):PAGE148_I75@PURE_QUANTA.CONN112_10137002101LF(CHIPS)':
 'N4': CDS_PINID='N4';
NODE_NAME     R2925 2
 '@S9S_MB_2U_LIB.S9S_MB_2U(SCH_1):PAGE140_I204@PURE_QUANTA.Q_RES(CHIPS)':
 'B': CDS_PINID='B';
NET_NAME
'FM_HBM2_HBM3_VPP_SEL'
 '@S9S_MB_2U_LIB.S9S_MB_2U(SCH_1):FM_HBM2_HBM3_VPP_SEL':
 C_SIGNAL='@s9s_mb_2u_lib.s9s_mb_2u(sch_1):fm_hbm2_hbm3_vpp_sel';
NODE_NAME     U249 Y6
 '@S9S_MB_2U_LIB.S9S_MB_2U(SCH_1):PAGE312_I1@PURE_QUANTA.LCMXO3LF9400C5BG484C(CHIPS)':
 'PB10D': CDS_PINID='PB10D';
NODE_NAME     PU173 G
 '@S9S_MB_2U_LIB.S9S_MB_2U(SCH_1):PAGE267_I31@PURE_QUANTA.MOSFET_N(CHIPS)':
 'GATE': CDS_PINID='GATE';
NODE_NAME     PU174 G
 '@S9S_MB_2U_LIB.S9S_MB_2U(SCH_1):PAGE285_I29@PURE_QUANTA.MOSFET_N(CHIPS)':
 'GATE': CDS_PINID='GATE';
NET_NAME
'FM_HBM_VPP_SEL_CPU0_D'
 '@S9S_MB_2U_LIB.S9S_MB_2U(SCH_1):FM_HBM_VPP_SEL_CPU0_D':
 C_SIGNAL='@s9s_mb_2u_lib.s9s_mb_2u(sch_1):fm_hbm_vpp_sel_cpu0_d';
NODE_NAME     PR2336 2
 '@S9S_MB_2U_LIB.S9S_MB_2U(SCH_1):PAGE267_I34@PURE_QUANTA.Q_RES(CHIPS)':
 'B': CDS_PINID='B';
NODE_NAME     PU173 D
 '@S9S_MB_2U_LIB.S9S_MB_2U(SCH_1):PAGE267_I31@PURE_QUANTA.MOSFET_N(CHIPS)':
 'DRAIN': CDS_PINID='DRAIN';
NET_NAME
'FM_HBM_VPP_SEL_CPU1_D'
 '@S9S_MB_2U_LIB.S9S_MB_2U(SCH_1):FM_HBM_VPP_SEL_CPU1_D':
 C_SIGNAL='@s9s_mb_2u_lib.s9s_mb_2u(sch_1):fm_hbm_vpp_sel_cpu1_d';
NODE_NAME     PR2381 2
 '@S9S_MB_2U_LIB.S9S_MB_2U(SCH_1):PAGE285_I30@PURE_QUANTA.Q_RES(CHIPS)':
 'B': CDS_PINID='B';
NODE_NAME     PU174 D
 '@S9S_MB_2U_LIB.S9S_MB_2U(SCH_1):PAGE285_I29@PURE_QUANTA.MOSFET_N(CHIPS)':
 'DRAIN': CDS_PINID='DRAIN';
NET_NAME
'FM_INTRUDER_HDR_PCH_N'
 '@S9S_MB_2U_LIB.S9S_MB_2U(SCH_1):FM_INTRUDER_HDR_PCH_N':
 C_SIGNAL='@s9s_mb_2u_lib.s9s_mb_2u(sch_1):fm_intruder_hdr_pch_n';
NODE_NAME     U4 BG8
 '@S9S_MB_2U_LIB.S9S_MB_2U(SCH_1):PAGE174_I36@PURE_QUANTA.EMMITSBURG_REV0P9(CHIPS)':
 'INTRUDER_N': CDS_PINID='INTRUDER_N';
NODE_NAME     R2966 2
 '@S9S_MB_2U_LIB.S9S_MB_2U(SCH_1):PAGE174_I96@PURE_QUANTA.Q_RES(CHIPS)':
 'B': CDS_PINID='B';
NET_NAME
'FM_JTAG_BMC_MUX_SEL'
 '@S9S_MB_2U_LIB.S9S_MB_2U(SCH_1):FM_JTAG_BMC_MUX_SEL':
 C_SIGNAL='@s9s_mb_2u_lib.s9s_mb_2u(sch_1):fm_jtag_bmc_mux_sel';
NODE_NAME     U97 8
 '@S9S_MB_2U_LIB.S9S_MB_2U(SCH_1):PAGE226_I38@PURE_QUANTA.NX3L2267GM(CHIPS)':
 '1S': CDS_PINID='\1s\';
NODE_NAME     U97 7
 '@S9S_MB_2U_LIB.S9S_MB_2U(SCH_1):PAGE226_I38@PURE_QUANTA.NX3L2267GM(CHIPS)':
 '2S': CDS_PINID='\2s\';
NODE_NAME     U96 8
 '@S9S_MB_2U_LIB.S9S_MB_2U(SCH_1):PAGE226_I68@PURE_QUANTA.NX3L2267GM(CHIPS)':
 '1S': CDS_PINID='\1s\';
NODE_NAME     U96 7
 '@S9S_MB_2U_LIB.S9S_MB_2U(SCH_1):PAGE226_I68@PURE_QUANTA.NX3L2267GM(CHIPS)':
 '2S': CDS_PINID='\2s\';
NODE_NAME     R1814 1
 '@S9S_MB_2U_LIB.S9S_MB_2U(SCH_1):PAGE226_I77@PURE_QUANTA.Q_RES(CHIPS)':
 'A': CDS_PINID='A';
NODE_NAME     R1813 2
 '@S9S_MB_2U_LIB.S9S_MB_2U(SCH_1):PAGE226_I79@PURE_QUANTA.Q_RES(CHIPS)':
 'B': CDS_PINID='B';
NODE_NAME     R4088 2
 '@S9S_MB_2U_LIB.S9S_MB_2U(SCH_1):PAGE313_I166@PURE_QUANTA.Q_RES(CHIPS)':
 'B': CDS_PINID='B';
NODE_NAME     R1833 2
 '@S9S_MB_2U_LIB.S9S_MB_2U(SCH_1):PAGE313_I167@PURE_QUANTA.Q_RES(CHIPS)':
 'B': CDS_PINID='B';
NET_NAME
'FM_JTAG_BMC_MUX_SEL_FROM_BMC_R'
 '@S9S_MB_2U_LIB.S9S_MB_2U(SCH_1):FM_JTAG_BMC_MUX_SEL_FROM_BMC_R':
 C_SIGNAL='@s9s_mb_2u_lib.s9s_mb_2u(sch_1):fm_jtag_bmc_mux_sel_from_bmc_r';
NODE_NAME     R4088 1
 '@S9S_MB_2U_LIB.S9S_MB_2U(SCH_1):PAGE313_I166@PURE_QUANTA.Q_RES(CHIPS)':
 'A': CDS_PINID='A';
NODE_NAME     R4087 1
 '@S9S_MB_2U_LIB.S9S_MB_2U(SCH_1):PAGE227_I28@PURE_QUANTA.Q_RES(CHIPS)':
 'A': CDS_PINID='A';
NET_NAME
'FM_JTAG_BMC_MUX_SEL_FROM_BMC_R2'
 '@S9S_MB_2U_LIB.S9S_MB_2U(SCH_1):FM_JTAG_BMC_MUX_SEL_FROM_BMC_R2':
 C_SIGNAL='@s9s_mb_2u_lib.s9s_mb_2u(sch_1):fm_jtag_bmc_mux_sel_from_bmc_r2';
NODE_NAME     R4087 2
 '@S9S_MB_2U_LIB.S9S_MB_2U(SCH_1):PAGE227_I28@PURE_QUANTA.Q_RES(CHIPS)':
 'B': CDS_PINID='B';
NODE_NAME     J41 A43
 '@S9S_MB_2U_LIB.S9S_MB_2U(SCH_1):PAGE227_I173@PURE_QUANTA.SCONN168_ME1016810202011(CHIPS)':
 'GND_A43': CDS_PINID='GND_A43';
NET_NAME
'FM_JTAG_BMC_MUX_SEL_R'
 '@S9S_MB_2U_LIB.S9S_MB_2U(SCH_1):FM_JTAG_BMC_MUX_SEL_R':
 C_SIGNAL='@s9s_mb_2u_lib.s9s_mb_2u(sch_1):fm_jtag_bmc_mux_sel_r';
NODE_NAME     U249 U22
 '@S9S_MB_2U_LIB.S9S_MB_2U(SCH_1):PAGE313_I1@PURE_QUANTA.LCMXO3LF9400C5BG484C(CHIPS)':
 'PR24C': CDS_PINID='PR24C';
NODE_NAME     R1833 1
 '@S9S_MB_2U_LIB.S9S_MB_2U(SCH_1):PAGE313_I167@PURE_QUANTA.Q_RES(CHIPS)':
 'A': CDS_PINID='A';
NET_NAME
'FM_JTAG_ODT_DISABLE'
 '@S9S_MB_2U_LIB.S9S_MB_2U(SCH_1):FM_JTAG_ODT_DISABLE':
 C_SIGNAL='@s9s_mb_2u_lib.s9s_mb_2u(sch_1):fm_jtag_odt_disable';
NODE_NAME     U4 AW10
 '@S9S_MB_2U_LIB.S9S_MB_2U(SCH_1):PAGE177_I27@PURE_QUANTA.EMMITSBURG_REV0P9(CHIPS)':
 'GPPC_S_10': CDS_PINID='GPPC_S_10';
NODE_NAME     R613 2
 '@S9S_MB_2U_LIB.S9S_MB_2U(SCH_1):PAGE187_I18@PURE_QUANTA.Q_RES(CHIPS)':
 'B': CDS_PINID='B';
NODE_NAME     R614 1
 '@S9S_MB_2U_LIB.S9S_MB_2U(SCH_1):PAGE187_I23@PURE_QUANTA.Q_RES(CHIPS)':
 'A': CDS_PINID='A';
NET_NAME
'FM_JTAG_TCK_MUX_SEL'
 '@S9S_MB_2U_LIB.S9S_MB_2U(SCH_1):FM_JTAG_TCK_MUX_SEL':
 C_SIGNAL='@s9s_mb_2u_lib.s9s_mb_2u(sch_1):fm_jtag_tck_mux_sel';
NODE_NAME     U85 6
 '@S9S_MB_2U_LIB.S9S_MB_2U(SCH_1):PAGE137_I109@PURE_QUANTA.NC7SB3157(CHIPS)':
 'S': CDS_PINID='S';
NODE_NAME     R1365 1
 '@S9S_MB_2U_LIB.S9S_MB_2U(SCH_1):PAGE137_I116@PURE_QUANTA.Q_RES(CHIPS)':
 'A': CDS_PINID='A';
NODE_NAME     R4609 2
 '@S9S_MB_2U_LIB.S9S_MB_2U(SCH_1):PAGE313_I194@PURE_QUANTA.Q_RES(CHIPS)':
 'B': CDS_PINID='B';
NET_NAME
'FM_JTAG_TCK_MUX_SEL_R'
 '@S9S_MB_2U_LIB.S9S_MB_2U(SCH_1):FM_JTAG_TCK_MUX_SEL_R':
 C_SIGNAL='@s9s_mb_2u_lib.s9s_mb_2u(sch_1):fm_jtag_tck_mux_sel_r';
NODE_NAME     U249 U17
 '@S9S_MB_2U_LIB.S9S_MB_2U(SCH_1):PAGE313_I1@PURE_QUANTA.LCMXO3LF9400C5BG484C(CHIPS)':
 'PR29C': CDS_PINID='PR29C';
NODE_NAME     R4609 1
 '@S9S_MB_2U_LIB.S9S_MB_2U(SCH_1):PAGE313_I194@PURE_QUANTA.Q_RES(CHIPS)':
 'A': CDS_PINID='A';
NET_NAME
'FM_LM75_2_ALERT_N'
 '@S9S_MB_2U_LIB.S9S_MB_2U(SCH_1):FM_LM75_2_ALERT_N':
 C_SIGNAL='@s9s_mb_2u_lib.s9s_mb_2u(sch_1):fm_lm75_2_alert_n';
NODE_NAME     R4213 2
 '@S9S_MB_2U_LIB.S9S_MB_2U(SCH_1):PAGE161_I115@PURE_QUANTA.Q_RES(CHIPS)':
 'B': CDS_PINID='B';
NODE_NAME     U272 3
 '@S9S_MB_2U_LIB.S9S_MB_2U(SCH_1):PAGE161_I166@PURE_QUANTA.LM75BD(CHIPS)':
 'OS': CDS_PINID='OS';
NET_NAME
'FM_LM75_3_ALERT_N'
 '@S9S_MB_2U_LIB.S9S_MB_2U(SCH_1):FM_LM75_3_ALERT_N':
 C_SIGNAL='@s9s_mb_2u_lib.s9s_mb_2u(sch_1):fm_lm75_3_alert_n';
NODE_NAME     R4212 2
 '@S9S_MB_2U_LIB.S9S_MB_2U(SCH_1):PAGE161_I135@PURE_QUANTA.Q_RES(CHIPS)':
 'B': CDS_PINID='B';
NODE_NAME     U273 3
 '@S9S_MB_2U_LIB.S9S_MB_2U(SCH_1):PAGE161_I167@PURE_QUANTA.LM75BD(CHIPS)':
 'OS': CDS_PINID='OS';
NET_NAME
'FM_LPC_ESPI_SEL'
 '@S9S_MB_2U_LIB.S9S_MB_2U(SCH_1):FM_LPC_ESPI_SEL':
 C_SIGNAL='@s9s_mb_2u_lib.s9s_mb_2u(sch_1):fm_lpc_espi_sel';
NODE_NAME     R1763 2
 '@S9S_MB_2U_LIB.S9S_MB_2U(SCH_1):PAGE243_I7@PURE_QUANTA.Q_RES(CHIPS)':
 'B': CDS_PINID='B';
NODE_NAME     R1764 1
 '@S9S_MB_2U_LIB.S9S_MB_2U(SCH_1):PAGE243_I8@PURE_QUANTA.Q_RES(CHIPS)':
 'A': CDS_PINID='A';
NODE_NAME     U307 D
 '@S9S_MB_2U_LIB.S9S_MB_2U(SCH_1):PAGE243_I15@PURE_QUANTA.MOSFET_N(CHIPS)':
 'DRAIN': CDS_PINID='DRAIN';
NODE_NAME     R4176 2
 '@S9S_MB_2U_LIB.S9S_MB_2U(SCH_1):PAGE243_I16@PURE_QUANTA.Q_RES(CHIPS)':
 'B': CDS_PINID='B';
NODE_NAME     J41 B9
 '@S9S_MB_2U_LIB.S9S_MB_2U(SCH_1):PAGE227_I173@PURE_QUANTA.SCONN168_ME1016810202011(CHIPS)':
 'BIF2#': CDS_PINID='\bif2#\';
NET_NAME
'FM_LT_KEY_DOWNGRADE_N'
 '@S9S_MB_2U_LIB.S9S_MB_2U(SCH_1):FM_LT_KEY_DOWNGRADE_N':
 C_SIGNAL='@s9s_mb_2u_lib.s9s_mb_2u(sch_1):fm_lt_key_downgrade_n';
NODE_NAME     U4 L4
 '@S9S_MB_2U_LIB.S9S_MB_2U(SCH_1):PAGE176_I22@PURE_QUANTA.EMMITSBURG_REV0P9(CHIPS)':
 'GPPC_H_19': CDS_PINID='GPPC_H_19';
NODE_NAME     R619 2
 '@S9S_MB_2U_LIB.S9S_MB_2U(SCH_1):PAGE187_I48@PURE_QUANTA.Q_RES(CHIPS)':
 'B': CDS_PINID='B';
NET_NAME
'FM_M2_E1S_E6_PEDET'
 '@S9S_MB_2U_LIB.S9S_MB_2U(SCH_1):FM_M2_E1S_E6_PEDET':
 C_SIGNAL='@s9s_mb_2u_lib.s9s_mb_2u(sch_1):fm_m2_e1s_e6_pedet';
NODE_NAME     U4 BB24
 '@S9S_MB_2U_LIB.S9S_MB_2U(SCH_1):PAGE176_I22@PURE_QUANTA.EMMITSBURG_REV0P9(CHIPS)':
 'GPP_E_6_SATA0_USB3_XPCIE_0': CDS_PINID='GPP_E_6_SATA0_USB3_XPCIE_0';
NODE_NAME     R2510 2
 '@S9S_MB_2U_LIB.S9S_MB_2U(SCH_1):PAGE176_I175@PURE_QUANTA.Q_RES(CHIPS)':
 'B': CDS_PINID='B';
NODE_NAME     R2511 1
 '@S9S_MB_2U_LIB.S9S_MB_2U(SCH_1):PAGE176_I176@PURE_QUANTA.Q_RES(CHIPS)':
 'A': CDS_PINID='A';
NET_NAME
'FM_M2_SSD0_E7_PEDET'
 '@S9S_MB_2U_LIB.S9S_MB_2U(SCH_1):FM_M2_SSD0_E7_PEDET':
 C_SIGNAL='@s9s_mb_2u_lib.s9s_mb_2u(sch_1):fm_m2_ssd0_e7_pedet';
NODE_NAME     U4 AW32
 '@S9S_MB_2U_LIB.S9S_MB_2U(SCH_1):PAGE176_I22@PURE_QUANTA.EMMITSBURG_REV0P9(CHIPS)':
 'GPP_E_7_SATA0_USB3_XPCIE_1': CDS_PINID='GPP_E_7_SATA0_USB3_XPCIE_1';
NODE_NAME     R2508 2
 '@S9S_MB_2U_LIB.S9S_MB_2U(SCH_1):PAGE176_I173@PURE_QUANTA.Q_RES(CHIPS)':
 'B': CDS_PINID='B';
NODE_NAME     R2509 1
 '@S9S_MB_2U_LIB.S9S_MB_2U(SCH_1):PAGE176_I174@PURE_QUANTA.Q_RES(CHIPS)':
 'A': CDS_PINID='A';
NODE_NAME     R2526 2
 '@S9S_MB_2U_LIB.S9S_MB_2U(SCH_1):PAGE182_I247@PURE_QUANTA.Q_RES(CHIPS)':
 'B': CDS_PINID='B';
NET_NAME
'FM_M2_SSD_0_PEDET'
 '@S9S_MB_2U_LIB.S9S_MB_2U(SCH_1):FM_M2_SSD_0_PEDET':
 C_SIGNAL='@s9s_mb_2u_lib.s9s_mb_2u(sch_1):fm_m2_ssd_0_pedet';
NODE_NAME     R1396 1
 '@S9S_MB_2U_LIB.S9S_MB_2U(SCH_1):PAGE182_I167@PURE_QUANTA.Q_RES(CHIPS)':
 'A': CDS_PINID='A';
NODE_NAME     J59 69
 '@S9S_MB_2U_LIB.S9S_MB_2U(SCH_1):PAGE182_I178@PURE_QUANTA.SCONN75K_APCI0155P004A(CHIPS)':
 'PEDET': CDS_PINID='PEDET';
NODE_NAME     R2526 1
 '@S9S_MB_2U_LIB.S9S_MB_2U(SCH_1):PAGE182_I247@PURE_QUANTA.Q_RES(CHIPS)':
 'A': CDS_PINID='A';
NET_NAME
'FM_MB_PDB_SMB9_R_EN'
 '@S9S_MB_2U_LIB.S9S_MB_2U(SCH_1):FM_MB_PDB_SMB9_R_EN':
 C_SIGNAL='@s9s_mb_2u_lib.s9s_mb_2u(sch_1):fm_mb_pdb_smb9_r_en';
NODE_NAME     R2796 2
 '@S9S_MB_2U_LIB.S9S_MB_2U(SCH_1):PAGE233_I10@PURE_QUANTA.Q_RES(CHIPS)':
 'B': CDS_PINID='B';
NODE_NAME     U192 1
 '@S9S_MB_2U_LIB.S9S_MB_2U(SCH_1):PAGE233_I16@PURE_QUANTA.LTC4307CMS8(CHIPS)':
 'ENABLE': CDS_PINID='ENABLE';
NET_NAME
'FM_ME_AUTHN_FAIL'
 '@S9S_MB_2U_LIB.S9S_MB_2U(SCH_1):FM_ME_AUTHN_FAIL':
 C_SIGNAL='@s9s_mb_2u_lib.s9s_mb_2u(sch_1):fm_me_authn_fail';
NODE_NAME     U4 AW20
 '@S9S_MB_2U_LIB.S9S_MB_2U(SCH_1):PAGE176_I22@PURE_QUANTA.EMMITSBURG_REV0P9(CHIPS)':
 'GPP_E_15_SATA2_SLOAD_SATA2_GP': CDS_PINID='GPP_E_15_SATA2_SLOAD_SATA2_GP';
NODE_NAME     R1554 2
 '@S9S_MB_2U_LIB.S9S_MB_2U(SCH_1):PAGE192_I62@PURE_QUANTA.Q_RES(CHIPS)':
 'B': CDS_PINID='B';
NODE_NAME     U249 Y8
 '@S9S_MB_2U_LIB.S9S_MB_2U(SCH_1):PAGE312_I1@PURE_QUANTA.LCMXO3LF9400C5BG484C(CHIPS)':
 'PB18C': CDS_PINID='PB18C';
NET_NAME
'FM_ME_BT_DONE'
 '@S9S_MB_2U_LIB.S9S_MB_2U(SCH_1):FM_ME_BT_DONE':
 C_SIGNAL='@s9s_mb_2u_lib.s9s_mb_2u(sch_1):fm_me_bt_done';
NODE_NAME     U4 AW29
 '@S9S_MB_2U_LIB.S9S_MB_2U(SCH_1):PAGE176_I22@PURE_QUANTA.EMMITSBURG_REV0P9(CHIPS)':
 'GPP_E_16_SATA2_SDATAOUT_SATA2_DEVSLP': CDS_PINID='GPP_E_16_SATA2_SDATAOUT_SATA2_DEVSLP';
NODE_NAME     R71 2
 '@S9S_MB_2U_LIB.S9S_MB_2U(SCH_1):PAGE192_I60@PURE_QUANTA.Q_RES(CHIPS)':
 'B': CDS_PINID='B';
NODE_NAME     U249 T14
 '@S9S_MB_2U_LIB.S9S_MB_2U(SCH_1):PAGE312_I1@PURE_QUANTA.LCMXO3LF9400C5BG484C(CHIPS)':
 'PB32B': CDS_PINID='PB32B';
NET_NAME
'FM_ME_RCVR_N'
 '@S9S_MB_2U_LIB.S9S_MB_2U(SCH_1):FM_ME_RCVR_N':
 C_SIGNAL='@s9s_mb_2u_lib.s9s_mb_2u(sch_1):fm_me_rcvr_n';
NODE_NAME     U4 AG7
 '@S9S_MB_2U_LIB.S9S_MB_2U(SCH_1):PAGE176_I22@PURE_QUANTA.EMMITSBURG_REV0P9(CHIPS)':
 'GPP_L_4': CDS_PINID='GPP_L_4';
NODE_NAME     R1342 2
 '@S9S_MB_2U_LIB.S9S_MB_2U(SCH_1):PAGE189_I114@PURE_QUANTA.Q_RES(CHIPS)':
 'B': CDS_PINID='B';
NODE_NAME     J104 12
 '@S9S_MB_2U_LIB.S9S_MB_2U(SCH_1):PAGE189_I134@PURE_QUANTA.CONN14_210HP207GBR1(CHIPS)':
 '12': CDS_PINID='\12\';
NET_NAME
'FM_MFG_MODE'
 '@S9S_MB_2U_LIB.S9S_MB_2U(SCH_1):FM_MFG_MODE':
 C_SIGNAL='@s9s_mb_2u_lib.s9s_mb_2u(sch_1):fm_mfg_mode';
NODE_NAME     U4 AG10
 '@S9S_MB_2U_LIB.S9S_MB_2U(SCH_1):PAGE176_I22@PURE_QUANTA.EMMITSBURG_REV0P9(CHIPS)':
 'GPP_L_6': CDS_PINID='GPP_L_6';
NODE_NAME     R1299 1
 '@S9S_MB_2U_LIB.S9S_MB_2U(SCH_1):PAGE188_I21@PURE_QUANTA.Q_RES(CHIPS)':
 'A': CDS_PINID='A';
NODE_NAME     R1298 2
 '@S9S_MB_2U_LIB.S9S_MB_2U(SCH_1):PAGE188_I22@PURE_QUANTA.Q_RES(CHIPS)':
 'B': CDS_PINID='B';
NET_NAME
'FM_NCSI_OCP_V3_1_R_OE'
 '@S9S_MB_2U_LIB.S9S_MB_2U(SCH_1):FM_NCSI_OCP_V3_1_R_OE':
 C_SIGNAL='@s9s_mb_2u_lib.s9s_mb_2u(sch_1):fm_ncsi_ocp_v3_1_r_oe';
NODE_NAME     U249 Y14
 '@S9S_MB_2U_LIB.S9S_MB_2U(SCH_1):PAGE312_I1@PURE_QUANTA.LCMXO3LF9400C5BG484C(CHIPS)':
 'PB33C': CDS_PINID='PB33C';
NODE_NAME     R2474 1
 '@S9S_MB_2U_LIB.S9S_MB_2U(SCH_1):PAGE151_I19@PURE_QUANTA.Q_RES(CHIPS)':
 'A': CDS_PINID='A';
NET_NAME
'FM_NCSI_OCP_V3_2_R_OE'
 '@S9S_MB_2U_LIB.S9S_MB_2U(SCH_1):FM_NCSI_OCP_V3_2_R_OE':
 C_SIGNAL='@s9s_mb_2u_lib.s9s_mb_2u(sch_1):fm_ncsi_ocp_v3_2_r_oe';
NODE_NAME     R3206 1
 '@S9S_MB_2U_LIB.S9S_MB_2U(SCH_1):PAGE307_I12@PURE_QUANTA.Q_RES(CHIPS)':
 'A': CDS_PINID='A';
NODE_NAME     U249 B14
 '@S9S_MB_2U_LIB.S9S_MB_2U(SCH_1):PAGE314_I188@PURE_QUANTA.LCMXO3LF9400C5BG484C(CHIPS)':
 'PT30B': CDS_PINID='PT30B';
NET_NAME
'FM_OCP_SFF_PWR_GOOD'
 '@S9S_MB_2U_LIB.S9S_MB_2U(SCH_1):FM_OCP_SFF_PWR_GOOD':
 C_SIGNAL='@s9s_mb_2u_lib.s9s_mb_2u(sch_1):fm_ocp_sff_pwr_good';
NODE_NAME     R3132 2
 '@S9S_MB_2U_LIB.S9S_MB_2U(SCH_1):PAGE150_I35@PURE_QUANTA.Q_RES(CHIPS)':
 'B': CDS_PINID='B';
NODE_NAME     J37 OB1
 '@S9S_MB_2U_LIB.S9S_MB_2U(SCH_1):PAGE150_I199@PURE_QUANTA.SCONN168_ME1016810202011(CHIPS)':
 'NIC_PWR_GOOD': CDS_PINID='NIC_PWR_GOOD';
NODE_NAME     R1606 1
 '@S9S_MB_2U_LIB.S9S_MB_2U(SCH_1):PAGE314_I109@PURE_QUANTA.Q_RES(CHIPS)':
 'A': CDS_PINID='A';
NODE_NAME     U66 2
 '@S9S_MB_2U_LIB.S9S_MB_2U(SCH_1):PAGE151_I15@PURE_QUANTA.74LVC1G126SE7(CHIPS)':
 'A': CDS_PINID='A';
NET_NAME
'FM_OCP_SFF_PWR_GOOD_R'
 '@S9S_MB_2U_LIB.S9S_MB_2U(SCH_1):FM_OCP_SFF_PWR_GOOD_R':
 C_SIGNAL='@s9s_mb_2u_lib.s9s_mb_2u(sch_1):fm_ocp_sff_pwr_good_r';
NODE_NAME     R1606 2
 '@S9S_MB_2U_LIB.S9S_MB_2U(SCH_1):PAGE314_I109@PURE_QUANTA.Q_RES(CHIPS)':
 'B': CDS_PINID='B';
NODE_NAME     U249 A7
 '@S9S_MB_2U_LIB.S9S_MB_2U(SCH_1):PAGE314_I188@PURE_QUANTA.LCMXO3LF9400C5BG484C(CHIPS)':
 'PT14B': CDS_PINID='PT14B';
NET_NAME
'FM_OCP_V3_2_PWR_GOOD'
 '@S9S_MB_2U_LIB.S9S_MB_2U(SCH_1):FM_OCP_V3_2_PWR_GOOD':
 C_SIGNAL='@s9s_mb_2u_lib.s9s_mb_2u(sch_1):fm_ocp_v3_2_pwr_good';
NODE_NAME     R413 2
 '@S9S_MB_2U_LIB.S9S_MB_2U(SCH_1):PAGE146_I43@PURE_QUANTA.Q_RES(CHIPS)':
 'B': CDS_PINID='B';
NODE_NAME     J35 OB1
 '@S9S_MB_2U_LIB.S9S_MB_2U(SCH_1):PAGE146_I303@PURE_QUANTA.SCONN168_ME1016810202011(CHIPS)':
 'NIC_PWR_GOOD': CDS_PINID='NIC_PWR_GOOD';
NODE_NAME     U286 2
 '@S9S_MB_2U_LIB.S9S_MB_2U(SCH_1):PAGE307_I80@PURE_QUANTA.74LVC1G126SE7(CHIPS)':
 'A': CDS_PINID='A';
NODE_NAME     R3230 1
 '@S9S_MB_2U_LIB.S9S_MB_2U(SCH_1):PAGE314_I110@PURE_QUANTA.Q_RES(CHIPS)':
 'A': CDS_PINID='A';
NET_NAME
'FM_OCP_V3_2_PWR_GOOD_R'
 '@S9S_MB_2U_LIB.S9S_MB_2U(SCH_1):FM_OCP_V3_2_PWR_GOOD_R':
 C_SIGNAL='@s9s_mb_2u_lib.s9s_mb_2u(sch_1):fm_ocp_v3_2_pwr_good_r';
NODE_NAME     R3230 2
 '@S9S_MB_2U_LIB.S9S_MB_2U(SCH_1):PAGE314_I110@PURE_QUANTA.Q_RES(CHIPS)':
 'B': CDS_PINID='B';
NODE_NAME     U249 B6
 '@S9S_MB_2U_LIB.S9S_MB_2U(SCH_1):PAGE314_I188@PURE_QUANTA.LCMXO3LF9400C5BG484C(CHIPS)':
 'PT14A': CDS_PINID='PT14A';
NET_NAME
'FM_P12V_HSC_EN_N'
 '@S9S_MB_2U_LIB.S9S_MB_2U(SCH_1):FM_P12V_HSC_EN_N':
 C_SIGNAL='@s9s_mb_2u_lib.s9s_mb_2u(sch_1):fm_p12v_hsc_en_n';
NODE_NAME     U158 D
 '@S9S_MB_2U_LIB.S9S_MB_2U(SCH_1):PAGE234_I6@PURE_QUANTA.MOSFET_NCH_GDS_ESD_PROTECTED(CHIPS)':
 'D': CDS_PINID='D';
NODE_NAME     R2529 1
 '@S9S_MB_2U_LIB.S9S_MB_2U(SCH_1):PAGE234_I7@PURE_QUANTA.Q_RES(CHIPS)':
 'A': CDS_PINID='A';
NODE_NAME     R2528 2
 '@S9S_MB_2U_LIB.S9S_MB_2U(SCH_1):PAGE234_I8@PURE_QUANTA.Q_RES(CHIPS)':
 'B': CDS_PINID='B';
NET_NAME
'FM_P12V_HSC_EN_R'
 '@S9S_MB_2U_LIB.S9S_MB_2U(SCH_1):FM_P12V_HSC_EN_R':
 C_SIGNAL='@s9s_mb_2u_lib.s9s_mb_2u(sch_1):fm_p12v_hsc_en_r';
NODE_NAME     R2531 2
 '@S9S_MB_2U_LIB.S9S_MB_2U(SCH_1):PAGE234_I3@PURE_QUANTA.Q_RES(CHIPS)':
 'B': CDS_PINID='B';
NODE_NAME     U158 G
 '@S9S_MB_2U_LIB.S9S_MB_2U(SCH_1):PAGE234_I6@PURE_QUANTA.MOSFET_NCH_GDS_ESD_PROTECTED(CHIPS)':
 'G': CDS_PINID='G';
NET_NAME
'FM_P12V_HSC_EN_R_N'
 '@S9S_MB_2U_LIB.S9S_MB_2U(SCH_1):FM_P12V_HSC_EN_R_N':
 C_SIGNAL='@s9s_mb_2u_lib.s9s_mb_2u(sch_1):fm_p12v_hsc_en_r_n';
NODE_NAME     R2529 2
 '@S9S_MB_2U_LIB.S9S_MB_2U(SCH_1):PAGE234_I7@PURE_QUANTA.Q_RES(CHIPS)':
 'B': CDS_PINID='B';
NODE_NAME     Q54 G
 '@S9S_MB_2U_LIB.S9S_MB_2U(SCH_1):PAGE234_I14@PURE_QUANTA.MOSFET_NCH_GDS_ESD_PROTECTED(CHIPS)':
 'G': CDS_PINID='G';
NET_NAME
'FM_P1V05_PCH_AUX_EN'
 '@S9S_MB_2U_LIB.S9S_MB_2U(SCH_1):FM_P1V05_PCH_AUX_EN':
 C_SIGNAL='@s9s_mb_2u_lib.s9s_mb_2u(sch_1):fm_p1v05_pch_aux_en';
NODE_NAME     U249 G20
 '@S9S_MB_2U_LIB.S9S_MB_2U(SCH_1):PAGE313_I1@PURE_QUANTA.LCMXO3LF9400C5BG484C(CHIPS)':
 'PR6B': CDS_PINID='PR6B';
NODE_NAME     R1389 1
 '@S9S_MB_2U_LIB.S9S_MB_2U(SCH_1):PAGE248_I27@PURE_QUANTA.Q_RES(CHIPS)':
 'A': CDS_PINID='A';
NET_NAME
'FM_P1V05_PCH_AUX_R_EN'
 '@S9S_MB_2U_LIB.S9S_MB_2U(SCH_1):FM_P1V05_PCH_AUX_R_EN':
 C_SIGNAL='@s9s_mb_2u_lib.s9s_mb_2u(sch_1):fm_p1v05_pch_aux_r_en';
NODE_NAME     PC2286 1
 '@S9S_MB_2U_LIB.S9S_MB_2U(SCH_1):PAGE248_I8@PURE_QUANTA.Q_CAP(CHIPS)':
 'A': CDS_PINID='A';
NODE_NAME     PR1649 1
 '@S9S_MB_2U_LIB.S9S_MB_2U(SCH_1):PAGE248_I9@PURE_QUANTA.Q_RES(CHIPS)':
 'A': CDS_PINID='A';
NODE_NAME     PR1647 2
 '@S9S_MB_2U_LIB.S9S_MB_2U(SCH_1):PAGE248_I26@PURE_QUANTA.Q_RES(CHIPS)':
 'B': CDS_PINID='B';
NODE_NAME     R1389 2
 '@S9S_MB_2U_LIB.S9S_MB_2U(SCH_1):PAGE248_I27@PURE_QUANTA.Q_RES(CHIPS)':
 'B': CDS_PINID='B';
NODE_NAME     PU73 8
 '@S9S_MB_2U_LIB.S9S_MB_2U(SCH_1):PAGE248_I11@PURE_QUANTA.RS53319LR(CHIPS)':
 'EN': CDS_PINID='EN';
NET_NAME
'FM_P2E_BUF2_EQA0'
 '@S9S_MB_2U_LIB.S9S_MB_2U(SCH_1):FM_P2E_BUF2_EQA0':
 C_SIGNAL='@s9s_mb_2u_lib.s9s_mb_2u(sch_1):fm_p2e_buf2_eqa0';
NODE_NAME     U328 10
 '@S9S_MB_2U_LIB.S9S_MB_2U(SCH_1):PAGE159_I95@PURE_QUANTA.DS125BR111RTWR(CHIPS)':
 'EQA0||AD0': CDS_PINID='\eqa0||ad0\';
NODE_NAME     R4650 1
 '@S9S_MB_2U_LIB.S9S_MB_2U(SCH_1):PAGE159_I71@PURE_QUANTA.Q_RES(CHIPS)':
 'A': CDS_PINID='A';
NODE_NAME     R4649 2
 '@S9S_MB_2U_LIB.S9S_MB_2U(SCH_1):PAGE159_I74@PURE_QUANTA.Q_RES(CHIPS)':
 'B': CDS_PINID='B';
NET_NAME
'FM_P2E_BUF2_EQA1'
 '@S9S_MB_2U_LIB.S9S_MB_2U(SCH_1):FM_P2E_BUF2_EQA1':
 C_SIGNAL='@s9s_mb_2u_lib.s9s_mb_2u(sch_1):fm_p2e_buf2_eqa1';
NODE_NAME     R4654 1
 '@S9S_MB_2U_LIB.S9S_MB_2U(SCH_1):PAGE159_I67@PURE_QUANTA.Q_RES(CHIPS)':
 'A': CDS_PINID='A';
NODE_NAME     U328 9
 '@S9S_MB_2U_LIB.S9S_MB_2U(SCH_1):PAGE159_I95@PURE_QUANTA.DS125BR111RTWR(CHIPS)':
 'EQA1||AD1': CDS_PINID='\eqa1||ad1\';
NODE_NAME     R4648 2
 '@S9S_MB_2U_LIB.S9S_MB_2U(SCH_1):PAGE159_I72@PURE_QUANTA.Q_RES(CHIPS)':
 'B': CDS_PINID='B';
NET_NAME
'FM_P2E_BUF2_EQB0'
 '@S9S_MB_2U_LIB.S9S_MB_2U(SCH_1):FM_P2E_BUF2_EQB0':
 C_SIGNAL='@s9s_mb_2u_lib.s9s_mb_2u(sch_1):fm_p2e_buf2_eqb0';
NODE_NAME     R4646 1
 '@S9S_MB_2U_LIB.S9S_MB_2U(SCH_1):PAGE159_I15@PURE_QUANTA.Q_RES(CHIPS)':
 'A': CDS_PINID='A';
NODE_NAME     R4645 2
 '@S9S_MB_2U_LIB.S9S_MB_2U(SCH_1):PAGE159_I16@PURE_QUANTA.Q_RES(CHIPS)':
 'B': CDS_PINID='B';
NODE_NAME     U328 1
 '@S9S_MB_2U_LIB.S9S_MB_2U(SCH_1):PAGE159_I95@PURE_QUANTA.DS125BR111RTWR(CHIPS)':
 'EQB0||AD3': CDS_PINID='\eqb0||ad3\';
NET_NAME
'FM_P2E_BUF2_EQB1'
 '@S9S_MB_2U_LIB.S9S_MB_2U(SCH_1):FM_P2E_BUF2_EQB1':
 C_SIGNAL='@s9s_mb_2u_lib.s9s_mb_2u(sch_1):fm_p2e_buf2_eqb1';
NODE_NAME     U328 2
 '@S9S_MB_2U_LIB.S9S_MB_2U(SCH_1):PAGE159_I95@PURE_QUANTA.DS125BR111RTWR(CHIPS)':
 'EQB1||AD2': CDS_PINID='\eqb1||ad2\';
NODE_NAME     R4694 1
 '@S9S_MB_2U_LIB.S9S_MB_2U(SCH_1):PAGE159_I10@PURE_QUANTA.Q_RES(CHIPS)':
 'A': CDS_PINID='A';
NODE_NAME     R4644 2
 '@S9S_MB_2U_LIB.S9S_MB_2U(SCH_1):PAGE159_I11@PURE_QUANTA.Q_RES(CHIPS)':
 'B': CDS_PINID='B';
NET_NAME
'FM_P2E_BUF2_RXDET'
 '@S9S_MB_2U_LIB.S9S_MB_2U(SCH_1):FM_P2E_BUF2_RXDET':
 C_SIGNAL='@s9s_mb_2u_lib.s9s_mb_2u(sch_1):fm_p2e_buf2_rxdet';
NODE_NAME     R4655 2
 '@S9S_MB_2U_LIB.S9S_MB_2U(SCH_1):PAGE159_I62@PURE_QUANTA.Q_RES(CHIPS)':
 'B': CDS_PINID='B';
NODE_NAME     U328 18
 '@S9S_MB_2U_LIB.S9S_MB_2U(SCH_1):PAGE159_I95@PURE_QUANTA.DS125BR111RTWR(CHIPS)':
 'RXDET||DONE#': CDS_PINID='\rxdet||done#\';
NODE_NAME     R3381 1
 '@S9S_MB_2U_LIB.S9S_MB_2U(SCH_1):PAGE159_I61@PURE_QUANTA.Q_RES(CHIPS)':
 'A': CDS_PINID='A';
NET_NAME
'FM_P2E_BUF2_SD_TH'
 '@S9S_MB_2U_LIB.S9S_MB_2U(SCH_1):FM_P2E_BUF2_SD_TH':
 C_SIGNAL='@s9s_mb_2u_lib.s9s_mb_2u(sch_1):fm_p2e_buf2_sd_th';
NODE_NAME     R4656 2
 '@S9S_MB_2U_LIB.S9S_MB_2U(SCH_1):PAGE159_I66@PURE_QUANTA.Q_RES(CHIPS)':
 'B': CDS_PINID='B';
NODE_NAME     U328 14
 '@S9S_MB_2U_LIB.S9S_MB_2U(SCH_1):PAGE159_I95@PURE_QUANTA.DS125BR111RTWR(CHIPS)':
 'SD_TH': CDS_PINID='SD_TH';
NODE_NAME     R4657 1
 '@S9S_MB_2U_LIB.S9S_MB_2U(SCH_1):PAGE159_I65@PURE_QUANTA.Q_RES(CHIPS)':
 'A': CDS_PINID='A';
NET_NAME
'FM_P2E_BUF2_VODA_DB'
 '@S9S_MB_2U_LIB.S9S_MB_2U(SCH_1):FM_P2E_BUF2_VODA_DB':
 C_SIGNAL='@s9s_mb_2u_lib.s9s_mb_2u(sch_1):fm_p2e_buf2_voda_db';
NODE_NAME     R4647 1
 '@S9S_MB_2U_LIB.S9S_MB_2U(SCH_1):PAGE159_I4@PURE_QUANTA.Q_RES(CHIPS)':
 'A': CDS_PINID='A';
NODE_NAME     U328 4
 '@S9S_MB_2U_LIB.S9S_MB_2U(SCH_1):PAGE159_I95@PURE_QUANTA.DS125BR111RTWR(CHIPS)':
 'SDA||VODA_DB': CDS_PINID='\sda||voda_db\';
NODE_NAME     R4643 2
 '@S9S_MB_2U_LIB.S9S_MB_2U(SCH_1):PAGE159_I13@PURE_QUANTA.Q_RES(CHIPS)':
 'B': CDS_PINID='B';
NET_NAME
'FM_P2E_BUF2_VODB_DB'
 '@S9S_MB_2U_LIB.S9S_MB_2U(SCH_1):FM_P2E_BUF2_VODB_DB':
 C_SIGNAL='@s9s_mb_2u_lib.s9s_mb_2u(sch_1):fm_p2e_buf2_vodb_db';
NODE_NAME     R4653 1
 '@S9S_MB_2U_LIB.S9S_MB_2U(SCH_1):PAGE159_I2@PURE_QUANTA.Q_RES(CHIPS)':
 'A': CDS_PINID='A';
NODE_NAME     U328 5
 '@S9S_MB_2U_LIB.S9S_MB_2U(SCH_1):PAGE159_I95@PURE_QUANTA.DS125BR111RTWR(CHIPS)':
 'SCL||VODB_DB': CDS_PINID='\scl||vodb_db\';
NODE_NAME     R4642 2
 '@S9S_MB_2U_LIB.S9S_MB_2U(SCH_1):PAGE159_I7@PURE_QUANTA.Q_RES(CHIPS)':
 'B': CDS_PINID='B';
NET_NAME
'FM_P2E_BUF2_VOD_SEL'
 '@S9S_MB_2U_LIB.S9S_MB_2U(SCH_1):FM_P2E_BUF2_VOD_SEL':
 C_SIGNAL='@s9s_mb_2u_lib.s9s_mb_2u(sch_1):fm_p2e_buf2_vod_sel';
NODE_NAME     R3386 2
 '@S9S_MB_2U_LIB.S9S_MB_2U(SCH_1):PAGE159_I81@PURE_QUANTA.Q_RES(CHIPS)':
 'B': CDS_PINID='B';
NODE_NAME     U328 17
 '@S9S_MB_2U_LIB.S9S_MB_2U(SCH_1):PAGE159_I95@PURE_QUANTA.DS125BR111RTWR(CHIPS)':
 'VOD_SEL||READEN#': CDS_PINID='\vod_sel||readen#\';
NODE_NAME     R4658 1
 '@S9S_MB_2U_LIB.S9S_MB_2U(SCH_1):PAGE159_I80@PURE_QUANTA.Q_RES(CHIPS)':
 'A': CDS_PINID='A';
NET_NAME
'FM_P2E_EN2_N'
 '@S9S_MB_2U_LIB.S9S_MB_2U(SCH_1):FM_P2E_EN2_N':
 C_SIGNAL='@s9s_mb_2u_lib.s9s_mb_2u(sch_1):fm_p2e_en2_n';
NODE_NAME     U328 6
 '@S9S_MB_2U_LIB.S9S_MB_2U(SCH_1):PAGE159_I95@PURE_QUANTA.DS125BR111RTWR(CHIPS)':
 'PWDN': CDS_PINID='PWDN';
NODE_NAME     R4651 1
 '@S9S_MB_2U_LIB.S9S_MB_2U(SCH_1):PAGE159_I102@PURE_QUANTA.Q_RES(CHIPS)':
 'A': CDS_PINID='A';
NET_NAME
'FM_P2E_EN_N'
 '@S9S_MB_2U_LIB.S9S_MB_2U(SCH_1):FM_P2E_EN_N':
 C_SIGNAL='@s9s_mb_2u_lib.s9s_mb_2u(sch_1):fm_p2e_en_n';
NODE_NAME     R4537 1
 '@S9S_MB_2U_LIB.S9S_MB_2U(SCH_1):PAGE136_I73@PURE_QUANTA.Q_RES(CHIPS)':
 'A': CDS_PINID='A';
NODE_NAME     U237 11
 '@S9S_MB_2U_LIB.S9S_MB_2U(SCH_1):PAGE136_I50@PURE_QUANTA.PI3EQX12902AZLEX(CHIPS)':
 'EN#': CDS_PINID='\en#\';
NET_NAME
'FM_P2E_EQA0'
 '@S9S_MB_2U_LIB.S9S_MB_2U(SCH_1):FM_P2E_EQA0':
 C_SIGNAL='@s9s_mb_2u_lib.s9s_mb_2u(sch_1):fm_p2e_eqa0';
NODE_NAME     R3277 2
 '@S9S_MB_2U_LIB.S9S_MB_2U(SCH_1):PAGE136_I16@PURE_QUANTA.Q_RES(CHIPS)':
 'B': CDS_PINID='B';
NODE_NAME     R3274 1
 '@S9S_MB_2U_LIB.S9S_MB_2U(SCH_1):PAGE136_I6@PURE_QUANTA.Q_RES(CHIPS)':
 'A': CDS_PINID='A';
NODE_NAME     R3278 1
 '@S9S_MB_2U_LIB.S9S_MB_2U(SCH_1):PAGE136_I8@PURE_QUANTA.Q_RES(CHIPS)':
 'A': CDS_PINID='A';
NODE_NAME     U237 21
 '@S9S_MB_2U_LIB.S9S_MB_2U(SCH_1):PAGE136_I50@PURE_QUANTA.PI3EQX12902AZLEX(CHIPS)':
 'EQA0': CDS_PINID='EQA0';
NET_NAME
'FM_P2E_EQA1'
 '@S9S_MB_2U_LIB.S9S_MB_2U(SCH_1):FM_P2E_EQA1':
 C_SIGNAL='@s9s_mb_2u_lib.s9s_mb_2u(sch_1):fm_p2e_eqa1';
NODE_NAME     R3268 1
 '@S9S_MB_2U_LIB.S9S_MB_2U(SCH_1):PAGE136_I2@PURE_QUANTA.Q_RES(CHIPS)':
 'A': CDS_PINID='A';
NODE_NAME     R3272 1
 '@S9S_MB_2U_LIB.S9S_MB_2U(SCH_1):PAGE136_I4@PURE_QUANTA.Q_RES(CHIPS)':
 'A': CDS_PINID='A';
NODE_NAME     R3271 2
 '@S9S_MB_2U_LIB.S9S_MB_2U(SCH_1):PAGE136_I9@PURE_QUANTA.Q_RES(CHIPS)':
 'B': CDS_PINID='B';
NODE_NAME     U237 26
 '@S9S_MB_2U_LIB.S9S_MB_2U(SCH_1):PAGE136_I50@PURE_QUANTA.PI3EQX12902AZLEX(CHIPS)':
 'EQA1': CDS_PINID='EQA1';
NET_NAME
'FM_P2E_EQB0'
 '@S9S_MB_2U_LIB.S9S_MB_2U(SCH_1):FM_P2E_EQB0':
 C_SIGNAL='@s9s_mb_2u_lib.s9s_mb_2u(sch_1):fm_p2e_eqb0';
NODE_NAME     R3282 1
 '@S9S_MB_2U_LIB.S9S_MB_2U(SCH_1):PAGE136_I27@PURE_QUANTA.Q_RES(CHIPS)':
 'A': CDS_PINID='A';
NODE_NAME     U237 20
 '@S9S_MB_2U_LIB.S9S_MB_2U(SCH_1):PAGE136_I50@PURE_QUANTA.PI3EQX12902AZLEX(CHIPS)':
 'EQB0': CDS_PINID='EQB0';
NODE_NAME     R3284 1
 '@S9S_MB_2U_LIB.S9S_MB_2U(SCH_1):PAGE136_I56@PURE_QUANTA.Q_RES(CHIPS)':
 'A': CDS_PINID='A';
NODE_NAME     R3283 2
 '@S9S_MB_2U_LIB.S9S_MB_2U(SCH_1):PAGE136_I57@PURE_QUANTA.Q_RES(CHIPS)':
 'B': CDS_PINID='B';
NET_NAME
'FM_P2E_EQB1'
 '@S9S_MB_2U_LIB.S9S_MB_2U(SCH_1):FM_P2E_EQB1':
 C_SIGNAL='@s9s_mb_2u_lib.s9s_mb_2u(sch_1):fm_p2e_eqb1';
NODE_NAME     R3279 1
 '@S9S_MB_2U_LIB.S9S_MB_2U(SCH_1):PAGE136_I23@PURE_QUANTA.Q_RES(CHIPS)':
 'A': CDS_PINID='A';
NODE_NAME     R3281 1
 '@S9S_MB_2U_LIB.S9S_MB_2U(SCH_1):PAGE136_I25@PURE_QUANTA.Q_RES(CHIPS)':
 'A': CDS_PINID='A';
NODE_NAME     R3280 2
 '@S9S_MB_2U_LIB.S9S_MB_2U(SCH_1):PAGE136_I32@PURE_QUANTA.Q_RES(CHIPS)':
 'B': CDS_PINID='B';
NODE_NAME     U237 15
 '@S9S_MB_2U_LIB.S9S_MB_2U(SCH_1):PAGE136_I50@PURE_QUANTA.PI3EQX12902AZLEX(CHIPS)':
 'EQB1': CDS_PINID='EQB1';
NET_NAME
'FM_P2E_FGA'
 '@S9S_MB_2U_LIB.S9S_MB_2U(SCH_1):FM_P2E_FGA':
 C_SIGNAL='@s9s_mb_2u_lib.s9s_mb_2u(sch_1):fm_p2e_fga';
NODE_NAME     R3273 1
 '@S9S_MB_2U_LIB.S9S_MB_2U(SCH_1):PAGE136_I18@PURE_QUANTA.Q_RES(CHIPS)':
 'A': CDS_PINID='A';
NODE_NAME     R3276 1
 '@S9S_MB_2U_LIB.S9S_MB_2U(SCH_1):PAGE136_I20@PURE_QUANTA.Q_RES(CHIPS)':
 'A': CDS_PINID='A';
NODE_NAME     R3275 2
 '@S9S_MB_2U_LIB.S9S_MB_2U(SCH_1):PAGE136_I21@PURE_QUANTA.Q_RES(CHIPS)':
 'B': CDS_PINID='B';
NODE_NAME     U237 27
 '@S9S_MB_2U_LIB.S9S_MB_2U(SCH_1):PAGE136_I50@PURE_QUANTA.PI3EQX12902AZLEX(CHIPS)':
 'FGA': CDS_PINID='FGA';
NET_NAME
'FM_P2E_FGB'
 '@S9S_MB_2U_LIB.S9S_MB_2U(SCH_1):FM_P2E_FGB':
 C_SIGNAL='@s9s_mb_2u_lib.s9s_mb_2u(sch_1):fm_p2e_fgb';
NODE_NAME     R3267 1
 '@S9S_MB_2U_LIB.S9S_MB_2U(SCH_1):PAGE136_I12@PURE_QUANTA.Q_RES(CHIPS)':
 'A': CDS_PINID='A';
NODE_NAME     R3270 1
 '@S9S_MB_2U_LIB.S9S_MB_2U(SCH_1):PAGE136_I14@PURE_QUANTA.Q_RES(CHIPS)':
 'A': CDS_PINID='A';
NODE_NAME     R3269 2
 '@S9S_MB_2U_LIB.S9S_MB_2U(SCH_1):PAGE136_I15@PURE_QUANTA.Q_RES(CHIPS)':
 'B': CDS_PINID='B';
NODE_NAME     U237 14
 '@S9S_MB_2U_LIB.S9S_MB_2U(SCH_1):PAGE136_I50@PURE_QUANTA.PI3EQX12902AZLEX(CHIPS)':
 'FGB': CDS_PINID='FGB';
NET_NAME
'FM_P2E_MODE'
 '@S9S_MB_2U_LIB.S9S_MB_2U(SCH_1):FM_P2E_MODE':
 C_SIGNAL='@s9s_mb_2u_lib.s9s_mb_2u(sch_1):fm_p2e_mode';
NODE_NAME     R3293 1
 '@S9S_MB_2U_LIB.S9S_MB_2U(SCH_1):PAGE136_I88@PURE_QUANTA.Q_RES(CHIPS)':
 'A': CDS_PINID='A';
NODE_NAME     U237 30
 '@S9S_MB_2U_LIB.S9S_MB_2U(SCH_1):PAGE136_I50@PURE_QUANTA.PI3EQX12902AZLEX(CHIPS)':
 'MODE': CDS_PINID='MODE';
NODE_NAME     R3266 2
 '@S9S_MB_2U_LIB.S9S_MB_2U(SCH_1):PAGE136_I89@PURE_QUANTA.Q_RES(CHIPS)':
 'B': CDS_PINID='B';
NET_NAME
'FM_P2E_SWA'
 '@S9S_MB_2U_LIB.S9S_MB_2U(SCH_1):FM_P2E_SWA':
 C_SIGNAL='@s9s_mb_2u_lib.s9s_mb_2u(sch_1):fm_p2e_swa';
NODE_NAME     R3290 1
 '@S9S_MB_2U_LIB.S9S_MB_2U(SCH_1):PAGE136_I68@PURE_QUANTA.Q_RES(CHIPS)':
 'A': CDS_PINID='A';
NODE_NAME     R3289 2
 '@S9S_MB_2U_LIB.S9S_MB_2U(SCH_1):PAGE136_I69@PURE_QUANTA.Q_RES(CHIPS)':
 'B': CDS_PINID='B';
NODE_NAME     U237 29
 '@S9S_MB_2U_LIB.S9S_MB_2U(SCH_1):PAGE136_I50@PURE_QUANTA.PI3EQX12902AZLEX(CHIPS)':
 'SWA': CDS_PINID='SWA';
NODE_NAME     R3288 1
 '@S9S_MB_2U_LIB.S9S_MB_2U(SCH_1):PAGE136_I66@PURE_QUANTA.Q_RES(CHIPS)':
 'A': CDS_PINID='A';
NET_NAME
'FM_P2E_SWB'
 '@S9S_MB_2U_LIB.S9S_MB_2U(SCH_1):FM_P2E_SWB':
 C_SIGNAL='@s9s_mb_2u_lib.s9s_mb_2u(sch_1):fm_p2e_swb';
NODE_NAME     U237 12
 '@S9S_MB_2U_LIB.S9S_MB_2U(SCH_1):PAGE136_I50@PURE_QUANTA.PI3EQX12902AZLEX(CHIPS)':
 'SWB': CDS_PINID='SWB';
NODE_NAME     R3285 1
 '@S9S_MB_2U_LIB.S9S_MB_2U(SCH_1):PAGE136_I61@PURE_QUANTA.Q_RES(CHIPS)':
 'A': CDS_PINID='A';
NODE_NAME     R3287 1
 '@S9S_MB_2U_LIB.S9S_MB_2U(SCH_1):PAGE136_I63@PURE_QUANTA.Q_RES(CHIPS)':
 'A': CDS_PINID='A';
NODE_NAME     R3286 2
 '@S9S_MB_2U_LIB.S9S_MB_2U(SCH_1):PAGE136_I64@PURE_QUANTA.Q_RES(CHIPS)':
 'B': CDS_PINID='B';
NET_NAME
'FM_P5V_EN'
 '@S9S_MB_2U_LIB.S9S_MB_2U(SCH_1):FM_P5V_EN':
 C_SIGNAL='@s9s_mb_2u_lib.s9s_mb_2u(sch_1):fm_p5v_en';
NODE_NAME     U249 G21
 '@S9S_MB_2U_LIB.S9S_MB_2U(SCH_1):PAGE313_I1@PURE_QUANTA.LCMXO3LF9400C5BG484C(CHIPS)':
 'PR6A': CDS_PINID='PR6A';
NODE_NAME     R1640 1
 '@S9S_MB_2U_LIB.S9S_MB_2U(SCH_1):PAGE246_I9@PURE_QUANTA.Q_RES(CHIPS)':
 'A': CDS_PINID='A';
NET_NAME
'FM_PASSWORD_CLEAR_N'
 '@S9S_MB_2U_LIB.S9S_MB_2U(SCH_1):FM_PASSWORD_CLEAR_N':
 C_SIGNAL='@s9s_mb_2u_lib.s9s_mb_2u(sch_1):fm_password_clear_n';
NODE_NAME     U4 AB8
 '@S9S_MB_2U_LIB.S9S_MB_2U(SCH_1):PAGE176_I22@PURE_QUANTA.EMMITSBURG_REV0P9(CHIPS)':
 'GPP_L_5': CDS_PINID='GPP_L_5';
NODE_NAME     R1343 2
 '@S9S_MB_2U_LIB.S9S_MB_2U(SCH_1):PAGE189_I113@PURE_QUANTA.Q_RES(CHIPS)':
 'B': CDS_PINID='B';
NODE_NAME     J104 14
 '@S9S_MB_2U_LIB.S9S_MB_2U(SCH_1):PAGE189_I134@PURE_QUANTA.CONN14_210HP207GBR1(CHIPS)':
 '14': CDS_PINID='\14\';
NET_NAME
'FM_PCHHOT_N'
 '@S9S_MB_2U_LIB.S9S_MB_2U(SCH_1):FM_PCHHOT_N':
 C_SIGNAL='@s9s_mb_2u_lib.s9s_mb_2u(sch_1):fm_pchhot_n';
NODE_NAME     U4 AH2
 '@S9S_MB_2U_LIB.S9S_MB_2U(SCH_1):PAGE175_I93@PURE_QUANTA.EMMITSBURG_REV0P9(CHIPS)':
 'GPP_D_12_PCHHOT_N': CDS_PINID='GPP_D_12_PCHHOT_N';
NODE_NAME     R474 1
 '@S9S_MB_2U_LIB.S9S_MB_2U(SCH_1):PAGE175_I213@PURE_QUANTA.Q_RES(CHIPS)':
 'A': CDS_PINID='A';
NODE_NAME     R1955 2
 '@S9S_MB_2U_LIB.S9S_MB_2U(SCH_1):PAGE192_I72@PURE_QUANTA.Q_RES(CHIPS)':
 'B': CDS_PINID='B';
NET_NAME
'FM_PCHHOT_R_N'
 '@S9S_MB_2U_LIB.S9S_MB_2U(SCH_1):FM_PCHHOT_R_N':
 C_SIGNAL='@s9s_mb_2u_lib.s9s_mb_2u(sch_1):fm_pchhot_r_n';
NODE_NAME     R474 2
 '@S9S_MB_2U_LIB.S9S_MB_2U(SCH_1):PAGE175_I213@PURE_QUANTA.Q_RES(CHIPS)':
 'B': CDS_PINID='B';
NODE_NAME     U249 AB17
 '@S9S_MB_2U_LIB.S9S_MB_2U(SCH_1):PAGE312_I1@PURE_QUANTA.LCMXO3LF9400C5BG484C(CHIPS)':
 'PB40A': CDS_PINID='PB40A';
NET_NAME
'FM_PCH_BIOS_RCVR_MODE'
 '@S9S_MB_2U_LIB.S9S_MB_2U(SCH_1):FM_PCH_BIOS_RCVR_MODE':
 C_SIGNAL='@s9s_mb_2u_lib.s9s_mb_2u(sch_1):fm_pch_bios_rcvr_mode';
NODE_NAME     U4 R7
 '@S9S_MB_2U_LIB.S9S_MB_2U(SCH_1):PAGE176_I22@PURE_QUANTA.EMMITSBURG_REV0P9(CHIPS)':
 'GPP_M_11': CDS_PINID='GPP_M_11';
NODE_NAME     R1338 1
 '@S9S_MB_2U_LIB.S9S_MB_2U(SCH_1):PAGE189_I107@PURE_QUANTA.Q_RES(CHIPS)':
 'A': CDS_PINID='A';
NODE_NAME     J104 4
 '@S9S_MB_2U_LIB.S9S_MB_2U(SCH_1):PAGE189_I134@PURE_QUANTA.CONN14_210HP207GBR1(CHIPS)':
 '4': CDS_PINID='\4\';
NET_NAME
'FM_PCH_BMC_RST_N'
 '@S9S_MB_2U_LIB.S9S_MB_2U(SCH_1):FM_PCH_BMC_RST_N':
 C_SIGNAL='@s9s_mb_2u_lib.s9s_mb_2u(sch_1):fm_pch_bmc_rst_n';
NODE_NAME     U249 Y10
 '@S9S_MB_2U_LIB.S9S_MB_2U(SCH_1):PAGE312_I1@PURE_QUANTA.LCMXO3LF9400C5BG484C(CHIPS)':
 'PB21D': CDS_PINID='PB21D';
NODE_NAME     R4723 2
 '@S9S_MB_2U_LIB.S9S_MB_2U(SCH_1):PAGE312_I213@PURE_QUANTA.Q_RES(CHIPS)':
 'B': CDS_PINID='B';
NET_NAME
'FM_PCH_BMC_RST_R_N'
 '@S9S_MB_2U_LIB.S9S_MB_2U(SCH_1):FM_PCH_BMC_RST_R_N':
 C_SIGNAL='@s9s_mb_2u_lib.s9s_mb_2u(sch_1):fm_pch_bmc_rst_r_n';
NODE_NAME     U4 U3
 '@S9S_MB_2U_LIB.S9S_MB_2U(SCH_1):PAGE176_I22@PURE_QUANTA.EMMITSBURG_REV0P9(CHIPS)':
 'GPP_I_12_HDA_BCLK': CDS_PINID='GPP_I_12_HDA_BCLK';
NODE_NAME     R4722 1
 '@S9S_MB_2U_LIB.S9S_MB_2U(SCH_1):PAGE176_I246@PURE_QUANTA.Q_RES(CHIPS)':
 'A': CDS_PINID='A';
NODE_NAME     R4723 1
 '@S9S_MB_2U_LIB.S9S_MB_2U(SCH_1):PAGE312_I213@PURE_QUANTA.Q_RES(CHIPS)':
 'A': CDS_PINID='A';
NET_NAME
'FM_PCH_BMC_THERMTRIP_N'
 '@S9S_MB_2U_LIB.S9S_MB_2U(SCH_1):FM_PCH_BMC_THERMTRIP_N':
 C_SIGNAL='@s9s_mb_2u_lib.s9s_mb_2u(sch_1):fm_pch_bmc_thermtrip_n';
NODE_NAME     R1263 2
 '@S9S_MB_2U_LIB.S9S_MB_2U(SCH_1):PAGE191_I29@PURE_QUANTA.Q_RES(CHIPS)':
 'B': CDS_PINID='B';
NODE_NAME     U249 AB8
 '@S9S_MB_2U_LIB.S9S_MB_2U(SCH_1):PAGE312_I1@PURE_QUANTA.LCMXO3LF9400C5BG484C(CHIPS)':
 'PB18B': CDS_PINID='PB18B';
NET_NAME
'FM_PCH_BOOT_BIOS_STRAP'
 '@S9S_MB_2U_LIB.S9S_MB_2U(SCH_1):FM_PCH_BOOT_BIOS_STRAP':
 C_SIGNAL='@s9s_mb_2u_lib.s9s_mb_2u(sch_1):fm_pch_boot_bios_strap';
NODE_NAME     U4 W1
 '@S9S_MB_2U_LIB.S9S_MB_2U(SCH_1):PAGE175_I93@PURE_QUANTA.EMMITSBURG_REV0P9(CHIPS)':
 'GPP_D_23': CDS_PINID='GPP_D_23';
NODE_NAME     R371 2
 '@S9S_MB_2U_LIB.S9S_MB_2U(SCH_1):PAGE186_I45@PURE_QUANTA.Q_RES(CHIPS)':
 'B': CDS_PINID='B';
NODE_NAME     R372 1
 '@S9S_MB_2U_LIB.S9S_MB_2U(SCH_1):PAGE186_I46@PURE_QUANTA.Q_RES(CHIPS)':
 'A': CDS_PINID='A';
NET_NAME
'FM_PCH_CONSENT_STRAP_N'
 '@S9S_MB_2U_LIB.S9S_MB_2U(SCH_1):FM_PCH_CONSENT_STRAP_N':
 C_SIGNAL='@s9s_mb_2u_lib.s9s_mb_2u(sch_1):fm_pch_consent_strap_n';
NODE_NAME     R771 2
 '@S9S_MB_2U_LIB.S9S_MB_2U(SCH_1):PAGE133_I120@PURE_QUANTA.Q_RES(CHIPS)':
 'B': CDS_PINID='B';
NODE_NAME     U4 AT18
 '@S9S_MB_2U_LIB.S9S_MB_2U(SCH_1):PAGE177_I27@PURE_QUANTA.EMMITSBURG_REV0P9(CHIPS)':
 'GPPC_S_5_CPU_GP_3': CDS_PINID='GPPC_S_5_CPU_GP_3';
NODE_NAME     R502 2
 '@S9S_MB_2U_LIB.S9S_MB_2U(SCH_1):PAGE186_I68@PURE_QUANTA.Q_RES(CHIPS)':
 'B': CDS_PINID='B';
NODE_NAME     R1962 1
 '@S9S_MB_2U_LIB.S9S_MB_2U(SCH_1):PAGE186_I90@PURE_QUANTA.Q_RES(CHIPS)':
 'A': CDS_PINID='A';
NET_NAME
'FM_PCH_CPU_PWR_DEBUG_N'
 '@S9S_MB_2U_LIB.S9S_MB_2U(SCH_1):FM_PCH_CPU_PWR_DEBUG_N':
 C_SIGNAL='@s9s_mb_2u_lib.s9s_mb_2u(sch_1):fm_pch_cpu_pwr_debug_n';
NODE_NAME     U4 F5
 '@S9S_MB_2U_LIB.S9S_MB_2U(SCH_1):PAGE174_I36@PURE_QUANTA.EMMITSBURG_REV0P9(CHIPS)':
 'CPU_PWR_DEBUG_N': CDS_PINID='CPU_PWR_DEBUG_N';
NODE_NAME     R1247 1
 '@S9S_MB_2U_LIB.S9S_MB_2U(SCH_1):PAGE191_I14@PURE_QUANTA.Q_RES(CHIPS)':
 'A': CDS_PINID='A';
NET_NAME
'FM_PCH_CRASHLOG_TRIG_N'
 '@S9S_MB_2U_LIB.S9S_MB_2U(SCH_1):FM_PCH_CRASHLOG_TRIG_N':
 C_SIGNAL='@s9s_mb_2u_lib.s9s_mb_2u(sch_1):fm_pch_crashlog_trig_n';
NODE_NAME     U4 AE3
 '@S9S_MB_2U_LIB.S9S_MB_2U(SCH_1):PAGE175_I93@PURE_QUANTA.EMMITSBURG_REV0P9(CHIPS)':
 'GPP_D_8_CRASHLOG_TRIG_N': CDS_PINID='GPP_D_8_CRASHLOG_TRIG_N';
NODE_NAME     R699 2
 '@S9S_MB_2U_LIB.S9S_MB_2U(SCH_1):PAGE175_I102@PURE_QUANTA.Q_RES(CHIPS)':
 'B': CDS_PINID='B';
NET_NAME
'FM_PCH_CRASHLOG_TRIG_R_N'
 '@S9S_MB_2U_LIB.S9S_MB_2U(SCH_1):FM_PCH_CRASHLOG_TRIG_R_N':
 C_SIGNAL='@s9s_mb_2u_lib.s9s_mb_2u(sch_1):fm_pch_crashlog_trig_r_n';
NODE_NAME     R699 1
 '@S9S_MB_2U_LIB.S9S_MB_2U(SCH_1):PAGE175_I102@PURE_QUANTA.Q_RES(CHIPS)':
 'A': CDS_PINID='A';
NODE_NAME     U249 AB7
 '@S9S_MB_2U_LIB.S9S_MB_2U(SCH_1):PAGE312_I1@PURE_QUANTA.LCMXO3LF9400C5BG484C(CHIPS)':
 'PB13B': CDS_PINID='PB13B';
NET_NAME
'FM_PCH_DFXTESTMODE'
 '@S9S_MB_2U_LIB.S9S_MB_2U(SCH_1):FM_PCH_DFXTESTMODE':
 C_SIGNAL='@s9s_mb_2u_lib.s9s_mb_2u(sch_1):fm_pch_dfxtestmode';
NODE_NAME     U4 P3
 '@S9S_MB_2U_LIB.S9S_MB_2U(SCH_1):PAGE176_I22@PURE_QUANTA.EMMITSBURG_REV0P9(CHIPS)':
 'GPP_I_22': CDS_PINID='GPP_I_22';
NODE_NAME     R1497 1
 '@S9S_MB_2U_LIB.S9S_MB_2U(SCH_1):PAGE188_I70@PURE_QUANTA.Q_RES(CHIPS)':
 'A': CDS_PINID='A';
NODE_NAME     R1496 2
 '@S9S_MB_2U_LIB.S9S_MB_2U(SCH_1):PAGE188_I71@PURE_QUANTA.Q_RES(CHIPS)':
 'B': CDS_PINID='B';
NET_NAME
'FM_PCH_EXTERNALCLKMODE'
 '@S9S_MB_2U_LIB.S9S_MB_2U(SCH_1):FM_PCH_EXTERNALCLKMODE':
 C_SIGNAL='@s9s_mb_2u_lib.s9s_mb_2u(sch_1):fm_pch_externalclkmode';
NODE_NAME     U4 L2
 '@S9S_MB_2U_LIB.S9S_MB_2U(SCH_1):PAGE176_I22@PURE_QUANTA.EMMITSBURG_REV0P9(CHIPS)':
 'GPPC_H_6': CDS_PINID='GPPC_H_6';
NODE_NAME     R611 2
 '@S9S_MB_2U_LIB.S9S_MB_2U(SCH_1):PAGE187_I43@PURE_QUANTA.Q_RES(CHIPS)':
 'B': CDS_PINID='B';
NODE_NAME     R612 1
 '@S9S_MB_2U_LIB.S9S_MB_2U(SCH_1):PAGE187_I44@PURE_QUANTA.Q_RES(CHIPS)':
 'A': CDS_PINID='A';
NET_NAME
'FM_PCH_GLB_RST_WARN_N'
 '@S9S_MB_2U_LIB.S9S_MB_2U(SCH_1):FM_PCH_GLB_RST_WARN_N':
 C_SIGNAL='@s9s_mb_2u_lib.s9s_mb_2u(sch_1):fm_pch_glb_rst_warn_n';
NODE_NAME     U4 AA1
 '@S9S_MB_2U_LIB.S9S_MB_2U(SCH_1):PAGE175_I93@PURE_QUANTA.EMMITSBURG_REV0P9(CHIPS)':
 'GPP_D_21_GLB_RST_WARN_N': CDS_PINID='GPP_D_21_GLB_RST_WARN_N';
NODE_NAME     R3041 2
 '@S9S_MB_2U_LIB.S9S_MB_2U(SCH_1):PAGE192_I6@PURE_QUANTA.Q_RES(CHIPS)':
 'B': CDS_PINID='B';
NODE_NAME     R1313 1
 '@S9S_MB_2U_LIB.S9S_MB_2U(SCH_1):PAGE193_I21@PURE_QUANTA.Q_RES(CHIPS)':
 'A': CDS_PINID='A';
NET_NAME
'FM_PCH_IO_EXPANDER'
 '@S9S_MB_2U_LIB.S9S_MB_2U(SCH_1):FM_PCH_IO_EXPANDER':
 C_SIGNAL='@s9s_mb_2u_lib.s9s_mb_2u(sch_1):fm_pch_io_expander';
NODE_NAME     U4 K1
 '@S9S_MB_2U_LIB.S9S_MB_2U(SCH_1):PAGE176_I22@PURE_QUANTA.EMMITSBURG_REV0P9(CHIPS)':
 'GPPC_H_1': CDS_PINID='GPPC_H_1';
NODE_NAME     R618 1
 '@S9S_MB_2U_LIB.S9S_MB_2U(SCH_1):PAGE187_I53@PURE_QUANTA.Q_RES(CHIPS)':
 'A': CDS_PINID='A';
NODE_NAME     R617 2
 '@S9S_MB_2U_LIB.S9S_MB_2U(SCH_1):PAGE187_I54@PURE_QUANTA.Q_RES(CHIPS)':
 'B': CDS_PINID='B';
NET_NAME
'FM_PCH_MCRO_LDO'
 '@S9S_MB_2U_LIB.S9S_MB_2U(SCH_1):FM_PCH_MCRO_LDO':
 C_SIGNAL='@s9s_mb_2u_lib.s9s_mb_2u(sch_1):fm_pch_mcro_ldo';
NODE_NAME     U4 K3
 '@S9S_MB_2U_LIB.S9S_MB_2U(SCH_1):PAGE176_I22@PURE_QUANTA.EMMITSBURG_REV0P9(CHIPS)':
 'GPPC_H_7': CDS_PINID='GPPC_H_7';
NODE_NAME     R1220 2
 '@S9S_MB_2U_LIB.S9S_MB_2U(SCH_1):PAGE188_I63@PURE_QUANTA.Q_RES(CHIPS)':
 'B': CDS_PINID='B';
NODE_NAME     R1221 1
 '@S9S_MB_2U_LIB.S9S_MB_2U(SCH_1):PAGE188_I64@PURE_QUANTA.Q_RES(CHIPS)':
 'A': CDS_PINID='A';
NET_NAME
'FM_PCH_P1V8_AUX_EN'
 '@S9S_MB_2U_LIB.S9S_MB_2U(SCH_1):FM_PCH_P1V8_AUX_EN':
 C_SIGNAL='@s9s_mb_2u_lib.s9s_mb_2u(sch_1):fm_pch_p1v8_aux_en';
NODE_NAME     R1404 1
 '@S9S_MB_2U_LIB.S9S_MB_2U(SCH_1):PAGE208_I25@PURE_QUANTA.Q_RES(CHIPS)':
 'A': CDS_PINID='A';
NODE_NAME     U249 F19
 '@S9S_MB_2U_LIB.S9S_MB_2U(SCH_1):PAGE313_I1@PURE_QUANTA.LCMXO3LF9400C5BG484C(CHIPS)':
 'PR5D': CDS_PINID='PR5D';
NODE_NAME     R2358 1
 '@S9S_MB_2U_LIB.S9S_MB_2U(SCH_1):PAGE249_I17@PURE_QUANTA.Q_RES(CHIPS)':
 'A': CDS_PINID='A';
NET_NAME
'FM_PCH_P1V8_AUX_EN_R'
 '@S9S_MB_2U_LIB.S9S_MB_2U(SCH_1):FM_PCH_P1V8_AUX_EN_R':
 C_SIGNAL='@s9s_mb_2u_lib.s9s_mb_2u(sch_1):fm_pch_p1v8_aux_en_r';
NODE_NAME     PU74 5
 '@S9S_MB_2U_LIB.S9S_MB_2U(SCH_1):PAGE249_I26@PURE_QUANTA.NB682GDZ(CHIPS)':
 'EN': CDS_PINID='EN';
NODE_NAME     R2358 2
 '@S9S_MB_2U_LIB.S9S_MB_2U(SCH_1):PAGE249_I17@PURE_QUANTA.Q_RES(CHIPS)':
 'B': CDS_PINID='B';
NODE_NAME     PR1850 2
 '@S9S_MB_2U_LIB.S9S_MB_2U(SCH_1):PAGE249_I11@PURE_QUANTA.Q_RES(CHIPS)':
 'B': CDS_PINID='B';
NET_NAME
'FM_PCH_PLD_GLB_RST_WARN_N'
 '@S9S_MB_2U_LIB.S9S_MB_2U(SCH_1):FM_PCH_PLD_GLB_RST_WARN_N':
 C_SIGNAL='@s9s_mb_2u_lib.s9s_mb_2u(sch_1):fm_pch_pld_glb_rst_warn_n';
NODE_NAME     R1313 2
 '@S9S_MB_2U_LIB.S9S_MB_2U(SCH_1):PAGE193_I21@PURE_QUANTA.Q_RES(CHIPS)':
 'B': CDS_PINID='B';
NODE_NAME     U249 AA16
 '@S9S_MB_2U_LIB.S9S_MB_2U(SCH_1):PAGE312_I1@PURE_QUANTA.LCMXO3LF9400C5BG484C(CHIPS)':
 'PB38B': CDS_PINID='PB38B';
NET_NAME
'FM_PCH_PRSNT_N'
 '@S9S_MB_2U_LIB.S9S_MB_2U(SCH_1):FM_PCH_PRSNT_N':
 C_SIGNAL='@s9s_mb_2u_lib.s9s_mb_2u(sch_1):fm_pch_prsnt_n';
NODE_NAME     R498 2
 '@S9S_MB_2U_LIB.S9S_MB_2U(SCH_1):PAGE177_I24@PURE_QUANTA.Q_RES(CHIPS)':
 'B': CDS_PINID='B';
NODE_NAME     U4 A41
 '@S9S_MB_2U_LIB.S9S_MB_2U(SCH_1):PAGE177_I27@PURE_QUANTA.EMMITSBURG_REV0P9(CHIPS)':
 'VSS_A41': CDS_PINID='VSS_A41';
NODE_NAME     U249 B4
 '@S9S_MB_2U_LIB.S9S_MB_2U(SCH_1):PAGE314_I188@PURE_QUANTA.LCMXO3LF9400C5BG484C(CHIPS)':
 'PT12A': CDS_PINID='PT12A';
NET_NAME
'FM_PCH_RING_OSC_BYPASS_MGPIO_TE'
 '@S9S_MB_2U_LIB.S9S_MB_2U(SCH_1):FM_PCH_RING_OSC_BYPASS_MGPIO_TEST2':
 C_SIGNAL='@s9s_mb_2u_lib.s9s_mb_2u(sch_1):fm_pch_ring_osc_bypass_mgpio_test2';
NODE_NAME     U4 G2
 '@S9S_MB_2U_LIB.S9S_MB_2U(SCH_1):PAGE176_I22@PURE_QUANTA.EMMITSBURG_REV0P9(CHIPS)':
 'GPPC_H_16_FLEX_CLK_OUT_1': CDS_PINID='GPPC_H_16_FLEX_CLK_OUT_1';
NODE_NAME     R1476 1
 '@S9S_MB_2U_LIB.S9S_MB_2U(SCH_1):PAGE188_I43@PURE_QUANTA.Q_RES(CHIPS)':
 'A': CDS_PINID='A';
NODE_NAME     R1475 2
 '@S9S_MB_2U_LIB.S9S_MB_2U(SCH_1):PAGE188_I44@PURE_QUANTA.Q_RES(CHIPS)':
 'B': CDS_PINID='B';
NET_NAME
'FM_PCH_SATA_RAID_KEY'
 '@S9S_MB_2U_LIB.S9S_MB_2U(SCH_1):FM_PCH_SATA_RAID_KEY':
 C_SIGNAL='@s9s_mb_2u_lib.s9s_mb_2u(sch_1):fm_pch_sata_raid_key';
NODE_NAME     U4 BD11
 '@S9S_MB_2U_LIB.S9S_MB_2U(SCH_1):PAGE175_I93@PURE_QUANTA.EMMITSBURG_REV0P9(CHIPS)':
 'GPPC_A_16_SRCCLKREQ_N_6': CDS_PINID='GPPC_A_16_SRCCLKREQ_N_6';
NODE_NAME     R1487 1
 '@S9S_MB_2U_LIB.S9S_MB_2U(SCH_1):PAGE175_I125@PURE_QUANTA.Q_RES(CHIPS)':
 'A': CDS_PINID='A';
NODE_NAME     R1271 2
 '@S9S_MB_2U_LIB.S9S_MB_2U(SCH_1):PAGE183_I5@PURE_QUANTA.Q_RES(CHIPS)':
 'B': CDS_PINID='B';
NET_NAME
'FM_PCH_SKIP_RTC_CLOCK'
 '@S9S_MB_2U_LIB.S9S_MB_2U(SCH_1):FM_PCH_SKIP_RTC_CLOCK':
 C_SIGNAL='@s9s_mb_2u_lib.s9s_mb_2u(sch_1):fm_pch_skip_rtc_clock';
NODE_NAME     U4 AU10
 '@S9S_MB_2U_LIB.S9S_MB_2U(SCH_1):PAGE174_I36@PURE_QUANTA.EMMITSBURG_REV0P9(CHIPS)':
 'GPP_O_7': CDS_PINID='GPP_O_7';
NODE_NAME     R621 2
 '@S9S_MB_2U_LIB.S9S_MB_2U(SCH_1):PAGE187_I55@PURE_QUANTA.Q_RES(CHIPS)':
 'B': CDS_PINID='B';
NODE_NAME     R622 1
 '@S9S_MB_2U_LIB.S9S_MB_2U(SCH_1):PAGE187_I56@PURE_QUANTA.Q_RES(CHIPS)':
 'A': CDS_PINID='A';
NET_NAME
'FM_PCH_SLP_S3_N'
 '@S9S_MB_2U_LIB.S9S_MB_2U(SCH_1):FM_PCH_SLP_S3_N':
 C_SIGNAL='@s9s_mb_2u_lib.s9s_mb_2u(sch_1):fm_pch_slp_s3_n';
NODE_NAME     U4 AP8
 '@S9S_MB_2U_LIB.S9S_MB_2U(SCH_1):PAGE174_I36@PURE_QUANTA.EMMITSBURG_REV0P9(CHIPS)':
 'SLP_S3_N': CDS_PINID='SLP_S3_N';
NODE_NAME     R1995 1
 '@S9S_MB_2U_LIB.S9S_MB_2U(SCH_1):PAGE212_I86@PURE_QUANTA.Q_RES(CHIPS)':
 'A': CDS_PINID='A';
NODE_NAME     Q78 2
 '@S9S_MB_2U_LIB.S9S_MB_2U(SCH_1):PAGE242_I34@PURE_QUANTA.MOSFET_NCH_DUAL(CHIPS)':
 'G1': CDS_PINID='G1';
NET_NAME
'FM_PCH_SLP_S4_N'
 '@S9S_MB_2U_LIB.S9S_MB_2U(SCH_1):FM_PCH_SLP_S4_N':
 C_SIGNAL='@s9s_mb_2u_lib.s9s_mb_2u(sch_1):fm_pch_slp_s4_n';
NODE_NAME     U4 AL13
 '@S9S_MB_2U_LIB.S9S_MB_2U(SCH_1):PAGE174_I36@PURE_QUANTA.EMMITSBURG_REV0P9(CHIPS)':
 'SLP_S4_N': CDS_PINID='SLP_S4_N';
NODE_NAME     R1996 1
 '@S9S_MB_2U_LIB.S9S_MB_2U(SCH_1):PAGE212_I87@PURE_QUANTA.Q_RES(CHIPS)':
 'A': CDS_PINID='A';
NODE_NAME     Q77 5
 '@S9S_MB_2U_LIB.S9S_MB_2U(SCH_1):PAGE242_I3@PURE_QUANTA.MOSFET_NCH_DUAL(CHIPS)':
 'G2': CDS_PINID='G2';
NET_NAME
'FM_PCH_SLP_SUS_N'
 '@S9S_MB_2U_LIB.S9S_MB_2U(SCH_1):FM_PCH_SLP_SUS_N':
 C_SIGNAL='@s9s_mb_2u_lib.s9s_mb_2u(sch_1):fm_pch_slp_sus_n';
NODE_NAME     U4 AL7
 '@S9S_MB_2U_LIB.S9S_MB_2U(SCH_1):PAGE174_I36@PURE_QUANTA.EMMITSBURG_REV0P9(CHIPS)':
 'SLP_SUS_N': CDS_PINID='SLP_SUS_N';
NODE_NAME     R1736 1
 '@S9S_MB_2U_LIB.S9S_MB_2U(SCH_1):PAGE174_I99@PURE_QUANTA.Q_RES(CHIPS)':
 'A': CDS_PINID='A';
NET_NAME
'FM_PCH_SPARE0'
 '@S9S_MB_2U_LIB.S9S_MB_2U(SCH_1):FM_PCH_SPARE0':
 C_SIGNAL='@s9s_mb_2u_lib.s9s_mb_2u(sch_1):fm_pch_spare0';
NODE_NAME     U4 AN10
 '@S9S_MB_2U_LIB.S9S_MB_2U(SCH_1):PAGE174_I36@PURE_QUANTA.EMMITSBURG_REV0P9(CHIPS)':
 'GPP_O_0': CDS_PINID='GPP_O_0';
NODE_NAME     R3038 2
 '@S9S_MB_2U_LIB.S9S_MB_2U(SCH_1):PAGE188_I57@PURE_QUANTA.Q_RES(CHIPS)':
 'B': CDS_PINID='B';
NET_NAME
'FM_PCH_SPKR'
 '@S9S_MB_2U_LIB.S9S_MB_2U(SCH_1):FM_PCH_SPKR':
 C_SIGNAL='@s9s_mb_2u_lib.s9s_mb_2u(sch_1):fm_pch_spkr';
NODE_NAME     U4 AU16
 '@S9S_MB_2U_LIB.S9S_MB_2U(SCH_1):PAGE177_I27@PURE_QUANTA.EMMITSBURG_REV0P9(CHIPS)':
 'GPPC_S_1_SPKR_TIME_SYNC_1': CDS_PINID='GPPC_S_1_SPKR_TIME_SYNC_1';
NODE_NAME     R367 2
 '@S9S_MB_2U_LIB.S9S_MB_2U(SCH_1):PAGE186_I11@PURE_QUANTA.Q_RES(CHIPS)':
 'B': CDS_PINID='B';
NODE_NAME     R3325 1
 '@S9S_MB_2U_LIB.S9S_MB_2U(SCH_1):PAGE186_I92@PURE_QUANTA.Q_RES(CHIPS)':
 'A': CDS_PINID='A';
NODE_NAME     R4612 1
 '@S9S_MB_2U_LIB.S9S_MB_2U(SCH_1):PAGE313_I211@PURE_QUANTA.Q_RES(CHIPS)':
 'A': CDS_PINID='A';
NODE_NAME     R3302 2
 '@S9S_MB_2U_LIB.S9S_MB_2U(SCH_1):PAGE227_I48@PURE_QUANTA.Q_RES(CHIPS)':
 'B': CDS_PINID='B';
NET_NAME
'FM_PCH_SPKR_R'
 '@S9S_MB_2U_LIB.S9S_MB_2U(SCH_1):FM_PCH_SPKR_R':
 C_SIGNAL='@s9s_mb_2u_lib.s9s_mb_2u(sch_1):fm_pch_spkr_r';
NODE_NAME     U249 W20
 '@S9S_MB_2U_LIB.S9S_MB_2U(SCH_1):PAGE313_I1@PURE_QUANTA.LCMXO3LF9400C5BG484C(CHIPS)':
 'PR30B': CDS_PINID='PR30B';
NODE_NAME     R4612 2
 '@S9S_MB_2U_LIB.S9S_MB_2U(SCH_1):PAGE313_I211@PURE_QUANTA.Q_RES(CHIPS)':
 'B': CDS_PINID='B';
NET_NAME
'FM_PCH_TRIGGER0_N'
 '@S9S_MB_2U_LIB.S9S_MB_2U(SCH_1):FM_PCH_TRIGGER0_N':
 C_SIGNAL='@s9s_mb_2u_lib.s9s_mb_2u(sch_1):fm_pch_trigger0_n';
NODE_NAME     R20 2
 '@S9S_MB_2U_LIB.S9S_MB_2U(SCH_1):PAGE16_I31@PURE_QUANTA.Q_RES(CHIPS)':
 'B': CDS_PINID='B';
NODE_NAME     R1200 1
 '@S9S_MB_2U_LIB.S9S_MB_2U(SCH_1):PAGE174_I60@PURE_QUANTA.Q_RES(CHIPS)':
 'A': CDS_PINID='A';
NET_NAME
'FM_PCH_TRIGGER0_R_N'
 '@S9S_MB_2U_LIB.S9S_MB_2U(SCH_1):FM_PCH_TRIGGER0_R_N':
 C_SIGNAL='@s9s_mb_2u_lib.s9s_mb_2u(sch_1):fm_pch_trigger0_r_n';
NODE_NAME     U4 H11
 '@S9S_MB_2U_LIB.S9S_MB_2U(SCH_1):PAGE174_I36@PURE_QUANTA.EMMITSBURG_REV0P9(CHIPS)':
 'TRIGGER0_N': CDS_PINID='TRIGGER0_N';
NODE_NAME     R1200 2
 '@S9S_MB_2U_LIB.S9S_MB_2U(SCH_1):PAGE174_I60@PURE_QUANTA.Q_RES(CHIPS)':
 'B': CDS_PINID='B';
NODE_NAME     R1485 2
 '@S9S_MB_2U_LIB.S9S_MB_2U(SCH_1):PAGE174_I75@PURE_QUANTA.Q_RES(CHIPS)':
 'B': CDS_PINID='B';
NET_NAME
'FM_PCH_TRIGGER1_N'
 '@S9S_MB_2U_LIB.S9S_MB_2U(SCH_1):FM_PCH_TRIGGER1_N':
 C_SIGNAL='@s9s_mb_2u_lib.s9s_mb_2u(sch_1):fm_pch_trigger1_n';
NODE_NAME     R21 2
 '@S9S_MB_2U_LIB.S9S_MB_2U(SCH_1):PAGE16_I32@PURE_QUANTA.Q_RES(CHIPS)':
 'B': CDS_PINID='B';
NODE_NAME     R1201 1
 '@S9S_MB_2U_LIB.S9S_MB_2U(SCH_1):PAGE174_I58@PURE_QUANTA.Q_RES(CHIPS)':
 'A': CDS_PINID='A';
NET_NAME
'FM_PCH_TRIGGER1_R_N'
 '@S9S_MB_2U_LIB.S9S_MB_2U(SCH_1):FM_PCH_TRIGGER1_R_N':
 C_SIGNAL='@s9s_mb_2u_lib.s9s_mb_2u(sch_1):fm_pch_trigger1_r_n';
NODE_NAME     U4 K8
 '@S9S_MB_2U_LIB.S9S_MB_2U(SCH_1):PAGE174_I36@PURE_QUANTA.EMMITSBURG_REV0P9(CHIPS)':
 'TRIGGER1_N': CDS_PINID='TRIGGER1_N';
NODE_NAME     R1201 2
 '@S9S_MB_2U_LIB.S9S_MB_2U(SCH_1):PAGE174_I58@PURE_QUANTA.Q_RES(CHIPS)':
 'B': CDS_PINID='B';
NODE_NAME     R1486 2
 '@S9S_MB_2U_LIB.S9S_MB_2U(SCH_1):PAGE174_I74@PURE_QUANTA.Q_RES(CHIPS)':
 'B': CDS_PINID='B';
NET_NAME
'FM_PCH_VISA_DEFAULT'
 '@S9S_MB_2U_LIB.S9S_MB_2U(SCH_1):FM_PCH_VISA_DEFAULT':
 C_SIGNAL='@s9s_mb_2u_lib.s9s_mb_2u(sch_1):fm_pch_visa_default';
NODE_NAME     U4 G4
 '@S9S_MB_2U_LIB.S9S_MB_2U(SCH_1):PAGE176_I22@PURE_QUANTA.EMMITSBURG_REV0P9(CHIPS)':
 'GPPC_H_0': CDS_PINID='GPPC_H_0';
NODE_NAME     R615 2
 '@S9S_MB_2U_LIB.S9S_MB_2U(SCH_1):PAGE187_I51@PURE_QUANTA.Q_RES(CHIPS)':
 'B': CDS_PINID='B';
NET_NAME
'FM_PCH_XTALSEL'
 '@S9S_MB_2U_LIB.S9S_MB_2U(SCH_1):FM_PCH_XTALSEL':
 C_SIGNAL='@s9s_mb_2u_lib.s9s_mb_2u(sch_1):fm_pch_xtalsel';
NODE_NAME     U4 R4
 '@S9S_MB_2U_LIB.S9S_MB_2U(SCH_1):PAGE176_I22@PURE_QUANTA.EMMITSBURG_REV0P9(CHIPS)':
 'GPP_I_23': CDS_PINID='GPP_I_23';
NODE_NAME     R623 2
 '@S9S_MB_2U_LIB.S9S_MB_2U(SCH_1):PAGE187_I13@PURE_QUANTA.Q_RES(CHIPS)':
 'B': CDS_PINID='B';
NODE_NAME     R624 1
 '@S9S_MB_2U_LIB.S9S_MB_2U(SCH_1):PAGE187_I14@PURE_QUANTA.Q_RES(CHIPS)':
 'A': CDS_PINID='A';
NET_NAME
'FM_PCH_XTAL_INPUT_MODE_MGPIO_TE'
 '@S9S_MB_2U_LIB.S9S_MB_2U(SCH_1):FM_PCH_XTAL_INPUT_MODE_MGPIO_TEST3':
 C_SIGNAL='@s9s_mb_2u_lib.s9s_mb_2u(sch_1):fm_pch_xtal_input_mode_mgpio_test3';
NODE_NAME     U4 H3
 '@S9S_MB_2U_LIB.S9S_MB_2U(SCH_1):PAGE176_I22@PURE_QUANTA.EMMITSBURG_REV0P9(CHIPS)':
 'GPPC_H_17_FLEX_CLK_OUT_2': CDS_PINID='GPPC_H_17_FLEX_CLK_OUT_2';
NODE_NAME     R1477 2
 '@S9S_MB_2U_LIB.S9S_MB_2U(SCH_1):PAGE188_I47@PURE_QUANTA.Q_RES(CHIPS)':
 'B': CDS_PINID='B';
NODE_NAME     R1478 1
 '@S9S_MB_2U_LIB.S9S_MB_2U(SCH_1):PAGE188_I50@PURE_QUANTA.Q_RES(CHIPS)':
 'A': CDS_PINID='A';
NET_NAME
'FM_PCIE_EV_BIF_EN'
 '@S9S_MB_2U_LIB.S9S_MB_2U(SCH_1):FM_PCIE_EV_BIF_EN':
 C_SIGNAL='@s9s_mb_2u_lib.s9s_mb_2u(sch_1):fm_pcie_ev_bif_en';
NODE_NAME     U4 F8
 '@S9S_MB_2U_LIB.S9S_MB_2U(SCH_1):PAGE174_I36@PURE_QUANTA.EMMITSBURG_REV0P9(CHIPS)':
 'CPU_CATERR_N': CDS_PINID='CPU_CATERR_N';
NODE_NAME     R1675 1
 '@S9S_MB_2U_LIB.S9S_MB_2U(SCH_1):PAGE174_I82@PURE_QUANTA.Q_RES(CHIPS)':
 'A': CDS_PINID='A';
NODE_NAME     R1676 1
 '@S9S_MB_2U_LIB.S9S_MB_2U(SCH_1):PAGE174_I94@PURE_QUANTA.Q_RES(CHIPS)':
 'A': CDS_PINID='A';
NET_NAME
'FM_PDB_BUF_EN'
 '@S9S_MB_2U_LIB.S9S_MB_2U(SCH_1):FM_PDB_BUF_EN':
 C_SIGNAL='@s9s_mb_2u_lib.s9s_mb_2u(sch_1):fm_pdb_buf_en';
NODE_NAME     U249 V17
 '@S9S_MB_2U_LIB.S9S_MB_2U(SCH_1):PAGE312_I1@PURE_QUANTA.LCMXO3LF9400C5BG484C(CHIPS)':
 'PB46C': CDS_PINID='PB46C';
NODE_NAME     R2792 1
 '@S9S_MB_2U_LIB.S9S_MB_2U(SCH_1):PAGE312_I178@PURE_QUANTA.Q_RES(CHIPS)':
 'A': CDS_PINID='A';
NET_NAME
'FM_PDB_BUF_EN_R'
 '@S9S_MB_2U_LIB.S9S_MB_2U(SCH_1):FM_PDB_BUF_EN_R':
 C_SIGNAL='@s9s_mb_2u_lib.s9s_mb_2u(sch_1):fm_pdb_buf_en_r';
NODE_NAME     R2792 2
 '@S9S_MB_2U_LIB.S9S_MB_2U(SCH_1):PAGE312_I178@PURE_QUANTA.Q_RES(CHIPS)':
 'B': CDS_PINID='B';
NODE_NAME     R3063 1
 '@S9S_MB_2U_LIB.S9S_MB_2U(SCH_1):PAGE140_I208@PURE_QUANTA.Q_RES(CHIPS)':
 'A': CDS_PINID='A';
NODE_NAME     R4769 1
 '@S9S_MB_2U_LIB.S9S_MB_2U(SCH_1):PAGE233_I3@PURE_QUANTA.Q_RES(CHIPS)':
 'A': CDS_PINID='A';
NODE_NAME     R2950 2
 '@S9S_MB_2U_LIB.S9S_MB_2U(SCH_1):PAGE233_I4@PURE_QUANTA.Q_RES(CHIPS)':
 'B': CDS_PINID='B';
NODE_NAME     R2796 1
 '@S9S_MB_2U_LIB.S9S_MB_2U(SCH_1):PAGE233_I10@PURE_QUANTA.Q_RES(CHIPS)':
 'A': CDS_PINID='A';
NET_NAME
'FM_PECI_MUX_SEL_N'
 '@S9S_MB_2U_LIB.S9S_MB_2U(SCH_1):FM_PECI_MUX_SEL_N':
 C_SIGNAL='@s9s_mb_2u_lib.s9s_mb_2u(sch_1):fm_peci_mux_sel_n';
NODE_NAME     R2255 2
 '@S9S_MB_2U_LIB.S9S_MB_2U(SCH_1):PAGE185_I41@PURE_QUANTA.Q_RES(CHIPS)':
 'B': CDS_PINID='B';
NODE_NAME     U249 A6
 '@S9S_MB_2U_LIB.S9S_MB_2U(SCH_1):PAGE314_I188@PURE_QUANTA.LCMXO3LF9400C5BG484C(CHIPS)':
 'PT13B': CDS_PINID='PT13B';
NET_NAME
'FM_PEHPCPU0_ALERT_N'
 '@S9S_MB_2U_LIB.S9S_MB_2U(SCH_1):FM_PEHPCPU0_ALERT_N':
 C_SIGNAL='@s9s_mb_2u_lib.s9s_mb_2u(sch_1):fm_pehpcpu0_alert_n';
NODE_NAME     U2 BV26
 '@S9S_MB_2U_LIB.S9S_MB_2U(SCH_1):PAGE14_I1@PURE_QUANTA.SOCKET4677_AZIF0045P001C01CS(CHIPS)':
 'CXPSMBUS_ALERT_N': CDS_PINID='CXPSMBUS_ALERT_N';
NODE_NAME     R1006 2
 '@S9S_MB_2U_LIB.S9S_MB_2U(SCH_1):PAGE223_I8@PURE_QUANTA.Q_RES(CHIPS)':
 'B': CDS_PINID='B';
NODE_NAME     Q15 3
 '@S9S_MB_2U_LIB.S9S_MB_2U(SCH_1):PAGE223_I108@PURE_QUANTA.MOSFET_NCH_DUAL(CHIPS)':
 'D2': CDS_PINID='D2';
NET_NAME
'FM_PEHPCPU1_ALERT_N'
 '@S9S_MB_2U_LIB.S9S_MB_2U(SCH_1):FM_PEHPCPU1_ALERT_N':
 C_SIGNAL='@s9s_mb_2u_lib.s9s_mb_2u(sch_1):fm_pehpcpu1_alert_n';
NODE_NAME     U1 BV26
 '@S9S_MB_2U_LIB.S9S_MB_2U(SCH_1):PAGE45_I29@PURE_QUANTA.SOCKET4677_AZIF0045P001C01CS(CHIPS)':
 'CXPSMBUS_ALERT_N': CDS_PINID='CXPSMBUS_ALERT_N';
NODE_NAME     R1007 2
 '@S9S_MB_2U_LIB.S9S_MB_2U(SCH_1):PAGE223_I12@PURE_QUANTA.Q_RES(CHIPS)':
 'B': CDS_PINID='B';
NODE_NAME     Q16 3
 '@S9S_MB_2U_LIB.S9S_MB_2U(SCH_1):PAGE223_I109@PURE_QUANTA.MOSFET_NCH_DUAL(CHIPS)':
 'D2': CDS_PINID='D2';
NET_NAME
'FM_PFR_DSW_PWROK_N'
 '@S9S_MB_2U_LIB.S9S_MB_2U(SCH_1):FM_PFR_DSW_PWROK_N':
 C_SIGNAL='@s9s_mb_2u_lib.s9s_mb_2u(sch_1):fm_pfr_dsw_pwrok_n';
NODE_NAME     U249 H17
 '@S9S_MB_2U_LIB.S9S_MB_2U(SCH_1):PAGE313_I1@PURE_QUANTA.LCMXO3LF9400C5BG484C(CHIPS)':
 'PR10C': CDS_PINID='PR10C';
NODE_NAME     R1399 1
 '@S9S_MB_2U_LIB.S9S_MB_2U(SCH_1):PAGE209_I17@PURE_QUANTA.Q_RES(CHIPS)':
 'A': CDS_PINID='A';
NODE_NAME     R1745 2
 '@S9S_MB_2U_LIB.S9S_MB_2U(SCH_1):PAGE232_I21@PURE_QUANTA.Q_RES(CHIPS)':
 'B': CDS_PINID='B';
NET_NAME
'FM_PLD_CLKS_DEV_EN'
 '@S9S_MB_2U_LIB.S9S_MB_2U(SCH_1):FM_PLD_CLKS_DEV_EN':
 C_SIGNAL='@s9s_mb_2u_lib.s9s_mb_2u(sch_1):fm_pld_clks_dev_en';
NODE_NAME     R575 1
 '@S9S_MB_2U_LIB.S9S_MB_2U(SCH_1):PAGE195_I199@PURE_QUANTA.Q_RES(CHIPS)':
 'A': CDS_PINID='A';
NODE_NAME     R106 2
 '@S9S_MB_2U_LIB.S9S_MB_2U(SCH_1):PAGE195_I304@PURE_QUANTA.Q_RES(CHIPS)':
 'B': CDS_PINID='B';
NODE_NAME     U13 A17
 '@S9S_MB_2U_LIB.S9S_MB_2U(SCH_1):PAGE197_I180@PURE_QUANTA.9SQ440NQQI8(CHIPS)':
 'PWRGD||PWRDN#': CDS_PINID='\pwrgd||pwrdn#\';
NODE_NAME     R1305 2
 '@S9S_MB_2U_LIB.S9S_MB_2U(SCH_1):PAGE197_I272@PURE_QUANTA.Q_RES(CHIPS)':
 'B': CDS_PINID='B';
NODE_NAME     R1390 1
 '@S9S_MB_2U_LIB.S9S_MB_2U(SCH_1):PAGE197_I275@PURE_QUANTA.Q_RES(CHIPS)':
 'A': CDS_PINID='A';
NODE_NAME     R110 2
 '@S9S_MB_2U_LIB.S9S_MB_2U(SCH_1):PAGE212_I17@PURE_QUANTA.Q_RES(CHIPS)':
 'B': CDS_PINID='B';
NODE_NAME     U70 G
 '@S9S_MB_2U_LIB.S9S_MB_2U(SCH_1):PAGE212_I19@PURE_QUANTA.MOSFET_N(CHIPS)':
 'GATE': CDS_PINID='GATE';
NODE_NAME     R4476 1
 '@S9S_MB_2U_LIB.S9S_MB_2U(SCH_1):PAGE200_I39@PURE_QUANTA.Q_RES(CHIPS)':
 'A': CDS_PINID='A';
NET_NAME
'FM_PLD_CLKS_DEV_R_EN'
 '@S9S_MB_2U_LIB.S9S_MB_2U(SCH_1):FM_PLD_CLKS_DEV_R_EN':
 C_SIGNAL='@s9s_mb_2u_lib.s9s_mb_2u(sch_1):fm_pld_clks_dev_r_en';
NODE_NAME     R110 1
 '@S9S_MB_2U_LIB.S9S_MB_2U(SCH_1):PAGE212_I17@PURE_QUANTA.Q_RES(CHIPS)':
 'A': CDS_PINID='A';
NODE_NAME     U249 U7
 '@S9S_MB_2U_LIB.S9S_MB_2U(SCH_1):PAGE312_I1@PURE_QUANTA.LCMXO3LF9400C5BG484C(CHIPS)':
 'PB8C': CDS_PINID='PB8C';
NET_NAME
'FM_PLD_CLKS_OE_R_N'
 '@S9S_MB_2U_LIB.S9S_MB_2U(SCH_1):FM_PLD_CLKS_OE_R_N':
 C_SIGNAL='@s9s_mb_2u_lib.s9s_mb_2u(sch_1):fm_pld_clks_oe_r_n';
NODE_NAME     U70 D
 '@S9S_MB_2U_LIB.S9S_MB_2U(SCH_1):PAGE212_I19@PURE_QUANTA.MOSFET_N(CHIPS)':
 'DRAIN': CDS_PINID='DRAIN';
NODE_NAME     R111 2
 '@S9S_MB_2U_LIB.S9S_MB_2U(SCH_1):PAGE212_I24@PURE_QUANTA.Q_RES(CHIPS)':
 'B': CDS_PINID='B';
NODE_NAME     R113 1
 '@S9S_MB_2U_LIB.S9S_MB_2U(SCH_1):PAGE212_I27@PURE_QUANTA.Q_RES(CHIPS)':
 'A': CDS_PINID='A';
NET_NAME
'FM_PLD_CLK_25M_EN'
 '@S9S_MB_2U_LIB.S9S_MB_2U(SCH_1):FM_PLD_CLK_25M_EN':
 C_SIGNAL='@s9s_mb_2u_lib.s9s_mb_2u(sch_1):fm_pld_clk_25m_en';
NODE_NAME     R1680 1
 '@S9S_MB_2U_LIB.S9S_MB_2U(SCH_1):PAGE197_I252@PURE_QUANTA.Q_RES(CHIPS)':
 'A': CDS_PINID='A';
NODE_NAME     R109 2
 '@S9S_MB_2U_LIB.S9S_MB_2U(SCH_1):PAGE212_I44@PURE_QUANTA.Q_RES(CHIPS)':
 'B': CDS_PINID='B';
NET_NAME
'FM_PLD_CLK_25M_R_EN'
 '@S9S_MB_2U_LIB.S9S_MB_2U(SCH_1):FM_PLD_CLK_25M_R_EN':
 C_SIGNAL='@s9s_mb_2u_lib.s9s_mb_2u(sch_1):fm_pld_clk_25m_r_en';
NODE_NAME     R990 1
 '@S9S_MB_2U_LIB.S9S_MB_2U(SCH_1):PAGE208_I18@PURE_QUANTA.Q_RES(CHIPS)':
 'A': CDS_PINID='A';
NODE_NAME     R109 1
 '@S9S_MB_2U_LIB.S9S_MB_2U(SCH_1):PAGE212_I44@PURE_QUANTA.Q_RES(CHIPS)':
 'A': CDS_PINID='A';
NODE_NAME     U249 T8
 '@S9S_MB_2U_LIB.S9S_MB_2U(SCH_1):PAGE312_I1@PURE_QUANTA.LCMXO3LF9400C5BG484C(CHIPS)':
 'PB8D': CDS_PINID='PB8D';
NET_NAME
'FM_PLD_HEARTBEAT_LVC3'
 '@S9S_MB_2U_LIB.S9S_MB_2U(SCH_1):FM_PLD_HEARTBEAT_LVC3':
 C_SIGNAL='@s9s_mb_2u_lib.s9s_mb_2u(sch_1):fm_pld_heartbeat_lvc3';
NODE_NAME     U89 G
 '@S9S_MB_2U_LIB.S9S_MB_2U(SCH_1):PAGE207_I236@PURE_QUANTA.MOSFET_N(CHIPS)':
 'GATE': CDS_PINID='GATE';
NODE_NAME     U249 T10
 '@S9S_MB_2U_LIB.S9S_MB_2U(SCH_1):PAGE312_I1@PURE_QUANTA.LCMXO3LF9400C5BG484C(CHIPS)':
 'PB19C': CDS_PINID='PB19C';
NODE_NAME     R1437 1
 '@S9S_MB_2U_LIB.S9S_MB_2U(SCH_1):PAGE209_I42@PURE_QUANTA.Q_RES(CHIPS)':
 'A': CDS_PINID='A';
NET_NAME
'FM_PLD_HEARTBEAT_LVC3_D'
 '@S9S_MB_2U_LIB.S9S_MB_2U(SCH_1):FM_PLD_HEARTBEAT_LVC3_D':
 C_SIGNAL='@s9s_mb_2u_lib.s9s_mb_2u(sch_1):fm_pld_heartbeat_lvc3_d';
NODE_NAME     U89 D
 '@S9S_MB_2U_LIB.S9S_MB_2U(SCH_1):PAGE207_I236@PURE_QUANTA.MOSFET_N(CHIPS)':
 'DRAIN': CDS_PINID='DRAIN';
NODE_NAME     D0 C
 '@S9S_MB_2U_LIB.S9S_MB_2U(SCH_1):PAGE207_I277@PURE_QUANTA.Q_LED(CHIPS)':
 'C': CDS_PINID='C';
NET_NAME
'FM_PLD_REV_N'
 '@S9S_MB_2U_LIB.S9S_MB_2U(SCH_1):FM_PLD_REV_N':
 C_SIGNAL='@s9s_mb_2u_lib.s9s_mb_2u(sch_1):fm_pld_rev_n';
NODE_NAME     U249 AA19
 '@S9S_MB_2U_LIB.S9S_MB_2U(SCH_1):PAGE312_I1@PURE_QUANTA.LCMXO3LF9400C5BG484C(CHIPS)':
 'PB43B': CDS_PINID='PB43B';
NODE_NAME     R1710 1
 '@S9S_MB_2U_LIB.S9S_MB_2U(SCH_1):PAGE312_I38@PURE_QUANTA.Q_RES(CHIPS)':
 'A': CDS_PINID='A';
NODE_NAME     C1325 1
 '@S9S_MB_2U_LIB.S9S_MB_2U(SCH_1):PAGE312_I39@PURE_QUANTA.Q_CAP(CHIPS)':
 'A': CDS_PINID='A';
NET_NAME
'FM_PLD_REV_R_N'
 '@S9S_MB_2U_LIB.S9S_MB_2U(SCH_1):FM_PLD_REV_R_N':
 C_SIGNAL='@s9s_mb_2u_lib.s9s_mb_2u(sch_1):fm_pld_rev_r_n';
NODE_NAME     R1106 2
 '@S9S_MB_2U_LIB.S9S_MB_2U(SCH_1):PAGE312_I5@PURE_QUANTA.Q_RES(CHIPS)':
 'B': CDS_PINID='B';
NODE_NAME     R1710 2
 '@S9S_MB_2U_LIB.S9S_MB_2U(SCH_1):PAGE312_I38@PURE_QUANTA.Q_RES(CHIPS)':
 'B': CDS_PINID='B';
NET_NAME
'FM_PLT_BMC_THERMTRIP_R_N'
 '@S9S_MB_2U_LIB.S9S_MB_2U(SCH_1):FM_PLT_BMC_THERMTRIP_R_N':
 C_SIGNAL='@s9s_mb_2u_lib.s9s_mb_2u(sch_1):fm_plt_bmc_thermtrip_r_n';
NODE_NAME     U4 Y2
 '@S9S_MB_2U_LIB.S9S_MB_2U(SCH_1):PAGE175_I93@PURE_QUANTA.EMMITSBURG_REV0P9(CHIPS)':
 'GPP_D_17_THERMTRIP_N': CDS_PINID='GPP_D_17_THERMTRIP_N';
NODE_NAME     R1263 1
 '@S9S_MB_2U_LIB.S9S_MB_2U(SCH_1):PAGE191_I29@PURE_QUANTA.Q_RES(CHIPS)':
 'A': CDS_PINID='A';
NODE_NAME     R1820 2
 '@S9S_MB_2U_LIB.S9S_MB_2U(SCH_1):PAGE191_I35@PURE_QUANTA.Q_RES(CHIPS)':
 'B': CDS_PINID='B';
NET_NAME
'FM_PMBUS_ALERT_B_EN'
 '@S9S_MB_2U_LIB.S9S_MB_2U(SCH_1):FM_PMBUS_ALERT_B_EN':
 C_SIGNAL='@s9s_mb_2u_lib.s9s_mb_2u(sch_1):fm_pmbus_alert_b_en';
NODE_NAME     U4 AV3
 '@S9S_MB_2U_LIB.S9S_MB_2U(SCH_1):PAGE175_I93@PURE_QUANTA.EMMITSBURG_REV0P9(CHIPS)':
 'GPPC_C_11_ME_SML2ALERT_N': CDS_PINID='GPPC_C_11_ME_SML2ALERT_N';
NODE_NAME     R1659 1
 '@S9S_MB_2U_LIB.S9S_MB_2U(SCH_1):PAGE175_I181@PURE_QUANTA.Q_RES(CHIPS)':
 'A': CDS_PINID='A';
NET_NAME
'FM_PS_EN_PLD_BUF1'
 '@S9S_MB_2U_LIB.S9S_MB_2U(SCH_1):FM_PS_EN_PLD_BUF1':
 C_SIGNAL='@s9s_mb_2u_lib.s9s_mb_2u(sch_1):fm_ps_en_pld_buf1';
NODE_NAME     R2350 1
 '@S9S_MB_2U_LIB.S9S_MB_2U(SCH_1):PAGE297_I157@PURE_QUANTA.Q_RES(CHIPS)':
 'A': CDS_PINID='A';
NODE_NAME     U150 6
 '@S9S_MB_2U_LIB.S9S_MB_2U(SCH_1):PAGE213_I2@PURE_QUANTA.74LVC2G17GW(CHIPS)':
 'B0': CDS_PINID='B0';
NODE_NAME     R2355 2
 '@S9S_MB_2U_LIB.S9S_MB_2U(SCH_1):PAGE213_I7@PURE_QUANTA.Q_RES(CHIPS)':
 'B': CDS_PINID='B';
NET_NAME
'FM_PS_EN_PLD_BUF1_R1'
 '@S9S_MB_2U_LIB.S9S_MB_2U(SCH_1):FM_PS_EN_PLD_BUF1_R1':
 C_SIGNAL='@s9s_mb_2u_lib.s9s_mb_2u(sch_1):fm_ps_en_pld_buf1_r1';
NODE_NAME     R2350 2
 '@S9S_MB_2U_LIB.S9S_MB_2U(SCH_1):PAGE297_I157@PURE_QUANTA.Q_RES(CHIPS)':
 'B': CDS_PINID='B';
NODE_NAME     U145 1
 '@S9S_MB_2U_LIB.S9S_MB_2U(SCH_1):PAGE297_I163@PURE_QUANTA.74LVC1G126SE7(CHIPS)':
 'OE': CDS_PINID='OE';
NET_NAME
'FM_PS_EN_PLD_R'
 '@S9S_MB_2U_LIB.S9S_MB_2U(SCH_1):FM_PS_EN_PLD_R':
 C_SIGNAL='@s9s_mb_2u_lib.s9s_mb_2u(sch_1):fm_ps_en_pld_r';
NODE_NAME     U249 V22
 '@S9S_MB_2U_LIB.S9S_MB_2U(SCH_1):PAGE313_I1@PURE_QUANTA.LCMXO3LF9400C5BG484C(CHIPS)':
 'PR25A': CDS_PINID='PR25A';
NODE_NAME     U150 1
 '@S9S_MB_2U_LIB.S9S_MB_2U(SCH_1):PAGE213_I2@PURE_QUANTA.74LVC2G17GW(CHIPS)':
 'A0': CDS_PINID='A0';
NODE_NAME     R1607 1
 '@S9S_MB_2U_LIB.S9S_MB_2U(SCH_1):PAGE246_I10@PURE_QUANTA.Q_RES(CHIPS)':
 'A': CDS_PINID='A';
NET_NAME
'FM_PS_PWROK_DLY_R_SEL'
 '@S9S_MB_2U_LIB.S9S_MB_2U(SCH_1):FM_PS_PWROK_DLY_R_SEL':
 C_SIGNAL='@s9s_mb_2u_lib.s9s_mb_2u(sch_1):fm_ps_pwrok_dly_r_sel';
NODE_NAME     U4 BA20
 '@S9S_MB_2U_LIB.S9S_MB_2U(SCH_1):PAGE176_I22@PURE_QUANTA.EMMITSBURG_REV0P9(CHIPS)':
 'GPP_E_18_ERR1_N': CDS_PINID='GPP_E_18_ERR1_N';
NODE_NAME     R8 2
 '@S9S_MB_2U_LIB.S9S_MB_2U(SCH_1):PAGE192_I59@PURE_QUANTA.Q_RES(CHIPS)':
 'B': CDS_PINID='B';
NODE_NAME     R1306 1
 '@S9S_MB_2U_LIB.S9S_MB_2U(SCH_1):PAGE193_I13@PURE_QUANTA.Q_RES(CHIPS)':
 'A': CDS_PINID='A';
NET_NAME
'FM_PS_PWROK_DLY_SEL'
 '@S9S_MB_2U_LIB.S9S_MB_2U(SCH_1):FM_PS_PWROK_DLY_SEL':
 C_SIGNAL='@s9s_mb_2u_lib.s9s_mb_2u(sch_1):fm_ps_pwrok_dly_sel';
NODE_NAME     R1306 2
 '@S9S_MB_2U_LIB.S9S_MB_2U(SCH_1):PAGE193_I13@PURE_QUANTA.Q_RES(CHIPS)':
 'B': CDS_PINID='B';
NODE_NAME     U249 V9
 '@S9S_MB_2U_LIB.S9S_MB_2U(SCH_1):PAGE312_I1@PURE_QUANTA.LCMXO3LF9400C5BG484C(CHIPS)':
 'PB16C': CDS_PINID='PB16C';
NET_NAME
'FM_PVCCD_HV_CPU0_EN'
 '@S9S_MB_2U_LIB.S9S_MB_2U(SCH_1):FM_PVCCD_HV_CPU0_EN':
 C_SIGNAL='@s9s_mb_2u_lib.s9s_mb_2u(sch_1):fm_pvccd_hv_cpu0_en';
NODE_NAME     R1413 1
 '@S9S_MB_2U_LIB.S9S_MB_2U(SCH_1):PAGE208_I59@PURE_QUANTA.Q_RES(CHIPS)':
 'A': CDS_PINID='A';
NODE_NAME     R363 1
 '@S9S_MB_2U_LIB.S9S_MB_2U(SCH_1):PAGE264_I45@PURE_QUANTA.Q_RES(CHIPS)':
 'A': CDS_PINID='A';
NODE_NAME     U249 C21
 '@S9S_MB_2U_LIB.S9S_MB_2U(SCH_1):PAGE313_I1@PURE_QUANTA.LCMXO3LF9400C5BG484C(CHIPS)':
 'PR2A||R_GPLLT_FB': CDS_PINID='\pr2a||r_gpllt_fb\';
NET_NAME
'FM_PVCCD_HV_CPU1_EN'
 '@S9S_MB_2U_LIB.S9S_MB_2U(SCH_1):FM_PVCCD_HV_CPU1_EN':
 C_SIGNAL='@s9s_mb_2u_lib.s9s_mb_2u(sch_1):fm_pvccd_hv_cpu1_en';
NODE_NAME     R1414 1
 '@S9S_MB_2U_LIB.S9S_MB_2U(SCH_1):PAGE208_I58@PURE_QUANTA.Q_RES(CHIPS)':
 'A': CDS_PINID='A';
NODE_NAME     U249 C22
 '@S9S_MB_2U_LIB.S9S_MB_2U(SCH_1):PAGE313_I1@PURE_QUANTA.LCMXO3LF9400C5BG484C(CHIPS)':
 'PR2B||R_GPLLC_FB': CDS_PINID='\pr2b||r_gpllc_fb\';
NODE_NAME     R2577 1
 '@S9S_MB_2U_LIB.S9S_MB_2U(SCH_1):PAGE282_I43@PURE_QUANTA.Q_RES(CHIPS)':
 'A': CDS_PINID='A';
NET_NAME
'FM_PVCCFA_EHV_CPU0_EN'
 '@S9S_MB_2U_LIB.S9S_MB_2U(SCH_1):FM_PVCCFA_EHV_CPU0_EN':
 C_SIGNAL='@s9s_mb_2u_lib.s9s_mb_2u(sch_1):fm_pvccfa_ehv_cpu0_en';
NODE_NAME     R982 2
 '@S9S_MB_2U_LIB.S9S_MB_2U(SCH_1):PAGE211_I10@PURE_QUANTA.Q_RES(CHIPS)':
 'B': CDS_PINID='B';
NODE_NAME     R2394 1
 '@S9S_MB_2U_LIB.S9S_MB_2U(SCH_1):PAGE260_I14@PURE_QUANTA.Q_RES(CHIPS)':
 'A': CDS_PINID='A';
NET_NAME
'FM_PVCCFA_EHV_CPU0_R_EN'
 '@S9S_MB_2U_LIB.S9S_MB_2U(SCH_1):FM_PVCCFA_EHV_CPU0_R_EN':
 C_SIGNAL='@s9s_mb_2u_lib.s9s_mb_2u(sch_1):fm_pvccfa_ehv_cpu0_r_en';
NODE_NAME     R1409 1
 '@S9S_MB_2U_LIB.S9S_MB_2U(SCH_1):PAGE208_I55@PURE_QUANTA.Q_RES(CHIPS)':
 'A': CDS_PINID='A';
NODE_NAME     R982 1
 '@S9S_MB_2U_LIB.S9S_MB_2U(SCH_1):PAGE211_I10@PURE_QUANTA.Q_RES(CHIPS)':
 'A': CDS_PINID='A';
NODE_NAME     U249 F17
 '@S9S_MB_2U_LIB.S9S_MB_2U(SCH_1):PAGE313_I1@PURE_QUANTA.LCMXO3LF9400C5BG484C(CHIPS)':
 'PR2C': CDS_PINID='PR2C';
NET_NAME
'FM_PVCCFA_EHV_CPU1_EN'
 '@S9S_MB_2U_LIB.S9S_MB_2U(SCH_1):FM_PVCCFA_EHV_CPU1_EN':
 C_SIGNAL='@s9s_mb_2u_lib.s9s_mb_2u(sch_1):fm_pvccfa_ehv_cpu1_en';
NODE_NAME     R986 2
 '@S9S_MB_2U_LIB.S9S_MB_2U(SCH_1):PAGE211_I25@PURE_QUANTA.Q_RES(CHIPS)':
 'B': CDS_PINID='B';
NODE_NAME     R2570 1
 '@S9S_MB_2U_LIB.S9S_MB_2U(SCH_1):PAGE278_I31@PURE_QUANTA.Q_RES(CHIPS)':
 'A': CDS_PINID='A';
NET_NAME
'FM_PVCCFA_EHV_CPU1_R_EN'
 '@S9S_MB_2U_LIB.S9S_MB_2U(SCH_1):FM_PVCCFA_EHV_CPU1_R_EN':
 C_SIGNAL='@s9s_mb_2u_lib.s9s_mb_2u(sch_1):fm_pvccfa_ehv_cpu1_r_en';
NODE_NAME     R1410 1
 '@S9S_MB_2U_LIB.S9S_MB_2U(SCH_1):PAGE208_I54@PURE_QUANTA.Q_RES(CHIPS)':
 'A': CDS_PINID='A';
NODE_NAME     R986 1
 '@S9S_MB_2U_LIB.S9S_MB_2U(SCH_1):PAGE211_I25@PURE_QUANTA.Q_RES(CHIPS)':
 'A': CDS_PINID='A';
NODE_NAME     U249 G16
 '@S9S_MB_2U_LIB.S9S_MB_2U(SCH_1):PAGE313_I1@PURE_QUANTA.LCMXO3LF9400C5BG484C(CHIPS)':
 'PR2D': CDS_PINID='PR2D';
NET_NAME
'FM_PVCCFA_EHV_FIVRA_CPU0_EN'
 '@S9S_MB_2U_LIB.S9S_MB_2U(SCH_1):FM_PVCCFA_EHV_FIVRA_CPU0_EN':
 C_SIGNAL='@s9s_mb_2u_lib.s9s_mb_2u(sch_1):fm_pvccfa_ehv_fivra_cpu0_en';
NODE_NAME     R984 2
 '@S9S_MB_2U_LIB.S9S_MB_2U(SCH_1):PAGE211_I15@PURE_QUANTA.Q_RES(CHIPS)':
 'B': CDS_PINID='B';
NODE_NAME     R4216 1
 '@S9S_MB_2U_LIB.S9S_MB_2U(SCH_1):PAGE252_I56@PURE_QUANTA.Q_RES(CHIPS)':
 'A': CDS_PINID='A';
NET_NAME
'FM_PVCCFA_EHV_FIVRA_CPU0_R_EN'
 '@S9S_MB_2U_LIB.S9S_MB_2U(SCH_1):FM_PVCCFA_EHV_FIVRA_CPU0_R_EN':
 C_SIGNAL='@s9s_mb_2u_lib.s9s_mb_2u(sch_1):fm_pvccfa_ehv_fivra_cpu0_r_en';
NODE_NAME     R1411 1
 '@S9S_MB_2U_LIB.S9S_MB_2U(SCH_1):PAGE208_I56@PURE_QUANTA.Q_RES(CHIPS)':
 'A': CDS_PINID='A';
NODE_NAME     R984 1
 '@S9S_MB_2U_LIB.S9S_MB_2U(SCH_1):PAGE211_I15@PURE_QUANTA.Q_RES(CHIPS)':
 'A': CDS_PINID='A';
NODE_NAME     U249 D22
 '@S9S_MB_2U_LIB.S9S_MB_2U(SCH_1):PAGE313_I1@PURE_QUANTA.LCMXO3LF9400C5BG484C(CHIPS)':
 'PR3A||R_GPLLT_IN': CDS_PINID='\pr3a||r_gpllt_in\';
NET_NAME
'FM_PVCCFA_EHV_FIVRA_CPU1_EN'
 '@S9S_MB_2U_LIB.S9S_MB_2U(SCH_1):FM_PVCCFA_EHV_FIVRA_CPU1_EN':
 C_SIGNAL='@s9s_mb_2u_lib.s9s_mb_2u(sch_1):fm_pvccfa_ehv_fivra_cpu1_en';
NODE_NAME     R988 2
 '@S9S_MB_2U_LIB.S9S_MB_2U(SCH_1):PAGE211_I23@PURE_QUANTA.Q_RES(CHIPS)':
 'B': CDS_PINID='B';
NODE_NAME     R2550 1
 '@S9S_MB_2U_LIB.S9S_MB_2U(SCH_1):PAGE270_I19@PURE_QUANTA.Q_RES(CHIPS)':
 'A': CDS_PINID='A';
NET_NAME
'FM_PVCCFA_EHV_FIVRA_CPU1_R_EN'
 '@S9S_MB_2U_LIB.S9S_MB_2U(SCH_1):FM_PVCCFA_EHV_FIVRA_CPU1_R_EN':
 C_SIGNAL='@s9s_mb_2u_lib.s9s_mb_2u(sch_1):fm_pvccfa_ehv_fivra_cpu1_r_en';
NODE_NAME     R1412 1
 '@S9S_MB_2U_LIB.S9S_MB_2U(SCH_1):PAGE208_I57@PURE_QUANTA.Q_RES(CHIPS)':
 'A': CDS_PINID='A';
NODE_NAME     R988 1
 '@S9S_MB_2U_LIB.S9S_MB_2U(SCH_1):PAGE211_I23@PURE_QUANTA.Q_RES(CHIPS)':
 'A': CDS_PINID='A';
NODE_NAME     U249 D21
 '@S9S_MB_2U_LIB.S9S_MB_2U(SCH_1):PAGE313_I1@PURE_QUANTA.LCMXO3LF9400C5BG484C(CHIPS)':
 'PR3B||R_GPLLC_IN': CDS_PINID='\pr3b||r_gpllc_in\';
NET_NAME
'FM_PVCCINFAON_CPU0_EN'
 '@S9S_MB_2U_LIB.S9S_MB_2U(SCH_1):FM_PVCCINFAON_CPU0_EN':
 C_SIGNAL='@s9s_mb_2u_lib.s9s_mb_2u(sch_1):fm_pvccinfaon_cpu0_en';
NODE_NAME     R983 2
 '@S9S_MB_2U_LIB.S9S_MB_2U(SCH_1):PAGE211_I13@PURE_QUANTA.Q_RES(CHIPS)':
 'B': CDS_PINID='B';
NODE_NAME     R2594 1
 '@S9S_MB_2U_LIB.S9S_MB_2U(SCH_1):PAGE260_I55@PURE_QUANTA.Q_RES(CHIPS)':
 'A': CDS_PINID='A';
NET_NAME
'FM_PVCCINFAON_CPU0_R_EN'
 '@S9S_MB_2U_LIB.S9S_MB_2U(SCH_1):FM_PVCCINFAON_CPU0_R_EN':
 C_SIGNAL='@s9s_mb_2u_lib.s9s_mb_2u(sch_1):fm_pvccinfaon_cpu0_r_en';
NODE_NAME     R1407 1
 '@S9S_MB_2U_LIB.S9S_MB_2U(SCH_1):PAGE208_I52@PURE_QUANTA.Q_RES(CHIPS)':
 'A': CDS_PINID='A';
NODE_NAME     R983 1
 '@S9S_MB_2U_LIB.S9S_MB_2U(SCH_1):PAGE211_I13@PURE_QUANTA.Q_RES(CHIPS)':
 'A': CDS_PINID='A';
NODE_NAME     U249 D19
 '@S9S_MB_2U_LIB.S9S_MB_2U(SCH_1):PAGE313_I1@PURE_QUANTA.LCMXO3LF9400C5BG484C(CHIPS)':
 'PR3C': CDS_PINID='PR3C';
NET_NAME
'FM_PVCCINFAON_CPU1_EN'
 '@S9S_MB_2U_LIB.S9S_MB_2U(SCH_1):FM_PVCCINFAON_CPU1_EN':
 C_SIGNAL='@s9s_mb_2u_lib.s9s_mb_2u(sch_1):fm_pvccinfaon_cpu1_en';
NODE_NAME     R987 2
 '@S9S_MB_2U_LIB.S9S_MB_2U(SCH_1):PAGE211_I24@PURE_QUANTA.Q_RES(CHIPS)':
 'B': CDS_PINID='B';
NODE_NAME     R2558 1
 '@S9S_MB_2U_LIB.S9S_MB_2U(SCH_1):PAGE278_I104@PURE_QUANTA.Q_RES(CHIPS)':
 'A': CDS_PINID='A';
NET_NAME
'FM_PVCCINFAON_CPU1_R_EN'
 '@S9S_MB_2U_LIB.S9S_MB_2U(SCH_1):FM_PVCCINFAON_CPU1_R_EN':
 C_SIGNAL='@s9s_mb_2u_lib.s9s_mb_2u(sch_1):fm_pvccinfaon_cpu1_r_en';
NODE_NAME     R1408 1
 '@S9S_MB_2U_LIB.S9S_MB_2U(SCH_1):PAGE208_I53@PURE_QUANTA.Q_RES(CHIPS)':
 'A': CDS_PINID='A';
NODE_NAME     R987 1
 '@S9S_MB_2U_LIB.S9S_MB_2U(SCH_1):PAGE211_I24@PURE_QUANTA.Q_RES(CHIPS)':
 'A': CDS_PINID='A';
NODE_NAME     U249 D20
 '@S9S_MB_2U_LIB.S9S_MB_2U(SCH_1):PAGE313_I1@PURE_QUANTA.LCMXO3LF9400C5BG484C(CHIPS)':
 'PR3D': CDS_PINID='PR3D';
NET_NAME
'FM_PVCCIN_CPU0_EN'
 '@S9S_MB_2U_LIB.S9S_MB_2U(SCH_1):FM_PVCCIN_CPU0_EN':
 C_SIGNAL='@s9s_mb_2u_lib.s9s_mb_2u(sch_1):fm_pvccin_cpu0_en';
NODE_NAME     R981 2
 '@S9S_MB_2U_LIB.S9S_MB_2U(SCH_1):PAGE211_I9@PURE_QUANTA.Q_RES(CHIPS)':
 'B': CDS_PINID='B';
NODE_NAME     R2591 1
 '@S9S_MB_2U_LIB.S9S_MB_2U(SCH_1):PAGE252_I48@PURE_QUANTA.Q_RES(CHIPS)':
 'A': CDS_PINID='A';
NET_NAME
'FM_PVCCIN_CPU0_R_EN'
 '@S9S_MB_2U_LIB.S9S_MB_2U(SCH_1):FM_PVCCIN_CPU0_R_EN':
 C_SIGNAL='@s9s_mb_2u_lib.s9s_mb_2u(sch_1):fm_pvccin_cpu0_r_en';
NODE_NAME     R1405 1
 '@S9S_MB_2U_LIB.S9S_MB_2U(SCH_1):PAGE208_I26@PURE_QUANTA.Q_RES(CHIPS)':
 'A': CDS_PINID='A';
NODE_NAME     R981 1
 '@S9S_MB_2U_LIB.S9S_MB_2U(SCH_1):PAGE211_I9@PURE_QUANTA.Q_RES(CHIPS)':
 'A': CDS_PINID='A';
NODE_NAME     U249 E19
 '@S9S_MB_2U_LIB.S9S_MB_2U(SCH_1):PAGE313_I1@PURE_QUANTA.LCMXO3LF9400C5BG484C(CHIPS)':
 'PR4C': CDS_PINID='PR4C';
NET_NAME
'FM_PVCCIN_CPU1_EN'
 '@S9S_MB_2U_LIB.S9S_MB_2U(SCH_1):FM_PVCCIN_CPU1_EN':
 C_SIGNAL='@s9s_mb_2u_lib.s9s_mb_2u(sch_1):fm_pvccin_cpu1_en';
NODE_NAME     R985 2
 '@S9S_MB_2U_LIB.S9S_MB_2U(SCH_1):PAGE211_I21@PURE_QUANTA.Q_RES(CHIPS)':
 'B': CDS_PINID='B';
NODE_NAME     R309 1
 '@S9S_MB_2U_LIB.S9S_MB_2U(SCH_1):PAGE270_I59@PURE_QUANTA.Q_RES(CHIPS)':
 'A': CDS_PINID='A';
NET_NAME
'FM_PVCCIN_CPU1_R_EN'
 '@S9S_MB_2U_LIB.S9S_MB_2U(SCH_1):FM_PVCCIN_CPU1_R_EN':
 C_SIGNAL='@s9s_mb_2u_lib.s9s_mb_2u(sch_1):fm_pvccin_cpu1_r_en';
NODE_NAME     R1406 1
 '@S9S_MB_2U_LIB.S9S_MB_2U(SCH_1):PAGE208_I51@PURE_QUANTA.Q_RES(CHIPS)':
 'A': CDS_PINID='A';
NODE_NAME     R985 1
 '@S9S_MB_2U_LIB.S9S_MB_2U(SCH_1):PAGE211_I21@PURE_QUANTA.Q_RES(CHIPS)':
 'A': CDS_PINID='A';
NODE_NAME     U249 E20
 '@S9S_MB_2U_LIB.S9S_MB_2U(SCH_1):PAGE313_I1@PURE_QUANTA.LCMXO3LF9400C5BG484C(CHIPS)':
 'PR4D': CDS_PINID='PR4D';
NET_NAME
'FM_PVNN_MAIN_CPU0_EN'
 '@S9S_MB_2U_LIB.S9S_MB_2U(SCH_1):FM_PVNN_MAIN_CPU0_EN':
 C_SIGNAL='@s9s_mb_2u_lib.s9s_mb_2u(sch_1):fm_pvnn_main_cpu0_en';
NODE_NAME     U249 E22
 '@S9S_MB_2U_LIB.S9S_MB_2U(SCH_1):PAGE313_I1@PURE_QUANTA.LCMXO3LF9400C5BG484C(CHIPS)':
 'PR4A': CDS_PINID='PR4A';
NODE_NAME     R1445 1
 '@S9S_MB_2U_LIB.S9S_MB_2U(SCH_1):PAGE268_I11@PURE_QUANTA.Q_RES(CHIPS)':
 'A': CDS_PINID='A';
NODE_NAME     C1307 1
 '@S9S_MB_2U_LIB.S9S_MB_2U(SCH_1):PAGE268_I4@PURE_QUANTA.Q_CAP(CHIPS)':
 'A': CDS_PINID='A';
NODE_NAME     R2338 2
 '@S9S_MB_2U_LIB.S9S_MB_2U(SCH_1):PAGE268_I5@PURE_QUANTA.Q_RES(CHIPS)':
 'B': CDS_PINID='B';
NODE_NAME     PU81 5
 '@S9S_MB_2U_LIB.S9S_MB_2U(SCH_1):PAGE268_I22@PURE_QUANTA.RS53317LR(CHIPS)':
 'EN': CDS_PINID='EN';
NET_NAME
'FM_PVNN_MAIN_CPU1_EN'
 '@S9S_MB_2U_LIB.S9S_MB_2U(SCH_1):FM_PVNN_MAIN_CPU1_EN':
 C_SIGNAL='@s9s_mb_2u_lib.s9s_mb_2u(sch_1):fm_pvnn_main_cpu1_en';
NODE_NAME     U249 E21
 '@S9S_MB_2U_LIB.S9S_MB_2U(SCH_1):PAGE313_I1@PURE_QUANTA.LCMXO3LF9400C5BG484C(CHIPS)':
 'PR4B': CDS_PINID='PR4B';
NODE_NAME     C1308 1
 '@S9S_MB_2U_LIB.S9S_MB_2U(SCH_1):PAGE286_I6@PURE_QUANTA.Q_CAP(CHIPS)':
 'A': CDS_PINID='A';
NODE_NAME     PU82 5
 '@S9S_MB_2U_LIB.S9S_MB_2U(SCH_1):PAGE286_I20@PURE_QUANTA.RS53317LR(CHIPS)':
 'EN': CDS_PINID='EN';
NODE_NAME     R2384 2
 '@S9S_MB_2U_LIB.S9S_MB_2U(SCH_1):PAGE286_I5@PURE_QUANTA.Q_RES(CHIPS)':
 'B': CDS_PINID='B';
NODE_NAME     R2385 1
 '@S9S_MB_2U_LIB.S9S_MB_2U(SCH_1):PAGE286_I7@PURE_QUANTA.Q_RES(CHIPS)':
 'A': CDS_PINID='A';
NET_NAME
'FM_PVPP_HBM_CPU0_EN'
 '@S9S_MB_2U_LIB.S9S_MB_2U(SCH_1):FM_PVPP_HBM_CPU0_EN':
 C_SIGNAL='@s9s_mb_2u_lib.s9s_mb_2u(sch_1):fm_pvpp_hbm_cpu0_en';
NODE_NAME     C1300 1
 '@S9S_MB_2U_LIB.S9S_MB_2U(SCH_1):PAGE267_I12@PURE_QUANTA.Q_CAP(CHIPS)':
 'A': CDS_PINID='A';
NODE_NAME     U249 G22
 '@S9S_MB_2U_LIB.S9S_MB_2U(SCH_1):PAGE313_I1@PURE_QUANTA.LCMXO3LF9400C5BG484C(CHIPS)':
 'PR5B': CDS_PINID='PR5B';
NODE_NAME     R2406 2
 '@S9S_MB_2U_LIB.S9S_MB_2U(SCH_1):PAGE267_I9@PURE_QUANTA.Q_RES(CHIPS)':
 'B': CDS_PINID='B';
NODE_NAME     R2332 1
 '@S9S_MB_2U_LIB.S9S_MB_2U(SCH_1):PAGE267_I14@PURE_QUANTA.Q_RES(CHIPS)':
 'A': CDS_PINID='A';
NODE_NAME     PU79 8
 '@S9S_MB_2U_LIB.S9S_MB_2U(SCH_1):PAGE267_I19@PURE_QUANTA.RS53318LR(CHIPS)':
 'EN': CDS_PINID='EN';
NET_NAME
'FM_PVPP_HBM_CPU1_EN'
 '@S9S_MB_2U_LIB.S9S_MB_2U(SCH_1):FM_PVPP_HBM_CPU1_EN':
 C_SIGNAL='@s9s_mb_2u_lib.s9s_mb_2u(sch_1):fm_pvpp_hbm_cpu1_en';
NODE_NAME     U249 F22
 '@S9S_MB_2U_LIB.S9S_MB_2U(SCH_1):PAGE313_I1@PURE_QUANTA.LCMXO3LF9400C5BG484C(CHIPS)':
 'PR5A': CDS_PINID='PR5A';
NODE_NAME     C2445 1
 '@S9S_MB_2U_LIB.S9S_MB_2U(SCH_1):PAGE285_I11@PURE_QUANTA.Q_CAP(CHIPS)':
 'A': CDS_PINID='A';
NODE_NAME     R2374 1
 '@S9S_MB_2U_LIB.S9S_MB_2U(SCH_1):PAGE285_I13@PURE_QUANTA.Q_RES(CHIPS)':
 'A': CDS_PINID='A';
NODE_NAME     PU80 8
 '@S9S_MB_2U_LIB.S9S_MB_2U(SCH_1):PAGE285_I25@PURE_QUANTA.RS53318LR(CHIPS)':
 'EN': CDS_PINID='EN';
NODE_NAME     R2367 2
 '@S9S_MB_2U_LIB.S9S_MB_2U(SCH_1):PAGE285_I14@PURE_QUANTA.Q_RES(CHIPS)':
 'B': CDS_PINID='B';
NET_NAME
'FM_REMOTE_DEBUG_DET'
 '@S9S_MB_2U_LIB.S9S_MB_2U(SCH_1):FM_REMOTE_DEBUG_DET':
 C_SIGNAL='@s9s_mb_2u_lib.s9s_mb_2u(sch_1):fm_remote_debug_det';
NODE_NAME     U249 V8
 '@S9S_MB_2U_LIB.S9S_MB_2U(SCH_1):PAGE312_I1@PURE_QUANTA.LCMXO3LF9400C5BG484C(CHIPS)':
 'PB13C': CDS_PINID='PB13C';
NODE_NAME     R2347 2
 '@S9S_MB_2U_LIB.S9S_MB_2U(SCH_1):PAGE312_I183@PURE_QUANTA.Q_RES(CHIPS)':
 'B': CDS_PINID='B';
NET_NAME
'FM_REMOTE_DEBUG_DET_R'
 '@S9S_MB_2U_LIB.S9S_MB_2U(SCH_1):FM_REMOTE_DEBUG_DET_R':
 C_SIGNAL='@s9s_mb_2u_lib.s9s_mb_2u(sch_1):fm_remote_debug_det_r';
NODE_NAME     U87 G
 '@S9S_MB_2U_LIB.S9S_MB_2U(SCH_1):PAGE137_I96@PURE_QUANTA.MOSFET_N(CHIPS)':
 'GATE': CDS_PINID='GATE';
NODE_NAME     R1370 2
 '@S9S_MB_2U_LIB.S9S_MB_2U(SCH_1):PAGE137_I98@PURE_QUANTA.Q_RES(CHIPS)':
 'B': CDS_PINID='B';
NODE_NAME     R3025 1
 '@S9S_MB_2U_LIB.S9S_MB_2U(SCH_1):PAGE137_I102@PURE_QUANTA.Q_RES(CHIPS)':
 'A': CDS_PINID='A';
NODE_NAME     R2347 1
 '@S9S_MB_2U_LIB.S9S_MB_2U(SCH_1):PAGE312_I183@PURE_QUANTA.Q_RES(CHIPS)':
 'A': CDS_PINID='A';
NET_NAME
'FM_RST_PERST_BIT0'
 '@S9S_MB_2U_LIB.S9S_MB_2U(SCH_1):FM_RST_PERST_BIT0':
 C_SIGNAL='@s9s_mb_2u_lib.s9s_mb_2u(sch_1):fm_rst_perst_bit0';
NODE_NAME     U249 P18
 '@S9S_MB_2U_LIB.S9S_MB_2U(SCH_1):PAGE313_I1@PURE_QUANTA.LCMXO3LF9400C5BG484C(CHIPS)':
 'PR21D': CDS_PINID='PR21D';
NODE_NAME     R1742 1
 '@S9S_MB_2U_LIB.S9S_MB_2U(SCH_1):PAGE209_I24@PURE_QUANTA.Q_RES(CHIPS)':
 'A': CDS_PINID='A';
NODE_NAME     R1741 1
 '@S9S_MB_2U_LIB.S9S_MB_2U(SCH_1):PAGE209_I38@PURE_QUANTA.Q_RES(CHIPS)':
 'A': CDS_PINID='A';
NET_NAME
'FM_RST_PERST_BIT1'
 '@S9S_MB_2U_LIB.S9S_MB_2U(SCH_1):FM_RST_PERST_BIT1':
 C_SIGNAL='@s9s_mb_2u_lib.s9s_mb_2u(sch_1):fm_rst_perst_bit1';
NODE_NAME     U249 P17
 '@S9S_MB_2U_LIB.S9S_MB_2U(SCH_1):PAGE313_I1@PURE_QUANTA.LCMXO3LF9400C5BG484C(CHIPS)':
 'PR24A': CDS_PINID='PR24A';
NODE_NAME     R1308 1
 '@S9S_MB_2U_LIB.S9S_MB_2U(SCH_1):PAGE209_I23@PURE_QUANTA.Q_RES(CHIPS)':
 'A': CDS_PINID='A';
NODE_NAME     R1473 1
 '@S9S_MB_2U_LIB.S9S_MB_2U(SCH_1):PAGE209_I37@PURE_QUANTA.Q_RES(CHIPS)':
 'A': CDS_PINID='A';
NET_NAME
'FM_RST_PERST_BIT2'
 '@S9S_MB_2U_LIB.S9S_MB_2U(SCH_1):FM_RST_PERST_BIT2':
 C_SIGNAL='@s9s_mb_2u_lib.s9s_mb_2u(sch_1):fm_rst_perst_bit2';
NODE_NAME     U249 W8
 '@S9S_MB_2U_LIB.S9S_MB_2U(SCH_1):PAGE312_I1@PURE_QUANTA.LCMXO3LF9400C5BG484C(CHIPS)':
 'PB16D': CDS_PINID='PB16D';
NODE_NAME     R1312 1
 '@S9S_MB_2U_LIB.S9S_MB_2U(SCH_1):PAGE209_I22@PURE_QUANTA.Q_RES(CHIPS)':
 'A': CDS_PINID='A';
NODE_NAME     R1474 1
 '@S9S_MB_2U_LIB.S9S_MB_2U(SCH_1):PAGE209_I36@PURE_QUANTA.Q_RES(CHIPS)':
 'A': CDS_PINID='A';
NET_NAME
'FM_S3M_CPU0_CPLD_CONFIG_N'
 '@S9S_MB_2U_LIB.S9S_MB_2U(SCH_1):FM_S3M_CPU0_CPLD_CONFIG_N':
 C_SIGNAL='@s9s_mb_2u_lib.s9s_mb_2u(sch_1):fm_s3m_cpu0_cpld_config_n';
NODE_NAME     U2 CK65
 '@S9S_MB_2U_LIB.S9S_MB_2U(SCH_1):PAGE15_I1@PURE_QUANTA.SOCKET4677_AZIF0045P001C01CS(CHIPS)':
 'TEST_2': CDS_PINID='TEST_2';
NODE_NAME     R321 2
 '@S9S_MB_2U_LIB.S9S_MB_2U(SCH_1):PAGE80_I2@PURE_QUANTA.Q_RES(CHIPS)':
 'B': CDS_PINID='B';
NET_NAME
'FM_S3M_CPU0_CPLD_CRC_ERROR'
 '@S9S_MB_2U_LIB.S9S_MB_2U(SCH_1):FM_S3M_CPU0_CPLD_CRC_ERROR':
 C_SIGNAL='@s9s_mb_2u_lib.s9s_mb_2u(sch_1):fm_s3m_cpu0_cpld_crc_error';
NODE_NAME     U2 CY20
 '@S9S_MB_2U_LIB.S9S_MB_2U(SCH_1):PAGE15_I1@PURE_QUANTA.SOCKET4677_AZIF0045P001C01CS(CHIPS)':
 'CD_INIT_ERROR': CDS_PINID='CD_INIT_ERROR';
NODE_NAME     R1216 2
 '@S9S_MB_2U_LIB.S9S_MB_2U(SCH_1):PAGE80_I1@PURE_QUANTA.Q_RES(CHIPS)':
 'B': CDS_PINID='B';
NODE_NAME     U249 C6
 '@S9S_MB_2U_LIB.S9S_MB_2U(SCH_1):PAGE314_I188@PURE_QUANTA.LCMXO3LF9400C5BG484C(CHIPS)':
 'PT14C': CDS_PINID='PT14C';
NET_NAME
'FM_S3M_CPU0_LVC1_GPIO_0'
 '@S9S_MB_2U_LIB.S9S_MB_2U(SCH_1):FM_S3M_CPU0_LVC1_GPIO_0':
 C_SIGNAL='@s9s_mb_2u_lib.s9s_mb_2u(sch_1):fm_s3m_cpu0_lvc1_gpio_0';
NODE_NAME     U2 BA70
 '@S9S_MB_2U_LIB.S9S_MB_2U(SCH_1):PAGE15_I1@PURE_QUANTA.SOCKET4677_AZIF0045P001C01CS(CHIPS)':
 'PARTITION_ID0': CDS_PINID='PARTITION_ID0';
NODE_NAME     R249 2
 '@S9S_MB_2U_LIB.S9S_MB_2U(SCH_1):PAGE120_I27@PURE_QUANTA.Q_RES(CHIPS)':
 'B': CDS_PINID='B';
NET_NAME
'FM_S3M_CPU0_LVC1_GPIO_1'
 '@S9S_MB_2U_LIB.S9S_MB_2U(SCH_1):FM_S3M_CPU0_LVC1_GPIO_1':
 C_SIGNAL='@s9s_mb_2u_lib.s9s_mb_2u(sch_1):fm_s3m_cpu0_lvc1_gpio_1';
NODE_NAME     U2 AV71
 '@S9S_MB_2U_LIB.S9S_MB_2U(SCH_1):PAGE15_I1@PURE_QUANTA.SOCKET4677_AZIF0045P001C01CS(CHIPS)':
 'PARTITION_ID1': CDS_PINID='PARTITION_ID1';
NODE_NAME     R250 2
 '@S9S_MB_2U_LIB.S9S_MB_2U(SCH_1):PAGE120_I29@PURE_QUANTA.Q_RES(CHIPS)':
 'B': CDS_PINID='B';
NET_NAME
'FM_S3M_CPU0_LVC1_GPIO_2'
 '@S9S_MB_2U_LIB.S9S_MB_2U(SCH_1):FM_S3M_CPU0_LVC1_GPIO_2':
 C_SIGNAL='@s9s_mb_2u_lib.s9s_mb_2u(sch_1):fm_s3m_cpu0_lvc1_gpio_2';
NODE_NAME     U2 AV69
 '@S9S_MB_2U_LIB.S9S_MB_2U(SCH_1):PAGE15_I1@PURE_QUANTA.SOCKET4677_AZIF0045P001C01CS(CHIPS)':
 'TEST_7': CDS_PINID='TEST_7';
NODE_NAME     R253 2
 '@S9S_MB_2U_LIB.S9S_MB_2U(SCH_1):PAGE120_I31@PURE_QUANTA.Q_RES(CHIPS)':
 'B': CDS_PINID='B';
NODE_NAME     R1391 2
 '@S9S_MB_2U_LIB.S9S_MB_2U(SCH_1):PAGE120_I61@PURE_QUANTA.Q_RES(CHIPS)':
 'B': CDS_PINID='B';
NET_NAME
'FM_S3M_CPU0_LVC1_GPIO_3'
 '@S9S_MB_2U_LIB.S9S_MB_2U(SCH_1):FM_S3M_CPU0_LVC1_GPIO_3':
 C_SIGNAL='@s9s_mb_2u_lib.s9s_mb_2u(sch_1):fm_s3m_cpu0_lvc1_gpio_3';
NODE_NAME     U2 AY69
 '@S9S_MB_2U_LIB.S9S_MB_2U(SCH_1):PAGE15_I1@PURE_QUANTA.SOCKET4677_AZIF0045P001C01CS(CHIPS)':
 'TEST_8': CDS_PINID='TEST_8';
NODE_NAME     R254 2
 '@S9S_MB_2U_LIB.S9S_MB_2U(SCH_1):PAGE120_I32@PURE_QUANTA.Q_RES(CHIPS)':
 'B': CDS_PINID='B';
NODE_NAME     R1392 2
 '@S9S_MB_2U_LIB.S9S_MB_2U(SCH_1):PAGE120_I62@PURE_QUANTA.Q_RES(CHIPS)':
 'B': CDS_PINID='B';
NET_NAME
'FM_S3M_CPU0_LVC1_GPIO_4'
 '@S9S_MB_2U_LIB.S9S_MB_2U(SCH_1):FM_S3M_CPU0_LVC1_GPIO_4':
 C_SIGNAL='@s9s_mb_2u_lib.s9s_mb_2u(sch_1):fm_s3m_cpu0_lvc1_gpio_4';
NODE_NAME     U2 AW70
 '@S9S_MB_2U_LIB.S9S_MB_2U(SCH_1):PAGE15_I1@PURE_QUANTA.SOCKET4677_AZIF0045P001C01CS(CHIPS)':
 'RSVD25': CDS_PINID='RSVD25';
NODE_NAME     R251 2
 '@S9S_MB_2U_LIB.S9S_MB_2U(SCH_1):PAGE120_I28@PURE_QUANTA.Q_RES(CHIPS)':
 'B': CDS_PINID='B';
NET_NAME
'FM_S3M_CPU1_CPLD_CONFIG_N'
 '@S9S_MB_2U_LIB.S9S_MB_2U(SCH_1):FM_S3M_CPU1_CPLD_CONFIG_N':
 C_SIGNAL='@s9s_mb_2u_lib.s9s_mb_2u(sch_1):fm_s3m_cpu1_cpld_config_n';
NODE_NAME     U1 CK65
 '@S9S_MB_2U_LIB.S9S_MB_2U(SCH_1):PAGE46_I5@PURE_QUANTA.SOCKET4677_AZIF0045P001C01CS(CHIPS)':
 'TEST_2': CDS_PINID='TEST_2';
NODE_NAME     R327 2
 '@S9S_MB_2U_LIB.S9S_MB_2U(SCH_1):PAGE80_I25@PURE_QUANTA.Q_RES(CHIPS)':
 'B': CDS_PINID='B';
NET_NAME
'FM_S3M_CPU1_CPLD_CRC_ERROR'
 '@S9S_MB_2U_LIB.S9S_MB_2U(SCH_1):FM_S3M_CPU1_CPLD_CRC_ERROR':
 C_SIGNAL='@s9s_mb_2u_lib.s9s_mb_2u(sch_1):fm_s3m_cpu1_cpld_crc_error';
NODE_NAME     U1 CY20
 '@S9S_MB_2U_LIB.S9S_MB_2U(SCH_1):PAGE46_I5@PURE_QUANTA.SOCKET4677_AZIF0045P001C01CS(CHIPS)':
 'CD_INIT_ERROR': CDS_PINID='CD_INIT_ERROR';
NODE_NAME     R1217 2
 '@S9S_MB_2U_LIB.S9S_MB_2U(SCH_1):PAGE80_I22@PURE_QUANTA.Q_RES(CHIPS)':
 'B': CDS_PINID='B';
NODE_NAME     U249 D7
 '@S9S_MB_2U_LIB.S9S_MB_2U(SCH_1):PAGE314_I188@PURE_QUANTA.LCMXO3LF9400C5BG484C(CHIPS)':
 'PT14D': CDS_PINID='PT14D';
NET_NAME
'FM_S3M_CPU1_LVC1_GPIO_0'
 '@S9S_MB_2U_LIB.S9S_MB_2U(SCH_1):FM_S3M_CPU1_LVC1_GPIO_0':
 C_SIGNAL='@s9s_mb_2u_lib.s9s_mb_2u(sch_1):fm_s3m_cpu1_lvc1_gpio_0';
NODE_NAME     U1 BA70
 '@S9S_MB_2U_LIB.S9S_MB_2U(SCH_1):PAGE46_I5@PURE_QUANTA.SOCKET4677_AZIF0045P001C01CS(CHIPS)':
 'PARTITION_ID0': CDS_PINID='PARTITION_ID0';
NODE_NAME     R255 2
 '@S9S_MB_2U_LIB.S9S_MB_2U(SCH_1):PAGE120_I42@PURE_QUANTA.Q_RES(CHIPS)':
 'B': CDS_PINID='B';
NET_NAME
'FM_S3M_CPU1_LVC1_GPIO_1'
 '@S9S_MB_2U_LIB.S9S_MB_2U(SCH_1):FM_S3M_CPU1_LVC1_GPIO_1':
 C_SIGNAL='@s9s_mb_2u_lib.s9s_mb_2u(sch_1):fm_s3m_cpu1_lvc1_gpio_1';
NODE_NAME     U1 AV71
 '@S9S_MB_2U_LIB.S9S_MB_2U(SCH_1):PAGE46_I5@PURE_QUANTA.SOCKET4677_AZIF0045P001C01CS(CHIPS)':
 'PARTITION_ID1': CDS_PINID='PARTITION_ID1';
NODE_NAME     R256 2
 '@S9S_MB_2U_LIB.S9S_MB_2U(SCH_1):PAGE120_I48@PURE_QUANTA.Q_RES(CHIPS)':
 'B': CDS_PINID='B';
NET_NAME
'FM_S3M_CPU1_LVC1_GPIO_2'
 '@S9S_MB_2U_LIB.S9S_MB_2U(SCH_1):FM_S3M_CPU1_LVC1_GPIO_2':
 C_SIGNAL='@s9s_mb_2u_lib.s9s_mb_2u(sch_1):fm_s3m_cpu1_lvc1_gpio_2';
NODE_NAME     U1 AV69
 '@S9S_MB_2U_LIB.S9S_MB_2U(SCH_1):PAGE46_I5@PURE_QUANTA.SOCKET4677_AZIF0045P001C01CS(CHIPS)':
 'TEST_7': CDS_PINID='TEST_7';
NODE_NAME     R259 2
 '@S9S_MB_2U_LIB.S9S_MB_2U(SCH_1):PAGE120_I45@PURE_QUANTA.Q_RES(CHIPS)':
 'B': CDS_PINID='B';
NODE_NAME     R1393 2
 '@S9S_MB_2U_LIB.S9S_MB_2U(SCH_1):PAGE120_I66@PURE_QUANTA.Q_RES(CHIPS)':
 'B': CDS_PINID='B';
NET_NAME
'FM_S3M_CPU1_LVC1_GPIO_3'
 '@S9S_MB_2U_LIB.S9S_MB_2U(SCH_1):FM_S3M_CPU1_LVC1_GPIO_3':
 C_SIGNAL='@s9s_mb_2u_lib.s9s_mb_2u(sch_1):fm_s3m_cpu1_lvc1_gpio_3';
NODE_NAME     U1 AY69
 '@S9S_MB_2U_LIB.S9S_MB_2U(SCH_1):PAGE46_I5@PURE_QUANTA.SOCKET4677_AZIF0045P001C01CS(CHIPS)':
 'TEST_8': CDS_PINID='TEST_8';
NODE_NAME     R260 2
 '@S9S_MB_2U_LIB.S9S_MB_2U(SCH_1):PAGE120_I46@PURE_QUANTA.Q_RES(CHIPS)':
 'B': CDS_PINID='B';
NODE_NAME     R1394 2
 '@S9S_MB_2U_LIB.S9S_MB_2U(SCH_1):PAGE120_I67@PURE_QUANTA.Q_RES(CHIPS)':
 'B': CDS_PINID='B';
NET_NAME
'FM_S3M_CPU1_LVC1_GPIO_4'
 '@S9S_MB_2U_LIB.S9S_MB_2U(SCH_1):FM_S3M_CPU1_LVC1_GPIO_4':
 C_SIGNAL='@s9s_mb_2u_lib.s9s_mb_2u(sch_1):fm_s3m_cpu1_lvc1_gpio_4';
NODE_NAME     U1 AW70
 '@S9S_MB_2U_LIB.S9S_MB_2U(SCH_1):PAGE46_I5@PURE_QUANTA.SOCKET4677_AZIF0045P001C01CS(CHIPS)':
 'RSVD25': CDS_PINID='RSVD25';
NODE_NAME     R257 2
 '@S9S_MB_2U_LIB.S9S_MB_2U(SCH_1):PAGE120_I43@PURE_QUANTA.Q_RES(CHIPS)':
 'B': CDS_PINID='B';
NET_NAME
'FM_SCM_PRSNT1_N'
 '@S9S_MB_2U_LIB.S9S_MB_2U(SCH_1):FM_SCM_PRSNT1_N':
 C_SIGNAL='@s9s_mb_2u_lib.s9s_mb_2u(sch_1):fm_scm_prsnt1_n';
NODE_NAME     R1854 2
 '@S9S_MB_2U_LIB.S9S_MB_2U(SCH_1):PAGE229_I2@PURE_QUANTA.Q_RES(CHIPS)':
 'B': CDS_PINID='B';
NODE_NAME     R1856 1
 '@S9S_MB_2U_LIB.S9S_MB_2U(SCH_1):PAGE229_I3@PURE_QUANTA.Q_RES(CHIPS)':
 'A': CDS_PINID='A';
NODE_NAME     J41 A57
 '@S9S_MB_2U_LIB.S9S_MB_2U(SCH_1):PAGE227_I173@PURE_QUANTA.SCONN168_ME1016810202011(CHIPS)':
 'PERP12': CDS_PINID='PERP12';
NET_NAME
'FM_SCM_PRSNT1_R_N'
 '@S9S_MB_2U_LIB.S9S_MB_2U(SCH_1):FM_SCM_PRSNT1_R_N':
 C_SIGNAL='@s9s_mb_2u_lib.s9s_mb_2u(sch_1):fm_scm_prsnt1_r_n';
NODE_NAME     R1856 2
 '@S9S_MB_2U_LIB.S9S_MB_2U(SCH_1):PAGE229_I3@PURE_QUANTA.Q_RES(CHIPS)':
 'B': CDS_PINID='B';
NODE_NAME     Q39 G
 '@S9S_MB_2U_LIB.S9S_MB_2U(SCH_1):PAGE229_I9@PURE_QUANTA.MOSFET_NCH_GDS_ESD_PROTECTED(CHIPS)':
 'G': CDS_PINID='G';
NET_NAME
'FM_SLPS3_PLD_N'
 '@S9S_MB_2U_LIB.S9S_MB_2U(SCH_1):FM_SLPS3_PLD_N':
 C_SIGNAL='@s9s_mb_2u_lib.s9s_mb_2u(sch_1):fm_slps3_pld_n';
NODE_NAME     R1995 2
 '@S9S_MB_2U_LIB.S9S_MB_2U(SCH_1):PAGE212_I86@PURE_QUANTA.Q_RES(CHIPS)':
 'B': CDS_PINID='B';
NODE_NAME     U249 U15
 '@S9S_MB_2U_LIB.S9S_MB_2U(SCH_1):PAGE312_I1@PURE_QUANTA.LCMXO3LF9400C5BG484C(CHIPS)':
 'PB38D': CDS_PINID='PB38D';
NET_NAME
'FM_SLPS4_PLD_N'
 '@S9S_MB_2U_LIB.S9S_MB_2U(SCH_1):FM_SLPS4_PLD_N':
 C_SIGNAL='@s9s_mb_2u_lib.s9s_mb_2u(sch_1):fm_slps4_pld_n';
NODE_NAME     R1996 2
 '@S9S_MB_2U_LIB.S9S_MB_2U(SCH_1):PAGE212_I87@PURE_QUANTA.Q_RES(CHIPS)':
 'B': CDS_PINID='B';
NODE_NAME     U249 U21
 '@S9S_MB_2U_LIB.S9S_MB_2U(SCH_1):PAGE313_I1@PURE_QUANTA.LCMXO3LF9400C5BG484C(CHIPS)':
 'PR24D': CDS_PINID='PR24D';
NET_NAME
'FM_SLP_SUS_RSM_RST_N'
 '@S9S_MB_2U_LIB.S9S_MB_2U(SCH_1):FM_SLP_SUS_RSM_RST_N':
 C_SIGNAL='@s9s_mb_2u_lib.s9s_mb_2u(sch_1):fm_slp_sus_rsm_rst_n';
NODE_NAME     R1660 1
 '@S9S_MB_2U_LIB.S9S_MB_2U(SCH_1):PAGE209_I14@PURE_QUANTA.Q_RES(CHIPS)':
 'A': CDS_PINID='A';
NODE_NAME     U249 C9
 '@S9S_MB_2U_LIB.S9S_MB_2U(SCH_1):PAGE314_I188@PURE_QUANTA.LCMXO3LF9400C5BG484C(CHIPS)':
 'PT20C': CDS_PINID='PT20C';
NODE_NAME     R4674 1
 '@S9S_MB_2U_LIB.S9S_MB_2U(SCH_1):PAGE209_I46@PURE_QUANTA.Q_RES(CHIPS)':
 'A': CDS_PINID='A';
NODE_NAME     R1736 2
 '@S9S_MB_2U_LIB.S9S_MB_2U(SCH_1):PAGE174_I99@PURE_QUANTA.Q_RES(CHIPS)':
 'B': CDS_PINID='B';
NET_NAME
'FM_SMB_1_ALERT_GPU'
 '@S9S_MB_2U_LIB.S9S_MB_2U(SCH_1):FM_SMB_1_ALERT_GPU':
 C_SIGNAL='@s9s_mb_2u_lib.s9s_mb_2u(sch_1):fm_smb_1_alert_gpu';
NODE_NAME     R3029 2
 '@S9S_MB_2U_LIB.S9S_MB_2U(SCH_1):PAGE145_I144@PURE_QUANTA.Q_RES(CHIPS)':
 'B': CDS_PINID='B';
NODE_NAME     Q75 5
 '@S9S_MB_2U_LIB.S9S_MB_2U(SCH_1):PAGE145_I151@PURE_QUANTA.MOSFET_NCH_DUAL(CHIPS)':
 'G2': CDS_PINID='G2';
NODE_NAME     Q75 6
 '@S9S_MB_2U_LIB.S9S_MB_2U(SCH_1):PAGE145_I152@PURE_QUANTA.MOSFET_NCH_DUAL(CHIPS)':
 'D1': CDS_PINID='D1';
NET_NAME
'FM_SMB_1_ALERT_GPU_ISO_N'
 '@S9S_MB_2U_LIB.S9S_MB_2U(SCH_1):FM_SMB_1_ALERT_GPU_ISO_N':
 C_SIGNAL='@s9s_mb_2u_lib.s9s_mb_2u(sch_1):fm_smb_1_alert_gpu_iso_n';
NODE_NAME     R3030 2
 '@S9S_MB_2U_LIB.S9S_MB_2U(SCH_1):PAGE145_I146@PURE_QUANTA.Q_RES(CHIPS)':
 'B': CDS_PINID='B';
NODE_NAME     C1802 1
 '@S9S_MB_2U_LIB.S9S_MB_2U(SCH_1):PAGE145_I148@PURE_QUANTA.Q_CAP(CHIPS)':
 'A': CDS_PINID='A';
NODE_NAME     Q75 3
 '@S9S_MB_2U_LIB.S9S_MB_2U(SCH_1):PAGE145_I151@PURE_QUANTA.MOSFET_NCH_DUAL(CHIPS)':
 'D2': CDS_PINID='D2';
NODE_NAME     R3066 1
 '@S9S_MB_2U_LIB.S9S_MB_2U(SCH_1):PAGE313_I175@PURE_QUANTA.Q_RES(CHIPS)':
 'A': CDS_PINID='A';
NET_NAME
'FM_SMB_1_ALERT_GPU_ISO_R_N'
 '@S9S_MB_2U_LIB.S9S_MB_2U(SCH_1):FM_SMB_1_ALERT_GPU_ISO_R_N':
 C_SIGNAL='@s9s_mb_2u_lib.s9s_mb_2u(sch_1):fm_smb_1_alert_gpu_iso_r_n';
NODE_NAME     U249 W21
 '@S9S_MB_2U_LIB.S9S_MB_2U(SCH_1):PAGE313_I1@PURE_QUANTA.LCMXO3LF9400C5BG484C(CHIPS)':
 'PR28B': CDS_PINID='PR28B';
NODE_NAME     R3066 2
 '@S9S_MB_2U_LIB.S9S_MB_2U(SCH_1):PAGE313_I175@PURE_QUANTA.Q_RES(CHIPS)':
 'B': CDS_PINID='B';
NET_NAME
'FM_SMB_1_ALERT_GPU_N'
 '@S9S_MB_2U_LIB.S9S_MB_2U(SCH_1):FM_SMB_1_ALERT_GPU_N':
 C_SIGNAL='@s9s_mb_2u_lib.s9s_mb_2u(sch_1):fm_smb_1_alert_gpu_n';
NODE_NAME     R3028 1
 '@S9S_MB_2U_LIB.S9S_MB_2U(SCH_1):PAGE145_I139@PURE_QUANTA.Q_RES(CHIPS)':
 'A': CDS_PINID='A';
NODE_NAME     Q75 2
 '@S9S_MB_2U_LIB.S9S_MB_2U(SCH_1):PAGE145_I152@PURE_QUANTA.MOSFET_NCH_DUAL(CHIPS)':
 'G1': CDS_PINID='G1';
NODE_NAME     J110 N4
 '@S9S_MB_2U_LIB.S9S_MB_2U(SCH_1):PAGE318_I54@PURE_QUANTA.CONN112_10137002101LF(CHIPS)':
 'N4': CDS_PINID='N4';
NODE_NAME     R3510 2
 '@S9S_MB_2U_LIB.S9S_MB_2U(SCH_1):PAGE145_I176@PURE_QUANTA.Q_RES(CHIPS)':
 'B': CDS_PINID='B';
NET_NAME
'FM_SMB_2_ALERT_GPU'
 '@S9S_MB_2U_LIB.S9S_MB_2U(SCH_1):FM_SMB_2_ALERT_GPU':
 C_SIGNAL='@s9s_mb_2u_lib.s9s_mb_2u(sch_1):fm_smb_2_alert_gpu';
NODE_NAME     Q74 6
 '@S9S_MB_2U_LIB.S9S_MB_2U(SCH_1):PAGE145_I121@PURE_QUANTA.MOSFET_NCH_DUAL(CHIPS)':
 'D1': CDS_PINID='D1';
NODE_NAME     Q74 5
 '@S9S_MB_2U_LIB.S9S_MB_2U(SCH_1):PAGE145_I122@PURE_QUANTA.MOSFET_NCH_DUAL(CHIPS)':
 'G2': CDS_PINID='G2';
NODE_NAME     R3034 2
 '@S9S_MB_2U_LIB.S9S_MB_2U(SCH_1):PAGE145_I129@PURE_QUANTA.Q_RES(CHIPS)':
 'B': CDS_PINID='B';
NET_NAME
'FM_SMB_2_ALERT_GPU_ISO_N'
 '@S9S_MB_2U_LIB.S9S_MB_2U(SCH_1):FM_SMB_2_ALERT_GPU_ISO_N':
 C_SIGNAL='@s9s_mb_2u_lib.s9s_mb_2u(sch_1):fm_smb_2_alert_gpu_iso_n';
NODE_NAME     Q74 3
 '@S9S_MB_2U_LIB.S9S_MB_2U(SCH_1):PAGE145_I122@PURE_QUANTA.MOSFET_NCH_DUAL(CHIPS)':
 'D2': CDS_PINID='D2';
NODE_NAME     C1804 1
 '@S9S_MB_2U_LIB.S9S_MB_2U(SCH_1):PAGE145_I125@PURE_QUANTA.Q_CAP(CHIPS)':
 'A': CDS_PINID='A';
NODE_NAME     R3035 2
 '@S9S_MB_2U_LIB.S9S_MB_2U(SCH_1):PAGE145_I127@PURE_QUANTA.Q_RES(CHIPS)':
 'B': CDS_PINID='B';
NODE_NAME     R3067 1
 '@S9S_MB_2U_LIB.S9S_MB_2U(SCH_1):PAGE313_I176@PURE_QUANTA.Q_RES(CHIPS)':
 'A': CDS_PINID='A';
NET_NAME
'FM_SMB_2_ALERT_GPU_ISO_R_N'
 '@S9S_MB_2U_LIB.S9S_MB_2U(SCH_1):FM_SMB_2_ALERT_GPU_ISO_R_N':
 C_SIGNAL='@s9s_mb_2u_lib.s9s_mb_2u(sch_1):fm_smb_2_alert_gpu_iso_r_n';
NODE_NAME     U249 U19
 '@S9S_MB_2U_LIB.S9S_MB_2U(SCH_1):PAGE313_I1@PURE_QUANTA.LCMXO3LF9400C5BG484C(CHIPS)':
 'PR28C': CDS_PINID='PR28C';
NODE_NAME     R3067 2
 '@S9S_MB_2U_LIB.S9S_MB_2U(SCH_1):PAGE313_I176@PURE_QUANTA.Q_RES(CHIPS)':
 'B': CDS_PINID='B';
NET_NAME
'FM_SMB_2_ALERT_GPU_N'
 '@S9S_MB_2U_LIB.S9S_MB_2U(SCH_1):FM_SMB_2_ALERT_GPU_N':
 C_SIGNAL='@s9s_mb_2u_lib.s9s_mb_2u(sch_1):fm_smb_2_alert_gpu_n';
NODE_NAME     Q74 2
 '@S9S_MB_2U_LIB.S9S_MB_2U(SCH_1):PAGE145_I121@PURE_QUANTA.MOSFET_NCH_DUAL(CHIPS)':
 'G1': CDS_PINID='G1';
NODE_NAME     R3032 1
 '@S9S_MB_2U_LIB.S9S_MB_2U(SCH_1):PAGE145_I134@PURE_QUANTA.Q_RES(CHIPS)':
 'A': CDS_PINID='A';
NODE_NAME     J110 N6
 '@S9S_MB_2U_LIB.S9S_MB_2U(SCH_1):PAGE318_I16@PURE_QUANTA.CONN112_10137002101LF(CHIPS)':
 'N6': CDS_PINID='N6';
NODE_NAME     R3514 2
 '@S9S_MB_2U_LIB.S9S_MB_2U(SCH_1):PAGE145_I175@PURE_QUANTA.Q_RES(CHIPS)':
 'B': CDS_PINID='B';
NET_NAME
'FM_SMB_CPU0_ALERT'
 '@S9S_MB_2U_LIB.S9S_MB_2U(SCH_1):FM_SMB_CPU0_ALERT':
 C_SIGNAL='@s9s_mb_2u_lib.s9s_mb_2u(sch_1):fm_smb_cpu0_alert';
NODE_NAME     R1921 1
 '@S9S_MB_2U_LIB.S9S_MB_2U(SCH_1):PAGE154_I132@PURE_QUANTA.Q_RES(CHIPS)':
 'A': CDS_PINID='A';
NODE_NAME     U209 1
 '@S9S_MB_2U_LIB.S9S_MB_2U(SCH_1):PAGE154_I206@PURE_QUANTA.PCA9555APW(CHIPS)':
 'INT#': CDS_PINID='\int#\';
NET_NAME
'FM_SMB_CPU0_ALERT_R1'
 '@S9S_MB_2U_LIB.S9S_MB_2U(SCH_1):FM_SMB_CPU0_ALERT_R1':
 C_SIGNAL='@s9s_mb_2u_lib.s9s_mb_2u(sch_1):fm_smb_cpu0_alert_r1';
NODE_NAME     R1002 2
 '@S9S_MB_2U_LIB.S9S_MB_2U(SCH_1):PAGE223_I34@PURE_QUANTA.Q_RES(CHIPS)':
 'B': CDS_PINID='B';
NODE_NAME     Q15 6
 '@S9S_MB_2U_LIB.S9S_MB_2U(SCH_1):PAGE223_I104@PURE_QUANTA.MOSFET_NCH_DUAL(CHIPS)':
 'D1': CDS_PINID='D1';
NODE_NAME     Q15 5
 '@S9S_MB_2U_LIB.S9S_MB_2U(SCH_1):PAGE223_I108@PURE_QUANTA.MOSFET_NCH_DUAL(CHIPS)':
 'G2': CDS_PINID='G2';
NET_NAME
'FM_SMB_CPU1_ALERT'
 '@S9S_MB_2U_LIB.S9S_MB_2U(SCH_1):FM_SMB_CPU1_ALERT':
 C_SIGNAL='@s9s_mb_2u_lib.s9s_mb_2u(sch_1):fm_smb_cpu1_alert';
NODE_NAME     R3158 1
 '@S9S_MB_2U_LIB.S9S_MB_2U(SCH_1):PAGE132_I23@PURE_QUANTA.Q_RES(CHIPS)':
 'A': CDS_PINID='A';
NODE_NAME     U51 1
 '@S9S_MB_2U_LIB.S9S_MB_2U(SCH_1):PAGE132_I66@PURE_QUANTA.PCA9555APW(CHIPS)':
 'INT#': CDS_PINID='\int#\';
NET_NAME
'FM_SMB_CPU1_ALERT_R1'
 '@S9S_MB_2U_LIB.S9S_MB_2U(SCH_1):FM_SMB_CPU1_ALERT_R1':
 C_SIGNAL='@s9s_mb_2u_lib.s9s_mb_2u(sch_1):fm_smb_cpu1_alert_r1';
NODE_NAME     R1003 2
 '@S9S_MB_2U_LIB.S9S_MB_2U(SCH_1):PAGE223_I38@PURE_QUANTA.Q_RES(CHIPS)':
 'B': CDS_PINID='B';
NODE_NAME     Q16 6
 '@S9S_MB_2U_LIB.S9S_MB_2U(SCH_1):PAGE223_I106@PURE_QUANTA.MOSFET_NCH_DUAL(CHIPS)':
 'D1': CDS_PINID='D1';
NODE_NAME     Q16 5
 '@S9S_MB_2U_LIB.S9S_MB_2U(SCH_1):PAGE223_I109@PURE_QUANTA.MOSFET_NCH_DUAL(CHIPS)':
 'G2': CDS_PINID='G2';
NET_NAME
'FM_SMB_PEHPCPU0_PCIE_ALERT_N'
 '@S9S_MB_2U_LIB.S9S_MB_2U(SCH_1):FM_SMB_PEHPCPU0_PCIE_ALERT_N':
 C_SIGNAL='@s9s_mb_2u_lib.s9s_mb_2u(sch_1):fm_smb_pehpcpu0_pcie_alert_n';
NODE_NAME     R1921 2
 '@S9S_MB_2U_LIB.S9S_MB_2U(SCH_1):PAGE154_I132@PURE_QUANTA.Q_RES(CHIPS)':
 'B': CDS_PINID='B';
NODE_NAME     R998 1
 '@S9S_MB_2U_LIB.S9S_MB_2U(SCH_1):PAGE223_I53@PURE_QUANTA.Q_RES(CHIPS)':
 'A': CDS_PINID='A';
NODE_NAME     JP7 1
 '@S9S_MB_2U_LIB.S9S_MB_2U(SCH_1):PAGE223_I64@PURE_QUANTA.CONN3_210HP1030BR1(CHIPS)':
 '1': CDS_PINID='\1\';
NET_NAME
'FM_SMB_PEHPCPU0_PCIE_ALERT_R_N'
 '@S9S_MB_2U_LIB.S9S_MB_2U(SCH_1):FM_SMB_PEHPCPU0_PCIE_ALERT_R_N':
 C_SIGNAL='@s9s_mb_2u_lib.s9s_mb_2u(sch_1):fm_smb_pehpcpu0_pcie_alert_r_n';
NODE_NAME     R1000 2
 '@S9S_MB_2U_LIB.S9S_MB_2U(SCH_1):PAGE223_I52@PURE_QUANTA.Q_RES(CHIPS)':
 'B': CDS_PINID='B';
NODE_NAME     R998 2
 '@S9S_MB_2U_LIB.S9S_MB_2U(SCH_1):PAGE223_I53@PURE_QUANTA.Q_RES(CHIPS)':
 'B': CDS_PINID='B';
NODE_NAME     Q15 2
 '@S9S_MB_2U_LIB.S9S_MB_2U(SCH_1):PAGE223_I104@PURE_QUANTA.MOSFET_NCH_DUAL(CHIPS)':
 'G1': CDS_PINID='G1';
NET_NAME
'FM_SMB_PEHPCPU1_PCIE_ALERT_N'
 '@S9S_MB_2U_LIB.S9S_MB_2U(SCH_1):FM_SMB_PEHPCPU1_PCIE_ALERT_N':
 C_SIGNAL='@s9s_mb_2u_lib.s9s_mb_2u(sch_1):fm_smb_pehpcpu1_pcie_alert_n';
NODE_NAME     JP7 3
 '@S9S_MB_2U_LIB.S9S_MB_2U(SCH_1):PAGE223_I64@PURE_QUANTA.CONN3_210HP1030BR1(CHIPS)':
 '3': CDS_PINID='\3\';
NODE_NAME     R999 1
 '@S9S_MB_2U_LIB.S9S_MB_2U(SCH_1):PAGE223_I69@PURE_QUANTA.Q_RES(CHIPS)':
 'A': CDS_PINID='A';
NODE_NAME     R3158 2
 '@S9S_MB_2U_LIB.S9S_MB_2U(SCH_1):PAGE132_I23@PURE_QUANTA.Q_RES(CHIPS)':
 'B': CDS_PINID='B';
NET_NAME
'FM_SMB_PEHPCPU1_PCIE_ALERT_R_N'
 '@S9S_MB_2U_LIB.S9S_MB_2U(SCH_1):FM_SMB_PEHPCPU1_PCIE_ALERT_R_N':
 C_SIGNAL='@s9s_mb_2u_lib.s9s_mb_2u(sch_1):fm_smb_pehpcpu1_pcie_alert_r_n';
NODE_NAME     R1001 2
 '@S9S_MB_2U_LIB.S9S_MB_2U(SCH_1):PAGE223_I55@PURE_QUANTA.Q_RES(CHIPS)':
 'B': CDS_PINID='B';
NODE_NAME     R999 2
 '@S9S_MB_2U_LIB.S9S_MB_2U(SCH_1):PAGE223_I69@PURE_QUANTA.Q_RES(CHIPS)':
 'B': CDS_PINID='B';
NODE_NAME     Q16 2
 '@S9S_MB_2U_LIB.S9S_MB_2U(SCH_1):PAGE223_I106@PURE_QUANTA.MOSFET_NCH_DUAL(CHIPS)':
 'G1': CDS_PINID='G1';
NET_NAME
'FM_SOL_UART_CH_SEL'
 '@S9S_MB_2U_LIB.S9S_MB_2U(SCH_1):FM_SOL_UART_CH_SEL':
 C_SIGNAL='@s9s_mb_2u_lib.s9s_mb_2u(sch_1):fm_sol_uart_ch_sel';
NODE_NAME     U249 K22
 '@S9S_MB_2U_LIB.S9S_MB_2U(SCH_1):PAGE313_I1@PURE_QUANTA.LCMXO3LF9400C5BG484C(CHIPS)':
 'PR16A': CDS_PINID='PR16A';
NODE_NAME     R3778 2
 '@S9S_MB_2U_LIB.S9S_MB_2U(SCH_1):PAGE227_I159@PURE_QUANTA.Q_RES(CHIPS)':
 'B': CDS_PINID='B';
NET_NAME
'FM_SOL_UART_CH_SEL_R'
 '@S9S_MB_2U_LIB.S9S_MB_2U(SCH_1):FM_SOL_UART_CH_SEL_R':
 C_SIGNAL='@s9s_mb_2u_lib.s9s_mb_2u(sch_1):fm_sol_uart_ch_sel_r';
NODE_NAME     R3778 1
 '@S9S_MB_2U_LIB.S9S_MB_2U(SCH_1):PAGE227_I159@PURE_QUANTA.Q_RES(CHIPS)':
 'A': CDS_PINID='A';
NODE_NAME     J41 OB14
 '@S9S_MB_2U_LIB.S9S_MB_2U(SCH_1):PAGE227_I173@PURE_QUANTA.SCONN168_ME1016810202011(CHIPS)':
 'RBT_CRS_DV': CDS_PINID='RBT_CRS_DV';
NET_NAME
'FM_SPD_REMOTE_EN'
 '@S9S_MB_2U_LIB.S9S_MB_2U(SCH_1):FM_SPD_REMOTE_EN':
 C_SIGNAL='@s9s_mb_2u_lib.s9s_mb_2u(sch_1):fm_spd_remote_en';
NODE_NAME     U15 1
 '@S9S_MB_2U_LIB.S9S_MB_2U(SCH_1):PAGE217_I19@PURE_QUANTA.QS3VH257QG8(CHIPS)':
 'S': CDS_PINID='S';
NODE_NAME     R318 1
 '@S9S_MB_2U_LIB.S9S_MB_2U(SCH_1):PAGE217_I42@PURE_QUANTA.Q_RES(CHIPS)':
 'A': CDS_PINID='A';
NODE_NAME     R87 2
 '@S9S_MB_2U_LIB.S9S_MB_2U(SCH_1):PAGE217_I43@PURE_QUANTA.Q_RES(CHIPS)':
 'B': CDS_PINID='B';
NODE_NAME     U14 1
 '@S9S_MB_2U_LIB.S9S_MB_2U(SCH_1):PAGE218_I12@PURE_QUANTA.QS3VH257QG8(CHIPS)':
 'S': CDS_PINID='S';
NODE_NAME     R1821 2
 '@S9S_MB_2U_LIB.S9S_MB_2U(SCH_1):PAGE217_I53@PURE_QUANTA.Q_RES(CHIPS)':
 'B': CDS_PINID='B';
NET_NAME
'FM_SPD_REMOTE_EN_R'
 '@S9S_MB_2U_LIB.S9S_MB_2U(SCH_1):FM_SPD_REMOTE_EN_R':
 C_SIGNAL='@s9s_mb_2u_lib.s9s_mb_2u(sch_1):fm_spd_remote_en_r';
NODE_NAME     U249 AB15
 '@S9S_MB_2U_LIB.S9S_MB_2U(SCH_1):PAGE312_I1@PURE_QUANTA.LCMXO3LF9400C5BG484C(CHIPS)':
 'PB35A': CDS_PINID='PB35A';
NODE_NAME     R1821 1
 '@S9S_MB_2U_LIB.S9S_MB_2U(SCH_1):PAGE217_I53@PURE_QUANTA.Q_RES(CHIPS)':
 'A': CDS_PINID='A';
NET_NAME
'FM_SPI_3V3_1V8_VOLTAGE'
 '@S9S_MB_2U_LIB.S9S_MB_2U(SCH_1):FM_SPI_3V3_1V8_VOLTAGE':
 C_SIGNAL='@s9s_mb_2u_lib.s9s_mb_2u(sch_1):fm_spi_3v3_1v8_voltage';
NODE_NAME     U4 AU13
 '@S9S_MB_2U_LIB.S9S_MB_2U(SCH_1):PAGE177_I27@PURE_QUANTA.EMMITSBURG_REV0P9(CHIPS)':
 'GPPC_S_4_CPU_GP_2': CDS_PINID='GPPC_S_4_CPU_GP_2';
NODE_NAME     R374 2
 '@S9S_MB_2U_LIB.S9S_MB_2U(SCH_1):PAGE186_I60@PURE_QUANTA.Q_RES(CHIPS)':
 'B': CDS_PINID='B';
NODE_NAME     R375 1
 '@S9S_MB_2U_LIB.S9S_MB_2U(SCH_1):PAGE186_I61@PURE_QUANTA.Q_RES(CHIPS)':
 'A': CDS_PINID='A';
NET_NAME
'FM_SUSACK_N'
 '@S9S_MB_2U_LIB.S9S_MB_2U(SCH_1):FM_SUSACK_N':
 C_SIGNAL='@s9s_mb_2u_lib.s9s_mb_2u(sch_1):fm_susack_n';
NODE_NAME     U4 BA7
 '@S9S_MB_2U_LIB.S9S_MB_2U(SCH_1):PAGE177_I27@PURE_QUANTA.EMMITSBURG_REV0P9(CHIPS)':
 'GPPC_S_7_SUSACK_N': CDS_PINID='GPPC_S_7_SUSACK_N';
NODE_NAME     R1461 2
 '@S9S_MB_2U_LIB.S9S_MB_2U(SCH_1):PAGE177_I80@PURE_QUANTA.Q_RES(CHIPS)':
 'B': CDS_PINID='B';
NODE_NAME     R2071 2
 '@S9S_MB_2U_LIB.S9S_MB_2U(SCH_1):PAGE314_I137@PURE_QUANTA.Q_RES(CHIPS)':
 'B': CDS_PINID='B';
NET_NAME
'FM_SWB_BIC_READY'
 '@S9S_MB_2U_LIB.S9S_MB_2U(SCH_1):FM_SWB_BIC_READY':
 C_SIGNAL='@s9s_mb_2u_lib.s9s_mb_2u(sch_1):fm_swb_bic_ready';
NODE_NAME     R2836 2
 '@S9S_MB_2U_LIB.S9S_MB_2U(SCH_1):PAGE145_I19@PURE_QUANTA.Q_RES(CHIPS)':
 'B': CDS_PINID='B';
NODE_NAME     Q70 6
 '@S9S_MB_2U_LIB.S9S_MB_2U(SCH_1):PAGE145_I35@PURE_QUANTA.MOSFET_NCH_DUAL(CHIPS)':
 'D1': CDS_PINID='D1';
NODE_NAME     Q70 5
 '@S9S_MB_2U_LIB.S9S_MB_2U(SCH_1):PAGE145_I120@PURE_QUANTA.MOSFET_NCH_DUAL(CHIPS)':
 'G2': CDS_PINID='G2';
NET_NAME
'FM_SWB_BIC_READY_ISO_N'
 '@S9S_MB_2U_LIB.S9S_MB_2U(SCH_1):FM_SWB_BIC_READY_ISO_N':
 C_SIGNAL='@s9s_mb_2u_lib.s9s_mb_2u(sch_1):fm_swb_bic_ready_iso_n';
NODE_NAME     C1754 1
 '@S9S_MB_2U_LIB.S9S_MB_2U(SCH_1):PAGE145_I92@PURE_QUANTA.Q_CAP(CHIPS)':
 'A': CDS_PINID='A';
NODE_NAME     R2933 2
 '@S9S_MB_2U_LIB.S9S_MB_2U(SCH_1):PAGE145_I97@PURE_QUANTA.Q_RES(CHIPS)':
 'B': CDS_PINID='B';
NODE_NAME     Q70 3
 '@S9S_MB_2U_LIB.S9S_MB_2U(SCH_1):PAGE145_I120@PURE_QUANTA.MOSFET_NCH_DUAL(CHIPS)':
 'D2': CDS_PINID='D2';
NODE_NAME     R2844 1
 '@S9S_MB_2U_LIB.S9S_MB_2U(SCH_1):PAGE314_I112@PURE_QUANTA.Q_RES(CHIPS)':
 'A': CDS_PINID='A';
NET_NAME
'FM_SWB_BIC_READY_ISO_R_N'
 '@S9S_MB_2U_LIB.S9S_MB_2U(SCH_1):FM_SWB_BIC_READY_ISO_R_N':
 C_SIGNAL='@s9s_mb_2u_lib.s9s_mb_2u(sch_1):fm_swb_bic_ready_iso_r_n';
NODE_NAME     R2844 2
 '@S9S_MB_2U_LIB.S9S_MB_2U(SCH_1):PAGE314_I112@PURE_QUANTA.Q_RES(CHIPS)':
 'B': CDS_PINID='B';
NODE_NAME     U249 B3
 '@S9S_MB_2U_LIB.S9S_MB_2U(SCH_1):PAGE314_I188@PURE_QUANTA.LCMXO3LF9400C5BG484C(CHIPS)':
 'PT11A': CDS_PINID='PT11A';
NET_NAME
'FM_SWB_BIC_READY_N'
 '@S9S_MB_2U_LIB.S9S_MB_2U(SCH_1):FM_SWB_BIC_READY_N':
 C_SIGNAL='@s9s_mb_2u_lib.s9s_mb_2u(sch_1):fm_swb_bic_ready_n';
NODE_NAME     J105 N4
 '@S9S_MB_2U_LIB.S9S_MB_2U(SCH_1):PAGE142_I65@PURE_QUANTA.CONN112_10137002101LF(CHIPS)':
 'N4': CDS_PINID='N4';
NODE_NAME     Q70 2
 '@S9S_MB_2U_LIB.S9S_MB_2U(SCH_1):PAGE145_I35@PURE_QUANTA.MOSFET_NCH_DUAL(CHIPS)':
 'G1': CDS_PINID='G1';
NODE_NAME     R2833 1
 '@S9S_MB_2U_LIB.S9S_MB_2U(SCH_1):PAGE145_I60@PURE_QUANTA.Q_RES(CHIPS)':
 'A': CDS_PINID='A';
NODE_NAME     R2832 2
 '@S9S_MB_2U_LIB.S9S_MB_2U(SCH_1):PAGE145_I67@PURE_QUANTA.Q_RES(CHIPS)':
 'B': CDS_PINID='B';
NET_NAME
'FM_SWB_PWRGD'
 '@S9S_MB_2U_LIB.S9S_MB_2U(SCH_1):FM_SWB_PWRGD':
 C_SIGNAL='@s9s_mb_2u_lib.s9s_mb_2u(sch_1):fm_swb_pwrgd';
NODE_NAME     J106 A3
 '@S9S_MB_2U_LIB.S9S_MB_2U(SCH_1):PAGE144_I65@PURE_QUANTA.CONN112_10137002101LF(CHIPS)':
 'A3': CDS_PINID='A3';
NODE_NAME     R2838 1
 '@S9S_MB_2U_LIB.S9S_MB_2U(SCH_1):PAGE145_I62@PURE_QUANTA.Q_RES(CHIPS)':
 'A': CDS_PINID='A';
NODE_NAME     R2837 2
 '@S9S_MB_2U_LIB.S9S_MB_2U(SCH_1):PAGE145_I80@PURE_QUANTA.Q_RES(CHIPS)':
 'B': CDS_PINID='B';
NODE_NAME     Q71 2
 '@S9S_MB_2U_LIB.S9S_MB_2U(SCH_1):PAGE145_I118@PURE_QUANTA.MOSFET_NCH_DUAL(CHIPS)':
 'G1': CDS_PINID='G1';
NET_NAME
'FM_SWB_PWRGD_ISO'
 '@S9S_MB_2U_LIB.S9S_MB_2U(SCH_1):FM_SWB_PWRGD_ISO':
 C_SIGNAL='@s9s_mb_2u_lib.s9s_mb_2u(sch_1):fm_swb_pwrgd_iso';
NODE_NAME     Q71 3
 '@S9S_MB_2U_LIB.S9S_MB_2U(SCH_1):PAGE145_I100@PURE_QUANTA.MOSFET_NCH_DUAL(CHIPS)':
 'D2': CDS_PINID='D2';
NODE_NAME     R2934 2
 '@S9S_MB_2U_LIB.S9S_MB_2U(SCH_1):PAGE145_I101@PURE_QUANTA.Q_RES(CHIPS)':
 'B': CDS_PINID='B';
NODE_NAME     C1774 1
 '@S9S_MB_2U_LIB.S9S_MB_2U(SCH_1):PAGE145_I111@PURE_QUANTA.Q_CAP(CHIPS)':
 'A': CDS_PINID='A';
NODE_NAME     R2663 1
 '@S9S_MB_2U_LIB.S9S_MB_2U(SCH_1):PAGE314_I114@PURE_QUANTA.Q_RES(CHIPS)':
 'A': CDS_PINID='A';
NET_NAME
'FM_SWB_PWRGD_ISO_R'
 '@S9S_MB_2U_LIB.S9S_MB_2U(SCH_1):FM_SWB_PWRGD_ISO_R':
 C_SIGNAL='@s9s_mb_2u_lib.s9s_mb_2u(sch_1):fm_swb_pwrgd_iso_r';
NODE_NAME     R2663 2
 '@S9S_MB_2U_LIB.S9S_MB_2U(SCH_1):PAGE314_I114@PURE_QUANTA.Q_RES(CHIPS)':
 'B': CDS_PINID='B';
NODE_NAME     U249 E6
 '@S9S_MB_2U_LIB.S9S_MB_2U(SCH_1):PAGE314_I188@PURE_QUANTA.LCMXO3LF9400C5BG484C(CHIPS)':
 'PT9C': CDS_PINID='PT9C';
NET_NAME
'FM_SWB_PWRGD_N'
 '@S9S_MB_2U_LIB.S9S_MB_2U(SCH_1):FM_SWB_PWRGD_N':
 C_SIGNAL='@s9s_mb_2u_lib.s9s_mb_2u(sch_1):fm_swb_pwrgd_n';
NODE_NAME     R2841 2
 '@S9S_MB_2U_LIB.S9S_MB_2U(SCH_1):PAGE145_I24@PURE_QUANTA.Q_RES(CHIPS)':
 'B': CDS_PINID='B';
NODE_NAME     Q71 5
 '@S9S_MB_2U_LIB.S9S_MB_2U(SCH_1):PAGE145_I100@PURE_QUANTA.MOSFET_NCH_DUAL(CHIPS)':
 'G2': CDS_PINID='G2';
NODE_NAME     Q71 6
 '@S9S_MB_2U_LIB.S9S_MB_2U(SCH_1):PAGE145_I118@PURE_QUANTA.MOSFET_NCH_DUAL(CHIPS)':
 'D1': CDS_PINID='D1';
NET_NAME
'FM_SWB_PWR_EN'
 '@S9S_MB_2U_LIB.S9S_MB_2U(SCH_1):FM_SWB_PWR_EN':
 C_SIGNAL='@s9s_mb_2u_lib.s9s_mb_2u(sch_1):fm_swb_pwr_en';
NODE_NAME     R2661 1
 '@S9S_MB_2U_LIB.S9S_MB_2U(SCH_1):PAGE314_I135@PURE_QUANTA.Q_RES(CHIPS)':
 'A': CDS_PINID='A';
NODE_NAME     U249 B1
 '@S9S_MB_2U_LIB.S9S_MB_2U(SCH_1):PAGE314_I188@PURE_QUANTA.LCMXO3LF9400C5BG484C(CHIPS)':
 'PT9A||L_GPLLT': CDS_PINID='\pt9a||l_gpllt\';
NET_NAME
'FM_SWB_PWR_EN_R'
 '@S9S_MB_2U_LIB.S9S_MB_2U(SCH_1):FM_SWB_PWR_EN_R':
 C_SIGNAL='@s9s_mb_2u_lib.s9s_mb_2u(sch_1):fm_swb_pwr_en_r';
NODE_NAME     U256 3
 '@S9S_MB_2U_LIB.S9S_MB_2U(SCH_1):PAGE160_I173@PURE_QUANTA.74LVC2G17GW(CHIPS)':
 'A1': CDS_PINID='A1';
NODE_NAME     R2910 2
 '@S9S_MB_2U_LIB.S9S_MB_2U(SCH_1):PAGE160_I187@PURE_QUANTA.Q_RES(CHIPS)':
 'B': CDS_PINID='B';
NODE_NAME     R2918 1
 '@S9S_MB_2U_LIB.S9S_MB_2U(SCH_1):PAGE160_I188@PURE_QUANTA.Q_RES(CHIPS)':
 'A': CDS_PINID='A';
NODE_NAME     R2661 2
 '@S9S_MB_2U_LIB.S9S_MB_2U(SCH_1):PAGE314_I135@PURE_QUANTA.Q_RES(CHIPS)':
 'B': CDS_PINID='B';
NET_NAME
'FM_SWB_PWR_EN_R1_BUF'
 '@S9S_MB_2U_LIB.S9S_MB_2U(SCH_1):FM_SWB_PWR_EN_R1_BUF':
 C_SIGNAL='@s9s_mb_2u_lib.s9s_mb_2u(sch_1):fm_swb_pwr_en_r1_buf';
NODE_NAME     U256 4
 '@S9S_MB_2U_LIB.S9S_MB_2U(SCH_1):PAGE160_I173@PURE_QUANTA.74LVC2G17GW(CHIPS)':
 'B1': CDS_PINID='B1';
NODE_NAME     R2914 2
 '@S9S_MB_2U_LIB.S9S_MB_2U(SCH_1):PAGE160_I192@PURE_QUANTA.Q_RES(CHIPS)':
 'B': CDS_PINID='B';
NODE_NAME     R2932 1
 '@S9S_MB_2U_LIB.S9S_MB_2U(SCH_1):PAGE160_I195@PURE_QUANTA.Q_RES(CHIPS)':
 'A': CDS_PINID='A';
NODE_NAME     R3515 1
 '@S9S_MB_2U_LIB.S9S_MB_2U(SCH_1):PAGE160_I198@PURE_QUANTA.Q_RES(CHIPS)':
 'A': CDS_PINID='A';
NET_NAME
'FM_SWB_PWR_EN_R_BUF'
 '@S9S_MB_2U_LIB.S9S_MB_2U(SCH_1):FM_SWB_PWR_EN_R_BUF':
 C_SIGNAL='@s9s_mb_2u_lib.s9s_mb_2u(sch_1):fm_swb_pwr_en_r_buf';
NODE_NAME     J105 N2
 '@S9S_MB_2U_LIB.S9S_MB_2U(SCH_1):PAGE142_I65@PURE_QUANTA.CONN112_10137002101LF(CHIPS)':
 'N2': CDS_PINID='N2';
NODE_NAME     R3515 2
 '@S9S_MB_2U_LIB.S9S_MB_2U(SCH_1):PAGE160_I198@PURE_QUANTA.Q_RES(CHIPS)':
 'B': CDS_PINID='B';
NET_NAME
'FM_SYS_THROTTLE_R_N'
 '@S9S_MB_2U_LIB.S9S_MB_2U(SCH_1):FM_SYS_THROTTLE_R_N':
 C_SIGNAL='@s9s_mb_2u_lib.s9s_mb_2u(sch_1):fm_sys_throttle_r_n';
NODE_NAME     U104 2
 '@S9S_MB_2U_LIB.S9S_MB_2U(SCH_1):PAGE152_I63@PURE_QUANTA.74LVC1G07GV(CHIPS)':
 'A': CDS_PINID='A';
NODE_NAME     U218 2
 '@S9S_MB_2U_LIB.S9S_MB_2U(SCH_1):PAGE156_I31@PURE_QUANTA.74LVC1G07GV(CHIPS)':
 'A': CDS_PINID='A';
NODE_NAME     U249 AA14
 '@S9S_MB_2U_LIB.S9S_MB_2U(SCH_1):PAGE312_I1@PURE_QUANTA.LCMXO3LF9400C5BG484C(CHIPS)':
 'PB33B': CDS_PINID='PB33B';
NODE_NAME     R1434 1
 '@S9S_MB_2U_LIB.S9S_MB_2U(SCH_1):PAGE209_I44@PURE_QUANTA.Q_RES(CHIPS)':
 'A': CDS_PINID='A';
NET_NAME
'FM_THERMAL_ALERT_N'
 '@S9S_MB_2U_LIB.S9S_MB_2U(SCH_1):FM_THERMAL_ALERT_N':
 C_SIGNAL='@s9s_mb_2u_lib.s9s_mb_2u(sch_1):fm_thermal_alert_n';
NODE_NAME     R4215 1
 '@S9S_MB_2U_LIB.S9S_MB_2U(SCH_1):PAGE161_I79@PURE_QUANTA.Q_RES(CHIPS)':
 'A': CDS_PINID='A';
NODE_NAME     R4214 1
 '@S9S_MB_2U_LIB.S9S_MB_2U(SCH_1):PAGE161_I108@PURE_QUANTA.Q_RES(CHIPS)':
 'A': CDS_PINID='A';
NODE_NAME     R4213 1
 '@S9S_MB_2U_LIB.S9S_MB_2U(SCH_1):PAGE161_I115@PURE_QUANTA.Q_RES(CHIPS)':
 'A': CDS_PINID='A';
NODE_NAME     R4212 1
 '@S9S_MB_2U_LIB.S9S_MB_2U(SCH_1):PAGE161_I135@PURE_QUANTA.Q_RES(CHIPS)':
 'A': CDS_PINID='A';
NODE_NAME     R4259 1
 '@S9S_MB_2U_LIB.S9S_MB_2U(SCH_1):PAGE313_I147@PURE_QUANTA.Q_RES(CHIPS)':
 'A': CDS_PINID='A';
NODE_NAME     R4211 2
 '@S9S_MB_2U_LIB.S9S_MB_2U(SCH_1):PAGE161_I168@PURE_QUANTA.Q_RES(CHIPS)':
 'B': CDS_PINID='B';
NODE_NAME     R4209 2
 '@S9S_MB_2U_LIB.S9S_MB_2U(SCH_1):PAGE161_I169@PURE_QUANTA.Q_RES(CHIPS)':
 'B': CDS_PINID='B';
NODE_NAME     R4210 2
 '@S9S_MB_2U_LIB.S9S_MB_2U(SCH_1):PAGE161_I170@PURE_QUANTA.Q_RES(CHIPS)':
 'B': CDS_PINID='B';
NODE_NAME     R4208 2
 '@S9S_MB_2U_LIB.S9S_MB_2U(SCH_1):PAGE161_I171@PURE_QUANTA.Q_RES(CHIPS)':
 'B': CDS_PINID='B';
NET_NAME
'FM_THERMAL_ALERT_R_N'
 '@S9S_MB_2U_LIB.S9S_MB_2U(SCH_1):FM_THERMAL_ALERT_R_N':
 C_SIGNAL='@s9s_mb_2u_lib.s9s_mb_2u(sch_1):fm_thermal_alert_r_n';
NODE_NAME     U249 L21
 '@S9S_MB_2U_LIB.S9S_MB_2U(SCH_1):PAGE313_I1@PURE_QUANTA.LCMXO3LF9400C5BG484C(CHIPS)':
 'PR16B': CDS_PINID='PR16B';
NODE_NAME     R4259 2
 '@S9S_MB_2U_LIB.S9S_MB_2U(SCH_1):PAGE313_I147@PURE_QUANTA.Q_RES(CHIPS)':
 'B': CDS_PINID='B';
NET_NAME
'FM_THERMTRIP_DLY_LVC1_N'
 '@S9S_MB_2U_LIB.S9S_MB_2U(SCH_1):FM_THERMTRIP_DLY_LVC1_N':
 C_SIGNAL='@s9s_mb_2u_lib.s9s_mb_2u(sch_1):fm_thermtrip_dly_lvc1_n';
NODE_NAME     R1249 1
 '@S9S_MB_2U_LIB.S9S_MB_2U(SCH_1):PAGE191_I2@PURE_QUANTA.Q_RES(CHIPS)':
 'A': CDS_PINID='A';
NODE_NAME     R1318 2
 '@S9S_MB_2U_LIB.S9S_MB_2U(SCH_1):PAGE212_I130@PURE_QUANTA.Q_RES(CHIPS)':
 'B': CDS_PINID='B';
NET_NAME
'FM_THERMTRIP_DLY_LVC1_R_N'
 '@S9S_MB_2U_LIB.S9S_MB_2U(SCH_1):FM_THERMTRIP_DLY_LVC1_R_N':
 C_SIGNAL='@s9s_mb_2u_lib.s9s_mb_2u(sch_1):fm_thermtrip_dly_lvc1_r_n';
NODE_NAME     U249 W3
 '@S9S_MB_2U_LIB.S9S_MB_2U(SCH_1):PAGE311_I33@PURE_QUANTA.LCMXO3LF9400C5BG484C(CHIPS)':
 'PL29C': CDS_PINID='PL29C';
NODE_NAME     R1318 1
 '@S9S_MB_2U_LIB.S9S_MB_2U(SCH_1):PAGE212_I130@PURE_QUANTA.Q_RES(CHIPS)':
 'A': CDS_PINID='A';
NET_NAME
'FM_THROTTLE_N'
 '@S9S_MB_2U_LIB.S9S_MB_2U(SCH_1):FM_THROTTLE_N':
 C_SIGNAL='@s9s_mb_2u_lib.s9s_mb_2u(sch_1):fm_throttle_n';
NODE_NAME     U4 AW2
 '@S9S_MB_2U_LIB.S9S_MB_2U(SCH_1):PAGE175_I93@PURE_QUANTA.EMMITSBURG_REV0P9(CHIPS)':
 'GPPC_C_14_ME_SML3ALERT_N': CDS_PINID='GPPC_C_14_ME_SML3ALERT_N';
NODE_NAME     R1450 2
 '@S9S_MB_2U_LIB.S9S_MB_2U(SCH_1):PAGE192_I42@PURE_QUANTA.Q_RES(CHIPS)':
 'B': CDS_PINID='B';
NODE_NAME     R1307 1
 '@S9S_MB_2U_LIB.S9S_MB_2U(SCH_1):PAGE193_I3@PURE_QUANTA.Q_RES(CHIPS)':
 'A': CDS_PINID='A';
NET_NAME
'FM_THROTTLE_R_N'
 '@S9S_MB_2U_LIB.S9S_MB_2U(SCH_1):FM_THROTTLE_R_N':
 C_SIGNAL='@s9s_mb_2u_lib.s9s_mb_2u(sch_1):fm_throttle_r_n';
NODE_NAME     R1307 2
 '@S9S_MB_2U_LIB.S9S_MB_2U(SCH_1):PAGE193_I3@PURE_QUANTA.Q_RES(CHIPS)':
 'B': CDS_PINID='B';
NODE_NAME     U249 Y15
 '@S9S_MB_2U_LIB.S9S_MB_2U(SCH_1):PAGE312_I1@PURE_QUANTA.LCMXO3LF9400C5BG484C(CHIPS)':
 'PB35C': CDS_PINID='PB35C';
NET_NAME
'FM_TPM_PRSNT_N'
 '@S9S_MB_2U_LIB.S9S_MB_2U(SCH_1):FM_TPM_PRSNT_N':
 C_SIGNAL='@s9s_mb_2u_lib.s9s_mb_2u(sch_1):fm_tpm_prsnt_n';
NODE_NAME     U4 BB31
 '@S9S_MB_2U_LIB.S9S_MB_2U(SCH_1):PAGE176_I22@PURE_QUANTA.EMMITSBURG_REV0P9(CHIPS)':
 'GPP_E_19_ERR2_N': CDS_PINID='GPP_E_19_ERR2_N';
NODE_NAME     R1547 2
 '@S9S_MB_2U_LIB.S9S_MB_2U(SCH_1):PAGE314_I139@PURE_QUANTA.Q_RES(CHIPS)':
 'B': CDS_PINID='B';
NET_NAME
'FM_TPM_PRSNT_R_N'
 '@S9S_MB_2U_LIB.S9S_MB_2U(SCH_1):FM_TPM_PRSNT_R_N':
 C_SIGNAL='@s9s_mb_2u_lib.s9s_mb_2u(sch_1):fm_tpm_prsnt_r_n';
NODE_NAME     R1547 1
 '@S9S_MB_2U_LIB.S9S_MB_2U(SCH_1):PAGE314_I139@PURE_QUANTA.Q_RES(CHIPS)':
 'A': CDS_PINID='A';
NODE_NAME     U249 A5
 '@S9S_MB_2U_LIB.S9S_MB_2U(SCH_1):PAGE314_I188@PURE_QUANTA.LCMXO3LF9400C5BG484C(CHIPS)':
 'PT12B': CDS_PINID='PT12B';
NET_NAME
'FM_UARTSW_LSB_N'
 '@S9S_MB_2U_LIB.S9S_MB_2U(SCH_1):FM_UARTSW_LSB_N':
 C_SIGNAL='@s9s_mb_2u_lib.s9s_mb_2u(sch_1):fm_uartsw_lsb_n';
NODE_NAME     U249 L19
 '@S9S_MB_2U_LIB.S9S_MB_2U(SCH_1):PAGE313_I1@PURE_QUANTA.LCMXO3LF9400C5BG484C(CHIPS)':
 'PR14C': CDS_PINID='PR14C';
NODE_NAME     R3777 1
 '@S9S_MB_2U_LIB.S9S_MB_2U(SCH_1):PAGE227_I19@PURE_QUANTA.Q_RES(CHIPS)':
 'A': CDS_PINID='A';
NET_NAME
'FM_UARTSW_LSB_R'
 '@S9S_MB_2U_LIB.S9S_MB_2U(SCH_1):FM_UARTSW_LSB_R':
 C_SIGNAL='@s9s_mb_2u_lib.s9s_mb_2u(sch_1):fm_uartsw_lsb_r';
NODE_NAME     R3777 2
 '@S9S_MB_2U_LIB.S9S_MB_2U(SCH_1):PAGE227_I19@PURE_QUANTA.Q_RES(CHIPS)':
 'B': CDS_PINID='B';
NODE_NAME     J41 A55
 '@S9S_MB_2U_LIB.S9S_MB_2U(SCH_1):PAGE227_I173@PURE_QUANTA.SCONN168_ME1016810202011(CHIPS)':
 'GND_A55': CDS_PINID='GND_A55';
NET_NAME
'FM_UARTSW_MSB_N'
 '@S9S_MB_2U_LIB.S9S_MB_2U(SCH_1):FM_UARTSW_MSB_N':
 C_SIGNAL='@s9s_mb_2u_lib.s9s_mb_2u(sch_1):fm_uartsw_msb_n';
NODE_NAME     U249 L20
 '@S9S_MB_2U_LIB.S9S_MB_2U(SCH_1):PAGE313_I1@PURE_QUANTA.LCMXO3LF9400C5BG484C(CHIPS)':
 'PR14D': CDS_PINID='PR14D';
NODE_NAME     R3776 1
 '@S9S_MB_2U_LIB.S9S_MB_2U(SCH_1):PAGE227_I21@PURE_QUANTA.Q_RES(CHIPS)':
 'A': CDS_PINID='A';
NET_NAME
'FM_UARTSW_MSB_R'
 '@S9S_MB_2U_LIB.S9S_MB_2U(SCH_1):FM_UARTSW_MSB_R':
 C_SIGNAL='@s9s_mb_2u_lib.s9s_mb_2u(sch_1):fm_uartsw_msb_r';
NODE_NAME     R3776 2
 '@S9S_MB_2U_LIB.S9S_MB_2U(SCH_1):PAGE227_I21@PURE_QUANTA.Q_RES(CHIPS)':
 'B': CDS_PINID='B';
NODE_NAME     J41 A52
 '@S9S_MB_2U_LIB.S9S_MB_2U(SCH_1):PAGE227_I173@PURE_QUANTA.SCONN168_ME1016810202011(CHIPS)':
 'GND_A52': CDS_PINID='GND_A52';
NET_NAME
'FM_UART_EN'
 '@S9S_MB_2U_LIB.S9S_MB_2U(SCH_1):FM_UART_EN':
 C_SIGNAL='@s9s_mb_2u_lib.s9s_mb_2u(sch_1):fm_uart_en';
NODE_NAME     U204 1
 '@S9S_MB_2U_LIB.S9S_MB_2U(SCH_1):PAGE140_I195@PURE_QUANTA.74LVC1G126SE7(CHIPS)':
 'OE': CDS_PINID='OE';
NODE_NAME     R3063 2
 '@S9S_MB_2U_LIB.S9S_MB_2U(SCH_1):PAGE140_I208@PURE_QUANTA.Q_RES(CHIPS)':
 'B': CDS_PINID='B';
NET_NAME
'FM_USB3_1_EN_N'
 '@S9S_MB_2U_LIB.S9S_MB_2U(SCH_1):FM_USB3_1_EN_N':
 C_SIGNAL='@s9s_mb_2u_lib.s9s_mb_2u(sch_1):fm_usb3_1_en_n';
NODE_NAME     R4292 1
 '@S9S_MB_2U_LIB.S9S_MB_2U(SCH_1):PAGE162_I63@PURE_QUANTA.Q_RES(CHIPS)':
 'A': CDS_PINID='A';
NODE_NAME     U309 4
 '@S9S_MB_2U_LIB.S9S_MB_2U(SCH_1):PAGE162_I43@PURE_QUANTA.PI3EQX1002EZREX(CHIPS)':
 'EN': CDS_PINID='EN';
NODE_NAME     R4291 2
 '@S9S_MB_2U_LIB.S9S_MB_2U(SCH_1):PAGE162_I65@PURE_QUANTA.Q_RES(CHIPS)':
 'B': CDS_PINID='B';
NET_NAME
'FM_USB3_1_EQA'
 '@S9S_MB_2U_LIB.S9S_MB_2U(SCH_1):FM_USB3_1_EQA':
 C_SIGNAL='@s9s_mb_2u_lib.s9s_mb_2u(sch_1):fm_usb3_1_eqa';
NODE_NAME     R4276 1
 '@S9S_MB_2U_LIB.S9S_MB_2U(SCH_1):PAGE162_I2@PURE_QUANTA.Q_RES(CHIPS)':
 'A': CDS_PINID='A';
NODE_NAME     R4275 2
 '@S9S_MB_2U_LIB.S9S_MB_2U(SCH_1):PAGE162_I3@PURE_QUANTA.Q_RES(CHIPS)':
 'B': CDS_PINID='B';
NODE_NAME     U309 1
 '@S9S_MB_2U_LIB.S9S_MB_2U(SCH_1):PAGE162_I43@PURE_QUANTA.PI3EQX1002EZREX(CHIPS)':
 'EQA': CDS_PINID='EQA';
NET_NAME
'FM_USB3_1_EQB'
 '@S9S_MB_2U_LIB.S9S_MB_2U(SCH_1):FM_USB3_1_EQB':
 C_SIGNAL='@s9s_mb_2u_lib.s9s_mb_2u(sch_1):fm_usb3_1_eqb';
NODE_NAME     R4281 2
 '@S9S_MB_2U_LIB.S9S_MB_2U(SCH_1):PAGE162_I7@PURE_QUANTA.Q_RES(CHIPS)':
 'B': CDS_PINID='B';
NODE_NAME     R4282 1
 '@S9S_MB_2U_LIB.S9S_MB_2U(SCH_1):PAGE162_I6@PURE_QUANTA.Q_RES(CHIPS)':
 'A': CDS_PINID='A';
NODE_NAME     U309 16
 '@S9S_MB_2U_LIB.S9S_MB_2U(SCH_1):PAGE162_I43@PURE_QUANTA.PI3EQX1002EZREX(CHIPS)':
 'EQB': CDS_PINID='EQB';
NET_NAME
'FM_USB3_1_FGA'
 '@S9S_MB_2U_LIB.S9S_MB_2U(SCH_1):FM_USB3_1_FGA':
 C_SIGNAL='@s9s_mb_2u_lib.s9s_mb_2u(sch_1):fm_usb3_1_fga';
NODE_NAME     R4280 1
 '@S9S_MB_2U_LIB.S9S_MB_2U(SCH_1):PAGE162_I17@PURE_QUANTA.Q_RES(CHIPS)':
 'A': CDS_PINID='A';
NODE_NAME     R4279 2
 '@S9S_MB_2U_LIB.S9S_MB_2U(SCH_1):PAGE162_I18@PURE_QUANTA.Q_RES(CHIPS)':
 'B': CDS_PINID='B';
NODE_NAME     U309 2
 '@S9S_MB_2U_LIB.S9S_MB_2U(SCH_1):PAGE162_I43@PURE_QUANTA.PI3EQX1002EZREX(CHIPS)':
 'FGA': CDS_PINID='FGA';
NET_NAME
'FM_USB3_1_FGB'
 '@S9S_MB_2U_LIB.S9S_MB_2U(SCH_1):FM_USB3_1_FGB':
 C_SIGNAL='@s9s_mb_2u_lib.s9s_mb_2u(sch_1):fm_usb3_1_fgb';
NODE_NAME     R4274 1
 '@S9S_MB_2U_LIB.S9S_MB_2U(SCH_1):PAGE162_I11@PURE_QUANTA.Q_RES(CHIPS)':
 'A': CDS_PINID='A';
NODE_NAME     R4273 2
 '@S9S_MB_2U_LIB.S9S_MB_2U(SCH_1):PAGE162_I12@PURE_QUANTA.Q_RES(CHIPS)':
 'B': CDS_PINID='B';
NODE_NAME     U309 15
 '@S9S_MB_2U_LIB.S9S_MB_2U(SCH_1):PAGE162_I43@PURE_QUANTA.PI3EQX1002EZREX(CHIPS)':
 'FGB': CDS_PINID='FGB';
NET_NAME
'FM_USB3_1_RXDET_EN'
 '@S9S_MB_2U_LIB.S9S_MB_2U(SCH_1):FM_USB3_1_RXDET_EN':
 C_SIGNAL='@s9s_mb_2u_lib.s9s_mb_2u(sch_1):fm_usb3_1_rxdet_en';
NODE_NAME     R4290 1
 '@S9S_MB_2U_LIB.S9S_MB_2U(SCH_1):PAGE162_I68@PURE_QUANTA.Q_RES(CHIPS)':
 'A': CDS_PINID='A';
NODE_NAME     U309 13
 '@S9S_MB_2U_LIB.S9S_MB_2U(SCH_1):PAGE162_I43@PURE_QUANTA.PI3EQX1002EZREX(CHIPS)':
 'RXDET_EN': CDS_PINID='RXDET_EN';
NODE_NAME     R4289 2
 '@S9S_MB_2U_LIB.S9S_MB_2U(SCH_1):PAGE162_I69@PURE_QUANTA.Q_RES(CHIPS)':
 'B': CDS_PINID='B';
NET_NAME
'FM_USB3_1_SWA'
 '@S9S_MB_2U_LIB.S9S_MB_2U(SCH_1):FM_USB3_1_SWA':
 C_SIGNAL='@s9s_mb_2u_lib.s9s_mb_2u(sch_1):fm_usb3_1_swa';
NODE_NAME     U309 3
 '@S9S_MB_2U_LIB.S9S_MB_2U(SCH_1):PAGE162_I43@PURE_QUANTA.PI3EQX1002EZREX(CHIPS)':
 'SWA': CDS_PINID='SWA';
NODE_NAME     R4288 1
 '@S9S_MB_2U_LIB.S9S_MB_2U(SCH_1):PAGE162_I48@PURE_QUANTA.Q_RES(CHIPS)':
 'A': CDS_PINID='A';
NODE_NAME     R4287 2
 '@S9S_MB_2U_LIB.S9S_MB_2U(SCH_1):PAGE162_I49@PURE_QUANTA.Q_RES(CHIPS)':
 'B': CDS_PINID='B';
NET_NAME
'FM_USB3_1_SWB'
 '@S9S_MB_2U_LIB.S9S_MB_2U(SCH_1):FM_USB3_1_SWB':
 C_SIGNAL='@s9s_mb_2u_lib.s9s_mb_2u(sch_1):fm_usb3_1_swb';
NODE_NAME     R4284 2
 '@S9S_MB_2U_LIB.S9S_MB_2U(SCH_1):PAGE162_I41@PURE_QUANTA.Q_RES(CHIPS)':
 'B': CDS_PINID='B';
NODE_NAME     R4285 1
 '@S9S_MB_2U_LIB.S9S_MB_2U(SCH_1):PAGE162_I40@PURE_QUANTA.Q_RES(CHIPS)':
 'A': CDS_PINID='A';
NODE_NAME     U309 14
 '@S9S_MB_2U_LIB.S9S_MB_2U(SCH_1):PAGE162_I43@PURE_QUANTA.PI3EQX1002EZREX(CHIPS)':
 'SWB': CDS_PINID='SWB';
NET_NAME
'FM_UV_ADR_TRIGGER_N'
 '@S9S_MB_2U_LIB.S9S_MB_2U(SCH_1):FM_UV_ADR_TRIGGER_N':
 C_SIGNAL='@s9s_mb_2u_lib.s9s_mb_2u(sch_1):fm_uv_adr_trigger_n';
NODE_NAME     R3046 1
 '@S9S_MB_2U_LIB.S9S_MB_2U(SCH_1):PAGE312_I165@PURE_QUANTA.Q_RES(CHIPS)':
 'A': CDS_PINID='A';
NODE_NAME     R2233 2
 '@S9S_MB_2U_LIB.S9S_MB_2U(SCH_1):PAGE326_I41@PURE_QUANTA.Q_RES(CHIPS)':
 'B': CDS_PINID='B';
NODE_NAME     R4784 2
 '@S9S_MB_2U_LIB.S9S_MB_2U(SCH_1):PAGE329_I6@PURE_QUANTA.Q_RES(CHIPS)':
 'B': CDS_PINID='B';
NODE_NAME     R4782 2
 '@S9S_MB_2U_LIB.S9S_MB_2U(SCH_1):PAGE329_I7@PURE_QUANTA.Q_RES(CHIPS)':
 'B': CDS_PINID='B';
NODE_NAME     U206 1
 '@S9S_MB_2U_LIB.S9S_MB_2U(SCH_1):PAGE326_I102@PURE_QUANTA.LT6700CS61TRPBF(CHIPS)':
 'OUTA': CDS_PINID='OUTA';
NET_NAME
'FM_UV_ADR_TRIGGER_N_R2'
 '@S9S_MB_2U_LIB.S9S_MB_2U(SCH_1):FM_UV_ADR_TRIGGER_N_R2':
 C_SIGNAL='@s9s_mb_2u_lib.s9s_mb_2u(sch_1):fm_uv_adr_trigger_n_r2';
NODE_NAME     R4782 1
 '@S9S_MB_2U_LIB.S9S_MB_2U(SCH_1):PAGE329_I7@PURE_QUANTA.Q_RES(CHIPS)':
 'A': CDS_PINID='A';
NODE_NAME     R4778 2
 '@S9S_MB_2U_LIB.S9S_MB_2U(SCH_1):PAGE329_I9@PURE_QUANTA.Q_RES(CHIPS)':
 'B': CDS_PINID='B';
NODE_NAME     U339 4
 '@S9S_MB_2U_LIB.S9S_MB_2U(SCH_1):PAGE329_I12@PURE_QUANTA.AP331AWG7(CHIPS)':
 'OUTPUT': CDS_PINID='OUTPUT';
NET_NAME
'FM_UV_ADR_TRIGGER_R_N'
 '@S9S_MB_2U_LIB.S9S_MB_2U(SCH_1):FM_UV_ADR_TRIGGER_R_N':
 C_SIGNAL='@s9s_mb_2u_lib.s9s_mb_2u(sch_1):fm_uv_adr_trigger_r_n';
NODE_NAME     U249 AB2
 '@S9S_MB_2U_LIB.S9S_MB_2U(SCH_1):PAGE312_I1@PURE_QUANTA.LCMXO3LF9400C5BG484C(CHIPS)':
 'PB5B': CDS_PINID='PB5B';
NODE_NAME     R3046 2
 '@S9S_MB_2U_LIB.S9S_MB_2U(SCH_1):PAGE312_I165@PURE_QUANTA.Q_RES(CHIPS)':
 'B': CDS_PINID='B';
NET_NAME
'FM_XTAL_INPUT_FREQUENCY_0_MGPIO'
 '@S9S_MB_2U_LIB.S9S_MB_2U(SCH_1):FM_XTAL_INPUT_FREQUENCY_0_MGPIO_TEST4':
 C_SIGNAL='@s9s_mb_2u_lib.s9s_mb_2u(sch_1):fm_xtal_input_frequency_0_mgpio_test4~
';
NODE_NAME     U4 BB18
 '@S9S_MB_2U_LIB.S9S_MB_2U(SCH_1):PAGE177_I27@PURE_QUANTA.EMMITSBURG_REV0P9(CHIPS)':
 'GPPC_S_0_TIME_SYNC_0': CDS_PINID='GPPC_S_0_TIME_SYNC_0';
NODE_NAME     R1311 1
 '@S9S_MB_2U_LIB.S9S_MB_2U(SCH_1):PAGE188_I31@PURE_QUANTA.Q_RES(CHIPS)':
 'A': CDS_PINID='A';
NET_NAME
'FM_XTAL_INPUT_FREQUENCY_1_MGPIO'
 '@S9S_MB_2U_LIB.S9S_MB_2U(SCH_1):FM_XTAL_INPUT_FREQUENCY_1_MGPIO_TEST5':
 C_SIGNAL='@s9s_mb_2u_lib.s9s_mb_2u(sch_1):fm_xtal_input_frequency_1_mgpio_test5~
';
NODE_NAME     U4 AR16
 '@S9S_MB_2U_LIB.S9S_MB_2U(SCH_1):PAGE177_I27@PURE_QUANTA.EMMITSBURG_REV0P9(CHIPS)':
 'GPPC_S_2_CPU_GP_0': CDS_PINID='GPPC_S_2_CPU_GP_0';
NODE_NAME     R1457 1
 '@S9S_MB_2U_LIB.S9S_MB_2U(SCH_1):PAGE188_I36@PURE_QUANTA.Q_RES(CHIPS)':
 'A': CDS_PINID='A';
NET_NAME
'GND'
 '@S9S_MB_2U_LIB.S9S_MB_2U(SCH_1):GND':
 C_SIGNAL='@s9s_mb_2u_lib.s9s_mb_2u(sch_1):gnd',
 PHYS_NET_NAME='GND',
 CDS_GLOBAL_NET='TRUE';
NODE_NAME     U2 EJ80
 '@S9S_MB_2U_LIB.S9S_MB_2U(SCH_1):PAGE35_I102@PURE_QUANTA.SOCKET4677_AZIF0045P001C01CS(CHIPS)':
 'UPI3_RX_DN0': CDS_PINID='UPI3_RX_DN0';
NODE_NAME     U2 EP81
 '@S9S_MB_2U_LIB.S9S_MB_2U(SCH_1):PAGE35_I102@PURE_QUANTA.SOCKET4677_AZIF0045P001C01CS(CHIPS)':
 'UPI3_RX_DN1': CDS_PINID='UPI3_RX_DN1';
NODE_NAME     U2 EL82
 '@S9S_MB_2U_LIB.S9S_MB_2U(SCH_1):PAGE35_I102@PURE_QUANTA.SOCKET4677_AZIF0045P001C01CS(CHIPS)':
 'UPI3_RX_DN2': CDS_PINID='UPI3_RX_DN2';
NODE_NAME     U2 EK81
 '@S9S_MB_2U_LIB.S9S_MB_2U(SCH_1):PAGE35_I102@PURE_QUANTA.SOCKET4677_AZIF0045P001C01CS(CHIPS)':
 'UPI3_RX_DN3': CDS_PINID='UPI3_RX_DN3';
NODE_NAME     U2 EF81
 '@S9S_MB_2U_LIB.S9S_MB_2U(SCH_1):PAGE35_I102@PURE_QUANTA.SOCKET4677_AZIF0045P001C01CS(CHIPS)':
 'UPI3_RX_DN4': CDS_PINID='UPI3_RX_DN4';
NODE_NAME     U2 ED83
 '@S9S_MB_2U_LIB.S9S_MB_2U(SCH_1):PAGE35_I102@PURE_QUANTA.SOCKET4677_AZIF0045P001C01CS(CHIPS)':
 'UPI3_RX_DN5': CDS_PINID='UPI3_RX_DN5';
NODE_NAME     U2 EC80
 '@S9S_MB_2U_LIB.S9S_MB_2U(SCH_1):PAGE35_I102@PURE_QUANTA.SOCKET4677_AZIF0045P001C01CS(CHIPS)':
 'UPI3_RX_DN6': CDS_PINID='UPI3_RX_DN6';
NODE_NAME     U2 EA82
 '@S9S_MB_2U_LIB.S9S_MB_2U(SCH_1):PAGE35_I102@PURE_QUANTA.SOCKET4677_AZIF0045P001C01CS(CHIPS)':
 'UPI3_RX_DN7': CDS_PINID='UPI3_RX_DN7';
NODE_NAME     U2 DY81
 '@S9S_MB_2U_LIB.S9S_MB_2U(SCH_1):PAGE35_I102@PURE_QUANTA.SOCKET4677_AZIF0045P001C01CS(CHIPS)':
 'UPI3_RX_DN8': CDS_PINID='UPI3_RX_DN8';
NODE_NAME     U2 DJ78
 '@S9S_MB_2U_LIB.S9S_MB_2U(SCH_1):PAGE35_I102@PURE_QUANTA.SOCKET4677_AZIF0045P001C01CS(CHIPS)':
 'UPI3_RX_DN9': CDS_PINID='UPI3_RX_DN9';
NODE_NAME     U2 DG78
 '@S9S_MB_2U_LIB.S9S_MB_2U(SCH_1):PAGE35_I102@PURE_QUANTA.SOCKET4677_AZIF0045P001C01CS(CHIPS)':
 'UPI3_RX_DN10': CDS_PINID='UPI3_RX_DN10';
NODE_NAME     U2 DH81
 '@S9S_MB_2U_LIB.S9S_MB_2U(SCH_1):PAGE35_I102@PURE_QUANTA.SOCKET4677_AZIF0045P001C01CS(CHIPS)':
 'UPI3_RX_DN11': CDS_PINID='UPI3_RX_DN11';
NODE_NAME     U2 DF83
 '@S9S_MB_2U_LIB.S9S_MB_2U(SCH_1):PAGE35_I102@PURE_QUANTA.SOCKET4677_AZIF0045P001C01CS(CHIPS)':
 'UPI3_RX_DN12': CDS_PINID='UPI3_RX_DN12';
NODE_NAME     U2 DE80
 '@S9S_MB_2U_LIB.S9S_MB_2U(SCH_1):PAGE35_I102@PURE_QUANTA.SOCKET4677_AZIF0045P001C01CS(CHIPS)':
 'UPI3_RX_DN13': CDS_PINID='UPI3_RX_DN13';
NODE_NAME     U2 DC82
 '@S9S_MB_2U_LIB.S9S_MB_2U(SCH_1):PAGE35_I102@PURE_QUANTA.SOCKET4677_AZIF0045P001C01CS(CHIPS)':
 'UPI3_RX_DN14': CDS_PINID='UPI3_RX_DN14';
NODE_NAME     U2 DB81
 '@S9S_MB_2U_LIB.S9S_MB_2U(SCH_1):PAGE35_I102@PURE_QUANTA.SOCKET4677_AZIF0045P001C01CS(CHIPS)':
 'UPI3_RX_DN15': CDS_PINID='UPI3_RX_DN15';
NODE_NAME     U2 DF77
 '@S9S_MB_2U_LIB.S9S_MB_2U(SCH_1):PAGE35_I102@PURE_QUANTA.SOCKET4677_AZIF0045P001C01CS(CHIPS)':
 'UPI3_RX_DN16': CDS_PINID='UPI3_RX_DN16';
NODE_NAME     U2 CU82
 '@S9S_MB_2U_LIB.S9S_MB_2U(SCH_1):PAGE35_I102@PURE_QUANTA.SOCKET4677_AZIF0045P001C01CS(CHIPS)':
 'UPI3_RX_DN17': CDS_PINID='UPI3_RX_DN17';
NODE_NAME     U2 CR82
 '@S9S_MB_2U_LIB.S9S_MB_2U(SCH_1):PAGE35_I102@PURE_QUANTA.SOCKET4677_AZIF0045P001C01CS(CHIPS)':
 'UPI3_RX_DN18': CDS_PINID='UPI3_RX_DN18';
NODE_NAME     U2 CW80
 '@S9S_MB_2U_LIB.S9S_MB_2U(SCH_1):PAGE35_I102@PURE_QUANTA.SOCKET4677_AZIF0045P001C01CS(CHIPS)':
 'UPI3_RX_DN19': CDS_PINID='UPI3_RX_DN19';
NODE_NAME     U2 CP81
 '@S9S_MB_2U_LIB.S9S_MB_2U(SCH_1):PAGE35_I102@PURE_QUANTA.SOCKET4677_AZIF0045P001C01CS(CHIPS)':
 'UPI3_RX_DN20': CDS_PINID='UPI3_RX_DN20';
NODE_NAME     U2 CN80
 '@S9S_MB_2U_LIB.S9S_MB_2U(SCH_1):PAGE35_I102@PURE_QUANTA.SOCKET4677_AZIF0045P001C01CS(CHIPS)':
 'UPI3_RX_DN21': CDS_PINID='UPI3_RX_DN21';
NODE_NAME     U2 CT79
 '@S9S_MB_2U_LIB.S9S_MB_2U(SCH_1):PAGE35_I102@PURE_QUANTA.SOCKET4677_AZIF0045P001C01CS(CHIPS)':
 'UPI3_RX_DN22': CDS_PINID='UPI3_RX_DN22';
NODE_NAME     U2 DA78
 '@S9S_MB_2U_LIB.S9S_MB_2U(SCH_1):PAGE35_I102@PURE_QUANTA.SOCKET4677_AZIF0045P001C01CS(CHIPS)':
 'UPI3_RX_DN23': CDS_PINID='UPI3_RX_DN23';
NODE_NAME     U2 EL80
 '@S9S_MB_2U_LIB.S9S_MB_2U(SCH_1):PAGE35_I102@PURE_QUANTA.SOCKET4677_AZIF0045P001C01CS(CHIPS)':
 'UPI3_RX_DP0': CDS_PINID='UPI3_RX_DP0';
NODE_NAME     U2 ER82
 '@S9S_MB_2U_LIB.S9S_MB_2U(SCH_1):PAGE35_I102@PURE_QUANTA.SOCKET4677_AZIF0045P001C01CS(CHIPS)':
 'UPI3_RX_DP1': CDS_PINID='UPI3_RX_DP1';
NODE_NAME     U2 EN82
 '@S9S_MB_2U_LIB.S9S_MB_2U(SCH_1):PAGE35_I102@PURE_QUANTA.SOCKET4677_AZIF0045P001C01CS(CHIPS)':
 'UPI3_RX_DP2': CDS_PINID='UPI3_RX_DP2';
NODE_NAME     U2 EJ82
 '@S9S_MB_2U_LIB.S9S_MB_2U(SCH_1):PAGE35_I102@PURE_QUANTA.SOCKET4677_AZIF0045P001C01CS(CHIPS)':
 'UPI3_RX_DP3': CDS_PINID='UPI3_RX_DP3';
NODE_NAME     U2 EE82
 '@S9S_MB_2U_LIB.S9S_MB_2U(SCH_1):PAGE35_I102@PURE_QUANTA.SOCKET4677_AZIF0045P001C01CS(CHIPS)':
 'UPI3_RX_DP4': CDS_PINID='UPI3_RX_DP4';
NODE_NAME     U2 EF83
 '@S9S_MB_2U_LIB.S9S_MB_2U(SCH_1):PAGE35_I102@PURE_QUANTA.SOCKET4677_AZIF0045P001C01CS(CHIPS)':
 'UPI3_RX_DP5': CDS_PINID='UPI3_RX_DP5';
NODE_NAME     U2 ED81
 '@S9S_MB_2U_LIB.S9S_MB_2U(SCH_1):PAGE35_I102@PURE_QUANTA.SOCKET4677_AZIF0045P001C01CS(CHIPS)':
 'UPI3_RX_DP6': CDS_PINID='UPI3_RX_DP6';
NODE_NAME     U2 DY83
 '@S9S_MB_2U_LIB.S9S_MB_2U(SCH_1):PAGE35_I102@PURE_QUANTA.SOCKET4677_AZIF0045P001C01CS(CHIPS)':
 'UPI3_RX_DP7': CDS_PINID='UPI3_RX_DP7';
NODE_NAME     U2 EB81
 '@S9S_MB_2U_LIB.S9S_MB_2U(SCH_1):PAGE35_I102@PURE_QUANTA.SOCKET4677_AZIF0045P001C01CS(CHIPS)':
 'UPI3_RX_DP8': CDS_PINID='UPI3_RX_DP8';
NODE_NAME     U2 DL78
 '@S9S_MB_2U_LIB.S9S_MB_2U(SCH_1):PAGE35_I102@PURE_QUANTA.SOCKET4677_AZIF0045P001C01CS(CHIPS)':
 'UPI3_RX_DP9': CDS_PINID='UPI3_RX_DP9';
NODE_NAME     U2 DH79
 '@S9S_MB_2U_LIB.S9S_MB_2U(SCH_1):PAGE35_I102@PURE_QUANTA.SOCKET4677_AZIF0045P001C01CS(CHIPS)':
 'UPI3_RX_DP10': CDS_PINID='UPI3_RX_DP10';
NODE_NAME     U2 DG82
 '@S9S_MB_2U_LIB.S9S_MB_2U(SCH_1):PAGE35_I102@PURE_QUANTA.SOCKET4677_AZIF0045P001C01CS(CHIPS)':
 'UPI3_RX_DP11': CDS_PINID='UPI3_RX_DP11';
NODE_NAME     U2 DH83
 '@S9S_MB_2U_LIB.S9S_MB_2U(SCH_1):PAGE35_I102@PURE_QUANTA.SOCKET4677_AZIF0045P001C01CS(CHIPS)':
 'UPI3_RX_DP12': CDS_PINID='UPI3_RX_DP12';
NODE_NAME     U2 DF81
 '@S9S_MB_2U_LIB.S9S_MB_2U(SCH_1):PAGE35_I102@PURE_QUANTA.SOCKET4677_AZIF0045P001C01CS(CHIPS)':
 'UPI3_RX_DP13': CDS_PINID='UPI3_RX_DP13';
NODE_NAME     U2 DB83
 '@S9S_MB_2U_LIB.S9S_MB_2U(SCH_1):PAGE35_I102@PURE_QUANTA.SOCKET4677_AZIF0045P001C01CS(CHIPS)':
 'UPI3_RX_DP14': CDS_PINID='UPI3_RX_DP14';
NODE_NAME     U2 DD81
 '@S9S_MB_2U_LIB.S9S_MB_2U(SCH_1):PAGE35_I102@PURE_QUANTA.SOCKET4677_AZIF0045P001C01CS(CHIPS)':
 'UPI3_RX_DP15': CDS_PINID='UPI3_RX_DP15';
NODE_NAME     U2 DE78
 '@S9S_MB_2U_LIB.S9S_MB_2U(SCH_1):PAGE35_I102@PURE_QUANTA.SOCKET4677_AZIF0045P001C01CS(CHIPS)':
 'UPI3_RX_DP16': CDS_PINID='UPI3_RX_DP16';
NODE_NAME     U2 CW82
 '@S9S_MB_2U_LIB.S9S_MB_2U(SCH_1):PAGE35_I102@PURE_QUANTA.SOCKET4677_AZIF0045P001C01CS(CHIPS)':
 'UPI3_RX_DP17': CDS_PINID='UPI3_RX_DP17';
NODE_NAME     U2 CT83
 '@S9S_MB_2U_LIB.S9S_MB_2U(SCH_1):PAGE35_I102@PURE_QUANTA.SOCKET4677_AZIF0045P001C01CS(CHIPS)':
 'UPI3_RX_DP18': CDS_PINID='UPI3_RX_DP18';
NODE_NAME     U2 CV81
 '@S9S_MB_2U_LIB.S9S_MB_2U(SCH_1):PAGE35_I102@PURE_QUANTA.SOCKET4677_AZIF0045P001C01CS(CHIPS)':
 'UPI3_RX_DP19': CDS_PINID='UPI3_RX_DP19';
NODE_NAME     U2 CN82
 '@S9S_MB_2U_LIB.S9S_MB_2U(SCH_1):PAGE35_I102@PURE_QUANTA.SOCKET4677_AZIF0045P001C01CS(CHIPS)':
 'UPI3_RX_DP20': CDS_PINID='UPI3_RX_DP20';
NODE_NAME     U2 CR80
 '@S9S_MB_2U_LIB.S9S_MB_2U(SCH_1):PAGE35_I102@PURE_QUANTA.SOCKET4677_AZIF0045P001C01CS(CHIPS)':
 'UPI3_RX_DP21': CDS_PINID='UPI3_RX_DP21';
NODE_NAME     U2 CU80
 '@S9S_MB_2U_LIB.S9S_MB_2U(SCH_1):PAGE35_I102@PURE_QUANTA.SOCKET4677_AZIF0045P001C01CS(CHIPS)':
 'UPI3_RX_DP22': CDS_PINID='UPI3_RX_DP22';
NODE_NAME     U2 DB79
 '@S9S_MB_2U_LIB.S9S_MB_2U(SCH_1):PAGE35_I102@PURE_QUANTA.SOCKET4677_AZIF0045P001C01CS(CHIPS)':
 'UPI3_RX_DP23': CDS_PINID='UPI3_RX_DP23';
NODE_NAME     C1 2
 '@S9S_MB_2U_LIB.S9S_MB_2U(SCH_1):PAGE37_I15@PURE_QUANTA.Q_CAP(CHIPS)':
 'B': CDS_PINID='B';
NODE_NAME     U2 EH42
 '@S9S_MB_2U_LIB.S9S_MB_2U(SCH_1):PAGE39_I1@PURE_QUANTA.SOCKET4677_AZIF0045P001C01CS(CHIPS)':
 'VSS1312': CDS_PINID='VSS1312';
NODE_NAME     U2 EH55
 '@S9S_MB_2U_LIB.S9S_MB_2U(SCH_1):PAGE39_I1@PURE_QUANTA.SOCKET4677_AZIF0045P001C01CS(CHIPS)':
 'VSS1315': CDS_PINID='VSS1315';
NODE_NAME     U2 EH61
 '@S9S_MB_2U_LIB.S9S_MB_2U(SCH_1):PAGE39_I1@PURE_QUANTA.SOCKET4677_AZIF0045P001C01CS(CHIPS)':
 'VSS1319': CDS_PINID='VSS1319';
NODE_NAME     U2 EH67
 '@S9S_MB_2U_LIB.S9S_MB_2U(SCH_1):PAGE39_I1@PURE_QUANTA.SOCKET4677_AZIF0045P001C01CS(CHIPS)':
 'VSS1320': CDS_PINID='VSS1320';
NODE_NAME     U2 EH79
 '@S9S_MB_2U_LIB.S9S_MB_2U(SCH_1):PAGE39_I1@PURE_QUANTA.SOCKET4677_AZIF0045P001C01CS(CHIPS)':
 'VSS1322': CDS_PINID='VSS1322';
NODE_NAME     U2 EJ11
 '@S9S_MB_2U_LIB.S9S_MB_2U(SCH_1):PAGE39_I1@PURE_QUANTA.SOCKET4677_AZIF0045P001C01CS(CHIPS)':
 'VSS1325': CDS_PINID='VSS1325';
NODE_NAME     U2 EJ17
 '@S9S_MB_2U_LIB.S9S_MB_2U(SCH_1):PAGE39_I1@PURE_QUANTA.SOCKET4677_AZIF0045P001C01CS(CHIPS)':
 'VSS1328': CDS_PINID='VSS1328';
NODE_NAME     U2 EJ25
 '@S9S_MB_2U_LIB.S9S_MB_2U(SCH_1):PAGE39_I1@PURE_QUANTA.SOCKET4677_AZIF0045P001C01CS(CHIPS)':
 'VSS1331': CDS_PINID='VSS1331';
NODE_NAME     U2 EJ35
 '@S9S_MB_2U_LIB.S9S_MB_2U(SCH_1):PAGE39_I1@PURE_QUANTA.SOCKET4677_AZIF0045P001C01CS(CHIPS)':
 'VSS1334': CDS_PINID='VSS1334';
NODE_NAME     U2 EJ54
 '@S9S_MB_2U_LIB.S9S_MB_2U(SCH_1):PAGE39_I1@PURE_QUANTA.SOCKET4677_AZIF0045P001C01CS(CHIPS)':
 'VSS1340': CDS_PINID='VSS1340';
NODE_NAME     U2 EJ62
 '@S9S_MB_2U_LIB.S9S_MB_2U(SCH_1):PAGE39_I1@PURE_QUANTA.SOCKET4677_AZIF0045P001C01CS(CHIPS)':
 'VSS1343': CDS_PINID='VSS1343';
NODE_NAME     U2 EJ68
 '@S9S_MB_2U_LIB.S9S_MB_2U(SCH_1):PAGE39_I1@PURE_QUANTA.SOCKET4677_AZIF0045P001C01CS(CHIPS)':
 'VSS1345': CDS_PINID='VSS1345';
NODE_NAME     U2 EJ72
 '@S9S_MB_2U_LIB.S9S_MB_2U(SCH_1):PAGE39_I1@PURE_QUANTA.SOCKET4677_AZIF0045P001C01CS(CHIPS)':
 'VSS1347': CDS_PINID='VSS1347';
NODE_NAME     U2 EK16
 '@S9S_MB_2U_LIB.S9S_MB_2U(SCH_1):PAGE39_I1@PURE_QUANTA.SOCKET4677_AZIF0045P001C01CS(CHIPS)':
 'VSS1355': CDS_PINID='VSS1355';
NODE_NAME     U2 EK20
 '@S9S_MB_2U_LIB.S9S_MB_2U(SCH_1):PAGE39_I1@PURE_QUANTA.SOCKET4677_AZIF0045P001C01CS(CHIPS)':
 'VSS1357': CDS_PINID='VSS1357';
NODE_NAME     U2 EK26
 '@S9S_MB_2U_LIB.S9S_MB_2U(SCH_1):PAGE39_I1@PURE_QUANTA.SOCKET4677_AZIF0045P001C01CS(CHIPS)':
 'VSS1359': CDS_PINID='VSS1359';
NODE_NAME     U2 EK44
 '@S9S_MB_2U_LIB.S9S_MB_2U(SCH_1):PAGE39_I1@PURE_QUANTA.SOCKET4677_AZIF0045P001C01CS(CHIPS)':
 'VSS1366': CDS_PINID='VSS1366';
NODE_NAME     U2 EK51
 '@S9S_MB_2U_LIB.S9S_MB_2U(SCH_1):PAGE39_I1@PURE_QUANTA.SOCKET4677_AZIF0045P001C01CS(CHIPS)':
 'VSS1368': CDS_PINID='VSS1368';
NODE_NAME     U2 EK53
 '@S9S_MB_2U_LIB.S9S_MB_2U(SCH_1):PAGE39_I1@PURE_QUANTA.SOCKET4677_AZIF0045P001C01CS(CHIPS)':
 'VSS1369': CDS_PINID='VSS1369';
NODE_NAME     U2 EK59
 '@S9S_MB_2U_LIB.S9S_MB_2U(SCH_1):PAGE39_I1@PURE_QUANTA.SOCKET4677_AZIF0045P001C01CS(CHIPS)':
 'VSS1371': CDS_PINID='VSS1371';
NODE_NAME     U2 EK63
 '@S9S_MB_2U_LIB.S9S_MB_2U(SCH_1):PAGE39_I1@PURE_QUANTA.SOCKET4677_AZIF0045P001C01CS(CHIPS)':
 'VSS1372': CDS_PINID='VSS1372';
NODE_NAME     U2 EK71
 '@S9S_MB_2U_LIB.S9S_MB_2U(SCH_1):PAGE39_I1@PURE_QUANTA.SOCKET4677_AZIF0045P001C01CS(CHIPS)':
 'VSS1375': CDS_PINID='VSS1375';
NODE_NAME     U2 EK77
 '@S9S_MB_2U_LIB.S9S_MB_2U(SCH_1):PAGE39_I1@PURE_QUANTA.SOCKET4677_AZIF0045P001C01CS(CHIPS)':
 'VSS1377': CDS_PINID='VSS1377';
NODE_NAME     U2 EK79
 '@S9S_MB_2U_LIB.S9S_MB_2U(SCH_1):PAGE39_I1@PURE_QUANTA.SOCKET4677_AZIF0045P001C01CS(CHIPS)':
 'VSS1378': CDS_PINID='VSS1378';
NODE_NAME     U2 EK83
 '@S9S_MB_2U_LIB.S9S_MB_2U(SCH_1):PAGE39_I1@PURE_QUANTA.SOCKET4677_AZIF0045P001C01CS(CHIPS)':
 'VSS1379': CDS_PINID='VSS1379';
NODE_NAME     U2 EK89
 '@S9S_MB_2U_LIB.S9S_MB_2U(SCH_1):PAGE39_I1@PURE_QUANTA.SOCKET4677_AZIF0045P001C01CS(CHIPS)':
 'VSS1380': CDS_PINID='VSS1380';
NODE_NAME     U2 EL15
 '@S9S_MB_2U_LIB.S9S_MB_2U(SCH_1):PAGE39_I1@PURE_QUANTA.SOCKET4677_AZIF0045P001C01CS(CHIPS)':
 'VSS1381': CDS_PINID='VSS1381';
NODE_NAME     U2 EL52
 '@S9S_MB_2U_LIB.S9S_MB_2U(SCH_1):PAGE39_I1@PURE_QUANTA.SOCKET4677_AZIF0045P001C01CS(CHIPS)':
 'VSS1391': CDS_PINID='VSS1391';
NODE_NAME     U2 EL58
 '@S9S_MB_2U_LIB.S9S_MB_2U(SCH_1):PAGE39_I1@PURE_QUANTA.SOCKET4677_AZIF0045P001C01CS(CHIPS)':
 'VSS1394': CDS_PINID='VSS1394';
NODE_NAME     U2 EL7
 '@S9S_MB_2U_LIB.S9S_MB_2U(SCH_1):PAGE39_I1@PURE_QUANTA.SOCKET4677_AZIF0045P001C01CS(CHIPS)':
 'VSS1396': CDS_PINID='VSS1396';
NODE_NAME     U2 EL70
 '@S9S_MB_2U_LIB.S9S_MB_2U(SCH_1):PAGE39_I1@PURE_QUANTA.SOCKET4677_AZIF0045P001C01CS(CHIPS)':
 'VSS1397': CDS_PINID='VSS1397';
NODE_NAME     U2 EL72
 '@S9S_MB_2U_LIB.S9S_MB_2U(SCH_1):PAGE39_I1@PURE_QUANTA.SOCKET4677_AZIF0045P001C01CS(CHIPS)':
 'VSS1398': CDS_PINID='VSS1398';
NODE_NAME     U2 EL86
 '@S9S_MB_2U_LIB.S9S_MB_2U(SCH_1):PAGE39_I1@PURE_QUANTA.SOCKET4677_AZIF0045P001C01CS(CHIPS)':
 'VSS1400': CDS_PINID='VSS1400';
NODE_NAME     U2 EL9
 '@S9S_MB_2U_LIB.S9S_MB_2U(SCH_1):PAGE39_I1@PURE_QUANTA.SOCKET4677_AZIF0045P001C01CS(CHIPS)':
 'VSS1401': CDS_PINID='VSS1401';
NODE_NAME     U2 EM49
 '@S9S_MB_2U_LIB.S9S_MB_2U(SCH_1):PAGE39_I1@PURE_QUANTA.SOCKET4677_AZIF0045P001C01CS(CHIPS)':
 'VSS1405': CDS_PINID='VSS1405';
NODE_NAME     U2 EM79
 '@S9S_MB_2U_LIB.S9S_MB_2U(SCH_1):PAGE39_I1@PURE_QUANTA.SOCKET4677_AZIF0045P001C01CS(CHIPS)':
 'VSS1409': CDS_PINID='VSS1409';
NODE_NAME     U2 EH36
 '@S9S_MB_2U_LIB.S9S_MB_2U(SCH_1):PAGE39_I1@PURE_QUANTA.SOCKET4677_AZIF0045P001C01CS(CHIPS)':
 'VSS1419': CDS_PINID='VSS1419';
NODE_NAME     U2 EH49
 '@S9S_MB_2U_LIB.S9S_MB_2U(SCH_1):PAGE39_I1@PURE_QUANTA.SOCKET4677_AZIF0045P001C01CS(CHIPS)':
 'VSS1421': CDS_PINID='VSS1421';
NODE_NAME     U2 EH73
 '@S9S_MB_2U_LIB.S9S_MB_2U(SCH_1):PAGE39_I1@PURE_QUANTA.SOCKET4677_AZIF0045P001C01CS(CHIPS)':
 'VSS1422': CDS_PINID='VSS1422';
NODE_NAME     U2 EH81
 '@S9S_MB_2U_LIB.S9S_MB_2U(SCH_1):PAGE39_I1@PURE_QUANTA.SOCKET4677_AZIF0045P001C01CS(CHIPS)':
 'VSS1423': CDS_PINID='VSS1423';
NODE_NAME     U2 EH83
 '@S9S_MB_2U_LIB.S9S_MB_2U(SCH_1):PAGE39_I1@PURE_QUANTA.SOCKET4677_AZIF0045P001C01CS(CHIPS)':
 'VSS1424': CDS_PINID='VSS1424';
NODE_NAME     U2 EJ13
 '@S9S_MB_2U_LIB.S9S_MB_2U(SCH_1):PAGE39_I1@PURE_QUANTA.SOCKET4677_AZIF0045P001C01CS(CHIPS)':
 'VSS1425': CDS_PINID='VSS1425';
NODE_NAME     U2 EJ19
 '@S9S_MB_2U_LIB.S9S_MB_2U(SCH_1):PAGE39_I1@PURE_QUANTA.SOCKET4677_AZIF0045P001C01CS(CHIPS)':
 'VSS1426': CDS_PINID='VSS1426';
NODE_NAME     U2 EN39
 '@S9S_MB_2U_LIB.S9S_MB_2U(SCH_1):PAGE39_I1@PURE_QUANTA.SOCKET4677_AZIF0045P001C01CS(CHIPS)':
 'VSS1427': CDS_PINID='VSS1427';
NODE_NAME     U2 EJ23
 '@S9S_MB_2U_LIB.S9S_MB_2U(SCH_1):PAGE39_I1@PURE_QUANTA.SOCKET4677_AZIF0045P001C01CS(CHIPS)':
 'VSS1428': CDS_PINID='VSS1428';
NODE_NAME     U2 EJ29
 '@S9S_MB_2U_LIB.S9S_MB_2U(SCH_1):PAGE39_I1@PURE_QUANTA.SOCKET4677_AZIF0045P001C01CS(CHIPS)':
 'VSS1429': CDS_PINID='VSS1429';
NODE_NAME     U2 EJ31
 '@S9S_MB_2U_LIB.S9S_MB_2U(SCH_1):PAGE39_I1@PURE_QUANTA.SOCKET4677_AZIF0045P001C01CS(CHIPS)':
 'VSS1430': CDS_PINID='VSS1430';
NODE_NAME     U2 EJ37
 '@S9S_MB_2U_LIB.S9S_MB_2U(SCH_1):PAGE39_I1@PURE_QUANTA.SOCKET4677_AZIF0045P001C01CS(CHIPS)':
 'VSS1431': CDS_PINID='VSS1431';
NODE_NAME     U2 EJ41
 '@S9S_MB_2U_LIB.S9S_MB_2U(SCH_1):PAGE39_I1@PURE_QUANTA.SOCKET4677_AZIF0045P001C01CS(CHIPS)':
 'VSS1432': CDS_PINID='VSS1432';
NODE_NAME     U2 EJ43
 '@S9S_MB_2U_LIB.S9S_MB_2U(SCH_1):PAGE39_I1@PURE_QUANTA.SOCKET4677_AZIF0045P001C01CS(CHIPS)':
 'VSS1433': CDS_PINID='VSS1433';
NODE_NAME     U2 EJ48
 '@S9S_MB_2U_LIB.S9S_MB_2U(SCH_1):PAGE39_I1@PURE_QUANTA.SOCKET4677_AZIF0045P001C01CS(CHIPS)':
 'VSS1434': CDS_PINID='VSS1434';
NODE_NAME     U2 EJ50
 '@S9S_MB_2U_LIB.S9S_MB_2U(SCH_1):PAGE39_I1@PURE_QUANTA.SOCKET4677_AZIF0045P001C01CS(CHIPS)':
 'VSS1435': CDS_PINID='VSS1435';
NODE_NAME     U2 EN58
 '@S9S_MB_2U_LIB.S9S_MB_2U(SCH_1):PAGE39_I1@PURE_QUANTA.SOCKET4677_AZIF0045P001C01CS(CHIPS)':
 'VSS1436': CDS_PINID='VSS1436';
NODE_NAME     U2 EN60
 '@S9S_MB_2U_LIB.S9S_MB_2U(SCH_1):PAGE39_I1@PURE_QUANTA.SOCKET4677_AZIF0045P001C01CS(CHIPS)':
 'VSS1437': CDS_PINID='VSS1437';
NODE_NAME     U2 EN62
 '@S9S_MB_2U_LIB.S9S_MB_2U(SCH_1):PAGE39_I1@PURE_QUANTA.SOCKET4677_AZIF0045P001C01CS(CHIPS)':
 'VSS1438': CDS_PINID='VSS1438';
NODE_NAME     U2 EJ56
 '@S9S_MB_2U_LIB.S9S_MB_2U(SCH_1):PAGE39_I1@PURE_QUANTA.SOCKET4677_AZIF0045P001C01CS(CHIPS)':
 'VSS1439': CDS_PINID='VSS1439';
NODE_NAME     U2 EN66
 '@S9S_MB_2U_LIB.S9S_MB_2U(SCH_1):PAGE39_I1@PURE_QUANTA.SOCKET4677_AZIF0045P001C01CS(CHIPS)':
 'VSS1440': CDS_PINID='VSS1440';
NODE_NAME     U2 EN72
 '@S9S_MB_2U_LIB.S9S_MB_2U(SCH_1):PAGE39_I1@PURE_QUANTA.SOCKET4677_AZIF0045P001C01CS(CHIPS)':
 'VSS1441': CDS_PINID='VSS1441';
NODE_NAME     U2 EJ60
 '@S9S_MB_2U_LIB.S9S_MB_2U(SCH_1):PAGE39_I1@PURE_QUANTA.SOCKET4677_AZIF0045P001C01CS(CHIPS)':
 'VSS1442': CDS_PINID='VSS1442';
NODE_NAME     U2 EJ66
 '@S9S_MB_2U_LIB.S9S_MB_2U(SCH_1):PAGE39_I1@PURE_QUANTA.SOCKET4677_AZIF0045P001C01CS(CHIPS)':
 'VSS1443': CDS_PINID='VSS1443';
NODE_NAME     U2 EJ7
 '@S9S_MB_2U_LIB.S9S_MB_2U(SCH_1):PAGE39_I1@PURE_QUANTA.SOCKET4677_AZIF0045P001C01CS(CHIPS)':
 'VSS1444': CDS_PINID='VSS1444';
NODE_NAME     U2 EN88
 '@S9S_MB_2U_LIB.S9S_MB_2U(SCH_1):PAGE39_I1@PURE_QUANTA.SOCKET4677_AZIF0045P001C01CS(CHIPS)':
 'VSS1445': CDS_PINID='VSS1445';
NODE_NAME     U2 EN9
 '@S9S_MB_2U_LIB.S9S_MB_2U(SCH_1):PAGE39_I1@PURE_QUANTA.SOCKET4677_AZIF0045P001C01CS(CHIPS)':
 'VSS1446': CDS_PINID='VSS1446';
NODE_NAME     U2 EJ74
 '@S9S_MB_2U_LIB.S9S_MB_2U(SCH_1):PAGE39_I1@PURE_QUANTA.SOCKET4677_AZIF0045P001C01CS(CHIPS)':
 'VSS1447': CDS_PINID='VSS1447';
NODE_NAME     U2 EJ78
 '@S9S_MB_2U_LIB.S9S_MB_2U(SCH_1):PAGE39_I1@PURE_QUANTA.SOCKET4677_AZIF0045P001C01CS(CHIPS)':
 'VSS1448': CDS_PINID='VSS1448';
NODE_NAME     U2 EJ88
 '@S9S_MB_2U_LIB.S9S_MB_2U(SCH_1):PAGE39_I1@PURE_QUANTA.SOCKET4677_AZIF0045P001C01CS(CHIPS)':
 'VSS1449': CDS_PINID='VSS1449';
NODE_NAME     U2 EJ9
 '@S9S_MB_2U_LIB.S9S_MB_2U(SCH_1):PAGE39_I1@PURE_QUANTA.SOCKET4677_AZIF0045P001C01CS(CHIPS)':
 'VSS1450': CDS_PINID='VSS1450';
NODE_NAME     U2 EK10
 '@S9S_MB_2U_LIB.S9S_MB_2U(SCH_1):PAGE39_I1@PURE_QUANTA.SOCKET4677_AZIF0045P001C01CS(CHIPS)':
 'VSS1451': CDS_PINID='VSS1451';
NODE_NAME     U2 EP69
 '@S9S_MB_2U_LIB.S9S_MB_2U(SCH_1):PAGE39_I1@PURE_QUANTA.SOCKET4677_AZIF0045P001C01CS(CHIPS)':
 'VSS1452': CDS_PINID='VSS1452';
NODE_NAME     U2 EP71
 '@S9S_MB_2U_LIB.S9S_MB_2U(SCH_1):PAGE39_I1@PURE_QUANTA.SOCKET4677_AZIF0045P001C01CS(CHIPS)':
 'VSS1453': CDS_PINID='VSS1453';
NODE_NAME     U2 EP77
 '@S9S_MB_2U_LIB.S9S_MB_2U(SCH_1):PAGE39_I1@PURE_QUANTA.SOCKET4677_AZIF0045P001C01CS(CHIPS)':
 'VSS1454': CDS_PINID='VSS1454';
NODE_NAME     U2 EK14
 '@S9S_MB_2U_LIB.S9S_MB_2U(SCH_1):PAGE39_I1@PURE_QUANTA.SOCKET4677_AZIF0045P001C01CS(CHIPS)':
 'VSS1455': CDS_PINID='VSS1455';
NODE_NAME     U2 ER15
 '@S9S_MB_2U_LIB.S9S_MB_2U(SCH_1):PAGE39_I1@PURE_QUANTA.SOCKET4677_AZIF0045P001C01CS(CHIPS)':
 'VSS1456': CDS_PINID='VSS1456';
NODE_NAME     U2 ER21
 '@S9S_MB_2U_LIB.S9S_MB_2U(SCH_1):PAGE39_I1@PURE_QUANTA.SOCKET4677_AZIF0045P001C01CS(CHIPS)':
 'VSS1457': CDS_PINID='VSS1457';
NODE_NAME     U2 EK2
 '@S9S_MB_2U_LIB.S9S_MB_2U(SCH_1):PAGE39_I1@PURE_QUANTA.SOCKET4677_AZIF0045P001C01CS(CHIPS)':
 'VSS1458': CDS_PINID='VSS1458';
NODE_NAME     U2 EK22
 '@S9S_MB_2U_LIB.S9S_MB_2U(SCH_1):PAGE39_I1@PURE_QUANTA.SOCKET4677_AZIF0045P001C01CS(CHIPS)':
 'VSS1459': CDS_PINID='VSS1459';
NODE_NAME     U2 EK28
 '@S9S_MB_2U_LIB.S9S_MB_2U(SCH_1):PAGE39_I1@PURE_QUANTA.SOCKET4677_AZIF0045P001C01CS(CHIPS)':
 'VSS1460': CDS_PINID='VSS1460';
NODE_NAME     U2 EK32
 '@S9S_MB_2U_LIB.S9S_MB_2U(SCH_1):PAGE39_I1@PURE_QUANTA.SOCKET4677_AZIF0045P001C01CS(CHIPS)':
 'VSS1461': CDS_PINID='VSS1461';
NODE_NAME     U2 ER39
 '@S9S_MB_2U_LIB.S9S_MB_2U(SCH_1):PAGE39_I1@PURE_QUANTA.SOCKET4677_AZIF0045P001C01CS(CHIPS)':
 'VSS1462': CDS_PINID='VSS1462';
NODE_NAME     U2 EK34
 '@S9S_MB_2U_LIB.S9S_MB_2U(SCH_1):PAGE39_I1@PURE_QUANTA.SOCKET4677_AZIF0045P001C01CS(CHIPS)':
 'VSS1463': CDS_PINID='VSS1463';
NODE_NAME     U2 ER52
 '@S9S_MB_2U_LIB.S9S_MB_2U(SCH_1):PAGE39_I1@PURE_QUANTA.SOCKET4677_AZIF0045P001C01CS(CHIPS)':
 'VSS1464': CDS_PINID='VSS1464';
NODE_NAME     U2 EK38
 '@S9S_MB_2U_LIB.S9S_MB_2U(SCH_1):PAGE39_I1@PURE_QUANTA.SOCKET4677_AZIF0045P001C01CS(CHIPS)':
 'VSS1465': CDS_PINID='VSS1465';
NODE_NAME     U2 EK4
 '@S9S_MB_2U_LIB.S9S_MB_2U(SCH_1):PAGE39_I1@PURE_QUANTA.SOCKET4677_AZIF0045P001C01CS(CHIPS)':
 'VSS1466': CDS_PINID='VSS1466';
NODE_NAME     U2 ER58
 '@S9S_MB_2U_LIB.S9S_MB_2U(SCH_1):PAGE39_I1@PURE_QUANTA.SOCKET4677_AZIF0045P001C01CS(CHIPS)':
 'VSS1467': CDS_PINID='VSS1467';
NODE_NAME     U2 ER64
 '@S9S_MB_2U_LIB.S9S_MB_2U(SCH_1):PAGE39_I1@PURE_QUANTA.SOCKET4677_AZIF0045P001C01CS(CHIPS)':
 'VSS1468': CDS_PINID='VSS1468';
NODE_NAME     U2 EK40
 '@S9S_MB_2U_LIB.S9S_MB_2U(SCH_1):PAGE39_I1@PURE_QUANTA.SOCKET4677_AZIF0045P001C01CS(CHIPS)':
 'VSS1469': CDS_PINID='VSS1469';
NODE_NAME     U2 EK47
 '@S9S_MB_2U_LIB.S9S_MB_2U(SCH_1):PAGE39_I1@PURE_QUANTA.SOCKET4677_AZIF0045P001C01CS(CHIPS)':
 'VSS1470': CDS_PINID='VSS1470';
NODE_NAME     U2 EK57
 '@S9S_MB_2U_LIB.S9S_MB_2U(SCH_1):PAGE39_I1@PURE_QUANTA.SOCKET4677_AZIF0045P001C01CS(CHIPS)':
 'VSS1471': CDS_PINID='VSS1471';
NODE_NAME     U2 EK65
 '@S9S_MB_2U_LIB.S9S_MB_2U(SCH_1):PAGE39_I1@PURE_QUANTA.SOCKET4677_AZIF0045P001C01CS(CHIPS)':
 'VSS1472': CDS_PINID='VSS1472';
NODE_NAME     U2 EK69
 '@S9S_MB_2U_LIB.S9S_MB_2U(SCH_1):PAGE39_I1@PURE_QUANTA.SOCKET4677_AZIF0045P001C01CS(CHIPS)':
 'VSS1473': CDS_PINID='VSS1473';
NODE_NAME     U2 EK75
 '@S9S_MB_2U_LIB.S9S_MB_2U(SCH_1):PAGE39_I1@PURE_QUANTA.SOCKET4677_AZIF0045P001C01CS(CHIPS)':
 'VSS1474': CDS_PINID='VSS1474';
NODE_NAME     U2 EL21
 '@S9S_MB_2U_LIB.S9S_MB_2U(SCH_1):PAGE39_I1@PURE_QUANTA.SOCKET4677_AZIF0045P001C01CS(CHIPS)':
 'VSS1475': CDS_PINID='VSS1475';
NODE_NAME     U2 ER9
 '@S9S_MB_2U_LIB.S9S_MB_2U(SCH_1):PAGE39_I1@PURE_QUANTA.SOCKET4677_AZIF0045P001C01CS(CHIPS)':
 'VSS1476': CDS_PINID='VSS1476';
NODE_NAME     U2 EL27
 '@S9S_MB_2U_LIB.S9S_MB_2U(SCH_1):PAGE39_I1@PURE_QUANTA.SOCKET4677_AZIF0045P001C01CS(CHIPS)':
 'VSS1477': CDS_PINID='VSS1477';
NODE_NAME     U2 ET14
 '@S9S_MB_2U_LIB.S9S_MB_2U(SCH_1):PAGE39_I1@PURE_QUANTA.SOCKET4677_AZIF0045P001C01CS(CHIPS)':
 'VSS1478': CDS_PINID='VSS1478';
NODE_NAME     U2 EL3
 '@S9S_MB_2U_LIB.S9S_MB_2U(SCH_1):PAGE39_I1@PURE_QUANTA.SOCKET4677_AZIF0045P001C01CS(CHIPS)':
 'VSS1479': CDS_PINID='VSS1479';
NODE_NAME     U2 ET20
 '@S9S_MB_2U_LIB.S9S_MB_2U(SCH_1):PAGE39_I1@PURE_QUANTA.SOCKET4677_AZIF0045P001C01CS(CHIPS)':
 'VSS1480': CDS_PINID='VSS1480';
NODE_NAME     U2 EL33
 '@S9S_MB_2U_LIB.S9S_MB_2U(SCH_1):PAGE39_I1@PURE_QUANTA.SOCKET4677_AZIF0045P001C01CS(CHIPS)':
 'VSS1481': CDS_PINID='VSS1481';
NODE_NAME     U2 ET26
 '@S9S_MB_2U_LIB.S9S_MB_2U(SCH_1):PAGE39_I1@PURE_QUANTA.SOCKET4677_AZIF0045P001C01CS(CHIPS)':
 'VSS1482': CDS_PINID='VSS1482';
NODE_NAME     U2 EL39
 '@S9S_MB_2U_LIB.S9S_MB_2U(SCH_1):PAGE39_I1@PURE_QUANTA.SOCKET4677_AZIF0045P001C01CS(CHIPS)':
 'VSS1483': CDS_PINID='VSS1483';
NODE_NAME     U2 ET32
 '@S9S_MB_2U_LIB.S9S_MB_2U(SCH_1):PAGE39_I1@PURE_QUANTA.SOCKET4677_AZIF0045P001C01CS(CHIPS)':
 'VSS1484': CDS_PINID='VSS1484';
NODE_NAME     U2 EL45
 '@S9S_MB_2U_LIB.S9S_MB_2U(SCH_1):PAGE39_I1@PURE_QUANTA.SOCKET4677_AZIF0045P001C01CS(CHIPS)':
 'VSS1485': CDS_PINID='VSS1485';
NODE_NAME     U2 EL5
 '@S9S_MB_2U_LIB.S9S_MB_2U(SCH_1):PAGE39_I1@PURE_QUANTA.SOCKET4677_AZIF0045P001C01CS(CHIPS)':
 'VSS1486': CDS_PINID='VSS1486';
NODE_NAME     U2 EL64
 '@S9S_MB_2U_LIB.S9S_MB_2U(SCH_1):PAGE39_I1@PURE_QUANTA.SOCKET4677_AZIF0045P001C01CS(CHIPS)':
 'VSS1488': CDS_PINID='VSS1488';
NODE_NAME     U2 EL76
 '@S9S_MB_2U_LIB.S9S_MB_2U(SCH_1):PAGE39_I1@PURE_QUANTA.SOCKET4677_AZIF0045P001C01CS(CHIPS)':
 'VSS1489': CDS_PINID='VSS1489';
NODE_NAME     U2 ET53
 '@S9S_MB_2U_LIB.S9S_MB_2U(SCH_1):PAGE39_I1@PURE_QUANTA.SOCKET4677_AZIF0045P001C01CS(CHIPS)':
 'VSS1491': CDS_PINID='VSS1491';
NODE_NAME     U2 EM42
 '@S9S_MB_2U_LIB.S9S_MB_2U(SCH_1):PAGE39_I1@PURE_QUANTA.SOCKET4677_AZIF0045P001C01CS(CHIPS)':
 'VSS1492': CDS_PINID='VSS1492';
NODE_NAME     U2 ET59
 '@S9S_MB_2U_LIB.S9S_MB_2U(SCH_1):PAGE39_I1@PURE_QUANTA.SOCKET4677_AZIF0045P001C01CS(CHIPS)':
 'VSS1493': CDS_PINID='VSS1493';
NODE_NAME     U2 EM73
 '@S9S_MB_2U_LIB.S9S_MB_2U(SCH_1):PAGE39_I1@PURE_QUANTA.SOCKET4677_AZIF0045P001C01CS(CHIPS)':
 'VSS1496': CDS_PINID='VSS1496';
NODE_NAME     U2 EM8
 '@S9S_MB_2U_LIB.S9S_MB_2U(SCH_1):PAGE39_I1@PURE_QUANTA.SOCKET4677_AZIF0045P001C01CS(CHIPS)':
 'VSS1497': CDS_PINID='VSS1497';
NODE_NAME     U2 EM81
 '@S9S_MB_2U_LIB.S9S_MB_2U(SCH_1):PAGE39_I1@PURE_QUANTA.SOCKET4677_AZIF0045P001C01CS(CHIPS)':
 'VSS1498': CDS_PINID='VSS1498';
NODE_NAME     U2 EM83
 '@S9S_MB_2U_LIB.S9S_MB_2U(SCH_1):PAGE39_I1@PURE_QUANTA.SOCKET4677_AZIF0045P001C01CS(CHIPS)':
 'VSS1499': CDS_PINID='VSS1499';
NODE_NAME     U2 EN11
 '@S9S_MB_2U_LIB.S9S_MB_2U(SCH_1):PAGE39_I1@PURE_QUANTA.SOCKET4677_AZIF0045P001C01CS(CHIPS)':
 'VSS1500': CDS_PINID='VSS1500';
NODE_NAME     U2 EN13
 '@S9S_MB_2U_LIB.S9S_MB_2U(SCH_1):PAGE39_I1@PURE_QUANTA.SOCKET4677_AZIF0045P001C01CS(CHIPS)':
 'VSS1501': CDS_PINID='VSS1501';
NODE_NAME     U2 EN15
 '@S9S_MB_2U_LIB.S9S_MB_2U(SCH_1):PAGE39_I1@PURE_QUANTA.SOCKET4677_AZIF0045P001C01CS(CHIPS)':
 'VSS1503': CDS_PINID='VSS1503';
NODE_NAME     U2 EN17
 '@S9S_MB_2U_LIB.S9S_MB_2U(SCH_1):PAGE39_I1@PURE_QUANTA.SOCKET4677_AZIF0045P001C01CS(CHIPS)':
 'VSS1505': CDS_PINID='VSS1505';
NODE_NAME     U2 EN19
 '@S9S_MB_2U_LIB.S9S_MB_2U(SCH_1):PAGE39_I1@PURE_QUANTA.SOCKET4677_AZIF0045P001C01CS(CHIPS)':
 'VSS1506': CDS_PINID='VSS1506';
NODE_NAME     U2 EN21
 '@S9S_MB_2U_LIB.S9S_MB_2U(SCH_1):PAGE39_I1@PURE_QUANTA.SOCKET4677_AZIF0045P001C01CS(CHIPS)':
 'VSS1512': CDS_PINID='VSS1512';
NODE_NAME     U2 EN23
 '@S9S_MB_2U_LIB.S9S_MB_2U(SCH_1):PAGE39_I1@PURE_QUANTA.SOCKET4677_AZIF0045P001C01CS(CHIPS)':
 'VSS1513': CDS_PINID='VSS1513';
NODE_NAME     U2 EN25
 '@S9S_MB_2U_LIB.S9S_MB_2U(SCH_1):PAGE39_I1@PURE_QUANTA.SOCKET4677_AZIF0045P001C01CS(CHIPS)':
 'VSS1515': CDS_PINID='VSS1515';
NODE_NAME     U2 EN27
 '@S9S_MB_2U_LIB.S9S_MB_2U(SCH_1):PAGE39_I1@PURE_QUANTA.SOCKET4677_AZIF0045P001C01CS(CHIPS)':
 'VSS1517': CDS_PINID='VSS1517';
NODE_NAME     U2 EN29
 '@S9S_MB_2U_LIB.S9S_MB_2U(SCH_1):PAGE39_I1@PURE_QUANTA.SOCKET4677_AZIF0045P001C01CS(CHIPS)':
 'VSS1518': CDS_PINID='VSS1518';
NODE_NAME     U2 EN31
 '@S9S_MB_2U_LIB.S9S_MB_2U(SCH_1):PAGE39_I1@PURE_QUANTA.SOCKET4677_AZIF0045P001C01CS(CHIPS)':
 'VSS1520': CDS_PINID='VSS1520';
NODE_NAME     U2 EN33
 '@S9S_MB_2U_LIB.S9S_MB_2U(SCH_1):PAGE39_I1@PURE_QUANTA.SOCKET4677_AZIF0045P001C01CS(CHIPS)':
 'VSS1522': CDS_PINID='VSS1522';
NODE_NAME     U2 EN35
 '@S9S_MB_2U_LIB.S9S_MB_2U(SCH_1):PAGE39_I1@PURE_QUANTA.SOCKET4677_AZIF0045P001C01CS(CHIPS)':
 'VSS1524': CDS_PINID='VSS1524';
NODE_NAME     U2 EN37
 '@S9S_MB_2U_LIB.S9S_MB_2U(SCH_1):PAGE39_I1@PURE_QUANTA.SOCKET4677_AZIF0045P001C01CS(CHIPS)':
 'VSS1525': CDS_PINID='VSS1525';
NODE_NAME     U2 EN41
 '@S9S_MB_2U_LIB.S9S_MB_2U(SCH_1):PAGE39_I1@PURE_QUANTA.SOCKET4677_AZIF0045P001C01CS(CHIPS)':
 'VSS1526': CDS_PINID='VSS1526';
NODE_NAME     U2 EN43
 '@S9S_MB_2U_LIB.S9S_MB_2U(SCH_1):PAGE39_I1@PURE_QUANTA.SOCKET4677_AZIF0045P001C01CS(CHIPS)':
 'VSS1528': CDS_PINID='VSS1528';
NODE_NAME     U2 EN45
 '@S9S_MB_2U_LIB.S9S_MB_2U(SCH_1):PAGE39_I1@PURE_QUANTA.SOCKET4677_AZIF0045P001C01CS(CHIPS)':
 'VSS1529': CDS_PINID='VSS1529';
NODE_NAME     U2 EN48
 '@S9S_MB_2U_LIB.S9S_MB_2U(SCH_1):PAGE39_I1@PURE_QUANTA.SOCKET4677_AZIF0045P001C01CS(CHIPS)':
 'VSS1530': CDS_PINID='VSS1530';
NODE_NAME     U2 EN50
 '@S9S_MB_2U_LIB.S9S_MB_2U(SCH_1):PAGE39_I1@PURE_QUANTA.SOCKET4677_AZIF0045P001C01CS(CHIPS)':
 'VSS1531': CDS_PINID='VSS1531';
NODE_NAME     U2 EN52
 '@S9S_MB_2U_LIB.S9S_MB_2U(SCH_1):PAGE39_I1@PURE_QUANTA.SOCKET4677_AZIF0045P001C01CS(CHIPS)':
 'VSS1533': CDS_PINID='VSS1533';
NODE_NAME     U2 EN54
 '@S9S_MB_2U_LIB.S9S_MB_2U(SCH_1):PAGE39_I1@PURE_QUANTA.SOCKET4677_AZIF0045P001C01CS(CHIPS)':
 'VSS1537': CDS_PINID='VSS1537';
NODE_NAME     U2 EN56
 '@S9S_MB_2U_LIB.S9S_MB_2U(SCH_1):PAGE39_I1@PURE_QUANTA.SOCKET4677_AZIF0045P001C01CS(CHIPS)':
 'VSS1539': CDS_PINID='VSS1539';
NODE_NAME     U2 EN64
 '@S9S_MB_2U_LIB.S9S_MB_2U(SCH_1):PAGE39_I1@PURE_QUANTA.SOCKET4677_AZIF0045P001C01CS(CHIPS)':
 'VSS1540': CDS_PINID='VSS1540';
NODE_NAME     U2 EN78
 '@S9S_MB_2U_LIB.S9S_MB_2U(SCH_1):PAGE39_I1@PURE_QUANTA.SOCKET4677_AZIF0045P001C01CS(CHIPS)':
 'VSS1541': CDS_PINID='VSS1541';
NODE_NAME     U2 EN80
 '@S9S_MB_2U_LIB.S9S_MB_2U(SCH_1):PAGE39_I1@PURE_QUANTA.SOCKET4677_AZIF0045P001C01CS(CHIPS)':
 'VSS1542': CDS_PINID='VSS1542';
NODE_NAME     U2 EP67
 '@S9S_MB_2U_LIB.S9S_MB_2U(SCH_1):PAGE39_I1@PURE_QUANTA.SOCKET4677_AZIF0045P001C01CS(CHIPS)':
 'VSS1543': CDS_PINID='VSS1543';
NODE_NAME     U2 EP83
 '@S9S_MB_2U_LIB.S9S_MB_2U(SCH_1):PAGE39_I1@PURE_QUANTA.SOCKET4677_AZIF0045P001C01CS(CHIPS)':
 'VSS1545': CDS_PINID='VSS1545';
NODE_NAME     U2 ER27
 '@S9S_MB_2U_LIB.S9S_MB_2U(SCH_1):PAGE39_I1@PURE_QUANTA.SOCKET4677_AZIF0045P001C01CS(CHIPS)':
 'VSS1547': CDS_PINID='VSS1547';
NODE_NAME     U2 ER33
 '@S9S_MB_2U_LIB.S9S_MB_2U(SCH_1):PAGE39_I1@PURE_QUANTA.SOCKET4677_AZIF0045P001C01CS(CHIPS)':
 'VSS1548': CDS_PINID='VSS1548';
NODE_NAME     U2 ER5
 '@S9S_MB_2U_LIB.S9S_MB_2U(SCH_1):PAGE39_I1@PURE_QUANTA.SOCKET4677_AZIF0045P001C01CS(CHIPS)':
 'VSS1549': CDS_PINID='VSS1549';
NODE_NAME     U2 ER7
 '@S9S_MB_2U_LIB.S9S_MB_2U(SCH_1):PAGE39_I1@PURE_QUANTA.SOCKET4677_AZIF0045P001C01CS(CHIPS)':
 'VSS1550': CDS_PINID='VSS1550';
NODE_NAME     U2 ER70
 '@S9S_MB_2U_LIB.S9S_MB_2U(SCH_1):PAGE39_I1@PURE_QUANTA.SOCKET4677_AZIF0045P001C01CS(CHIPS)':
 'VSS1551': CDS_PINID='VSS1551';
NODE_NAME     U2 ER74
 '@S9S_MB_2U_LIB.S9S_MB_2U(SCH_1):PAGE39_I1@PURE_QUANTA.SOCKET4677_AZIF0045P001C01CS(CHIPS)':
 'VSS1552': CDS_PINID='VSS1552';
NODE_NAME     U2 ER78
 '@S9S_MB_2U_LIB.S9S_MB_2U(SCH_1):PAGE39_I1@PURE_QUANTA.SOCKET4677_AZIF0045P001C01CS(CHIPS)':
 'VSS1553': CDS_PINID='VSS1553';
NODE_NAME     U2 ER80
 '@S9S_MB_2U_LIB.S9S_MB_2U(SCH_1):PAGE39_I1@PURE_QUANTA.SOCKET4677_AZIF0045P001C01CS(CHIPS)':
 'VSS1554': CDS_PINID='VSS1554';
NODE_NAME     U2 ER84
 '@S9S_MB_2U_LIB.S9S_MB_2U(SCH_1):PAGE39_I1@PURE_QUANTA.SOCKET4677_AZIF0045P001C01CS(CHIPS)':
 'VSS1555': CDS_PINID='VSS1555';
NODE_NAME     U2 ER86
 '@S9S_MB_2U_LIB.S9S_MB_2U(SCH_1):PAGE39_I1@PURE_QUANTA.SOCKET4677_AZIF0045P001C01CS(CHIPS)':
 'VSS1556': CDS_PINID='VSS1556';
NODE_NAME     U2 ET10
 '@S9S_MB_2U_LIB.S9S_MB_2U(SCH_1):PAGE39_I1@PURE_QUANTA.SOCKET4677_AZIF0045P001C01CS(CHIPS)':
 'VSS1557': CDS_PINID='VSS1557';
NODE_NAME     U2 ET16
 '@S9S_MB_2U_LIB.S9S_MB_2U(SCH_1):PAGE39_I1@PURE_QUANTA.SOCKET4677_AZIF0045P001C01CS(CHIPS)':
 'VSS1559': CDS_PINID='VSS1559';
NODE_NAME     U2 ET22
 '@S9S_MB_2U_LIB.S9S_MB_2U(SCH_1):PAGE39_I1@PURE_QUANTA.SOCKET4677_AZIF0045P001C01CS(CHIPS)':
 'VSS1561': CDS_PINID='VSS1561';
NODE_NAME     U2 ET28
 '@S9S_MB_2U_LIB.S9S_MB_2U(SCH_1):PAGE39_I1@PURE_QUANTA.SOCKET4677_AZIF0045P001C01CS(CHIPS)':
 'VSS1562': CDS_PINID='VSS1562';
NODE_NAME     U2 ET34
 '@S9S_MB_2U_LIB.S9S_MB_2U(SCH_1):PAGE39_I1@PURE_QUANTA.SOCKET4677_AZIF0045P001C01CS(CHIPS)':
 'VSS1563': CDS_PINID='VSS1563';
NODE_NAME     U2 ET38
 '@S9S_MB_2U_LIB.S9S_MB_2U(SCH_1):PAGE39_I1@PURE_QUANTA.SOCKET4677_AZIF0045P001C01CS(CHIPS)':
 'VSS1565': CDS_PINID='VSS1565';
NODE_NAME     U2 ET57
 '@S9S_MB_2U_LIB.S9S_MB_2U(SCH_1):PAGE39_I1@PURE_QUANTA.SOCKET4677_AZIF0045P001C01CS(CHIPS)':
 'VSS1569': CDS_PINID='VSS1569';
NODE_NAME     U2 ER41
 '@S9S_MB_2U_LIB.S9S_MB_2U(SCH_1):PAGE39_I1@PURE_QUANTA.SOCKET4677_AZIF0045P001C01CS(CHIPS)':
 'VSS1834': CDS_PINID='VSS1834';
NODE_NAME     U2 ER43
 '@S9S_MB_2U_LIB.S9S_MB_2U(SCH_1):PAGE39_I1@PURE_QUANTA.SOCKET4677_AZIF0045P001C01CS(CHIPS)':
 'VSS1835': CDS_PINID='VSS1835';
NODE_NAME     U2 ER48
 '@S9S_MB_2U_LIB.S9S_MB_2U(SCH_1):PAGE39_I1@PURE_QUANTA.SOCKET4677_AZIF0045P001C01CS(CHIPS)':
 'VSS1836': CDS_PINID='VSS1836';
NODE_NAME     U2 ER50
 '@S9S_MB_2U_LIB.S9S_MB_2U(SCH_1):PAGE39_I1@PURE_QUANTA.SOCKET4677_AZIF0045P001C01CS(CHIPS)':
 'VSS1837': CDS_PINID='VSS1837';
NODE_NAME     U2 DY12
 '@S9S_MB_2U_LIB.S9S_MB_2U(SCH_1):PAGE39_I9@PURE_QUANTA.SOCKET4677_AZIF0045P001C01CS(CHIPS)':
 'VSS1111': CDS_PINID='VSS1111';
NODE_NAME     U2 DY16
 '@S9S_MB_2U_LIB.S9S_MB_2U(SCH_1):PAGE39_I9@PURE_QUANTA.SOCKET4677_AZIF0045P001C01CS(CHIPS)':
 'VSS1112': CDS_PINID='VSS1112';
NODE_NAME     U2 DY4
 '@S9S_MB_2U_LIB.S9S_MB_2U(SCH_1):PAGE39_I9@PURE_QUANTA.SOCKET4677_AZIF0045P001C01CS(CHIPS)':
 'VSS1115': CDS_PINID='VSS1115';
NODE_NAME     U2 DY42
 '@S9S_MB_2U_LIB.S9S_MB_2U(SCH_1):PAGE39_I9@PURE_QUANTA.SOCKET4677_AZIF0045P001C01CS(CHIPS)':
 'VSS1116': CDS_PINID='VSS1116';
NODE_NAME     U2 EA39
 '@S9S_MB_2U_LIB.S9S_MB_2U(SCH_1):PAGE39_I9@PURE_QUANTA.SOCKET4677_AZIF0045P001C01CS(CHIPS)':
 'VSS1141': CDS_PINID='VSS1141';
NODE_NAME     U2 EA45
 '@S9S_MB_2U_LIB.S9S_MB_2U(SCH_1):PAGE39_I9@PURE_QUANTA.SOCKET4677_AZIF0045P001C01CS(CHIPS)':
 'VSS1142': CDS_PINID='VSS1142';
NODE_NAME     U2 EA52
 '@S9S_MB_2U_LIB.S9S_MB_2U(SCH_1):PAGE39_I9@PURE_QUANTA.SOCKET4677_AZIF0045P001C01CS(CHIPS)':
 'VSS1144': CDS_PINID='VSS1144';
NODE_NAME     U2 EA58
 '@S9S_MB_2U_LIB.S9S_MB_2U(SCH_1):PAGE39_I9@PURE_QUANTA.SOCKET4677_AZIF0045P001C01CS(CHIPS)':
 'VSS1145': CDS_PINID='VSS1145';
NODE_NAME     U2 EA64
 '@S9S_MB_2U_LIB.S9S_MB_2U(SCH_1):PAGE39_I9@PURE_QUANTA.SOCKET4677_AZIF0045P001C01CS(CHIPS)':
 'VSS1146': CDS_PINID='VSS1146';
NODE_NAME     U2 EB16
 '@S9S_MB_2U_LIB.S9S_MB_2U(SCH_1):PAGE39_I9@PURE_QUANTA.SOCKET4677_AZIF0045P001C01CS(CHIPS)':
 'VSS1155': CDS_PINID='VSS1155';
NODE_NAME     U2 EB20
 '@S9S_MB_2U_LIB.S9S_MB_2U(SCH_1):PAGE39_I9@PURE_QUANTA.SOCKET4677_AZIF0045P001C01CS(CHIPS)':
 'VSS1156': CDS_PINID='VSS1156';
NODE_NAME     U2 EB26
 '@S9S_MB_2U_LIB.S9S_MB_2U(SCH_1):PAGE39_I9@PURE_QUANTA.SOCKET4677_AZIF0045P001C01CS(CHIPS)':
 'VSS1158': CDS_PINID='VSS1158';
NODE_NAME     U2 EB34
 '@S9S_MB_2U_LIB.S9S_MB_2U(SCH_1):PAGE39_I9@PURE_QUANTA.SOCKET4677_AZIF0045P001C01CS(CHIPS)':
 'VSS1161': CDS_PINID='VSS1161';
NODE_NAME     U2 EB4
 '@S9S_MB_2U_LIB.S9S_MB_2U(SCH_1):PAGE39_I9@PURE_QUANTA.SOCKET4677_AZIF0045P001C01CS(CHIPS)':
 'VSS1163': CDS_PINID='VSS1163';
NODE_NAME     U2 EB44
 '@S9S_MB_2U_LIB.S9S_MB_2U(SCH_1):PAGE39_I9@PURE_QUANTA.SOCKET4677_AZIF0045P001C01CS(CHIPS)':
 'VSS1165': CDS_PINID='VSS1165';
NODE_NAME     U2 EB51
 '@S9S_MB_2U_LIB.S9S_MB_2U(SCH_1):PAGE39_I9@PURE_QUANTA.SOCKET4677_AZIF0045P001C01CS(CHIPS)':
 'VSS1167': CDS_PINID='VSS1167';
NODE_NAME     U2 EB53
 '@S9S_MB_2U_LIB.S9S_MB_2U(SCH_1):PAGE39_I9@PURE_QUANTA.SOCKET4677_AZIF0045P001C01CS(CHIPS)':
 'VSS1168': CDS_PINID='VSS1168';
NODE_NAME     U2 EB59
 '@S9S_MB_2U_LIB.S9S_MB_2U(SCH_1):PAGE39_I9@PURE_QUANTA.SOCKET4677_AZIF0045P001C01CS(CHIPS)':
 'VSS1170': CDS_PINID='VSS1170';
NODE_NAME     U2 EB63
 '@S9S_MB_2U_LIB.S9S_MB_2U(SCH_1):PAGE39_I9@PURE_QUANTA.SOCKET4677_AZIF0045P001C01CS(CHIPS)':
 'VSS1171': CDS_PINID='VSS1171';
NODE_NAME     U2 EB91
 '@S9S_MB_2U_LIB.S9S_MB_2U(SCH_1):PAGE39_I9@PURE_QUANTA.SOCKET4677_AZIF0045P001C01CS(CHIPS)':
 'VSS1180': CDS_PINID='VSS1180';
NODE_NAME     U2 EC25
 '@S9S_MB_2U_LIB.S9S_MB_2U(SCH_1):PAGE39_I9@PURE_QUANTA.SOCKET4677_AZIF0045P001C01CS(CHIPS)':
 'VSS1185': CDS_PINID='VSS1185';
NODE_NAME     U2 EC35
 '@S9S_MB_2U_LIB.S9S_MB_2U(SCH_1):PAGE39_I9@PURE_QUANTA.SOCKET4677_AZIF0045P001C01CS(CHIPS)':
 'VSS1188': CDS_PINID='VSS1188';
NODE_NAME     U2 EC5
 '@S9S_MB_2U_LIB.S9S_MB_2U(SCH_1):PAGE39_I9@PURE_QUANTA.SOCKET4677_AZIF0045P001C01CS(CHIPS)':
 'VSS1193': CDS_PINID='VSS1193';
NODE_NAME     U2 EC54
 '@S9S_MB_2U_LIB.S9S_MB_2U(SCH_1):PAGE39_I9@PURE_QUANTA.SOCKET4677_AZIF0045P001C01CS(CHIPS)':
 'VSS1195': CDS_PINID='VSS1195';
NODE_NAME     U2 EC60
 '@S9S_MB_2U_LIB.S9S_MB_2U(SCH_1):PAGE39_I9@PURE_QUANTA.SOCKET4677_AZIF0045P001C01CS(CHIPS)':
 'VSS1197': CDS_PINID='VSS1197';
NODE_NAME     U2 EC62
 '@S9S_MB_2U_LIB.S9S_MB_2U(SCH_1):PAGE39_I9@PURE_QUANTA.SOCKET4677_AZIF0045P001C01CS(CHIPS)':
 'VSS1198': CDS_PINID='VSS1198';
NODE_NAME     U2 EC68
 '@S9S_MB_2U_LIB.S9S_MB_2U(SCH_1):PAGE39_I9@PURE_QUANTA.SOCKET4677_AZIF0045P001C01CS(CHIPS)':
 'VSS1200': CDS_PINID='VSS1200';
NODE_NAME     U2 ED12
 '@S9S_MB_2U_LIB.S9S_MB_2U(SCH_1):PAGE39_I9@PURE_QUANTA.SOCKET4677_AZIF0045P001C01CS(CHIPS)':
 'VSS1208': CDS_PINID='VSS1208';
NODE_NAME     U2 ED18
 '@S9S_MB_2U_LIB.S9S_MB_2U(SCH_1):PAGE39_I9@PURE_QUANTA.SOCKET4677_AZIF0045P001C01CS(CHIPS)':
 'VSS1210': CDS_PINID='VSS1210';
NODE_NAME     U2 ED42
 '@S9S_MB_2U_LIB.S9S_MB_2U(SCH_1):PAGE39_I9@PURE_QUANTA.SOCKET4677_AZIF0045P001C01CS(CHIPS)':
 'VSS1217': CDS_PINID='VSS1217';
NODE_NAME     U2 ED55
 '@S9S_MB_2U_LIB.S9S_MB_2U(SCH_1):PAGE39_I9@PURE_QUANTA.SOCKET4677_AZIF0045P001C01CS(CHIPS)':
 'VSS1220': CDS_PINID='VSS1220';
NODE_NAME     U2 ED61
 '@S9S_MB_2U_LIB.S9S_MB_2U(SCH_1):PAGE39_I9@PURE_QUANTA.SOCKET4677_AZIF0045P001C01CS(CHIPS)':
 'VSS1223': CDS_PINID='VSS1223';
NODE_NAME     U2 ED67
 '@S9S_MB_2U_LIB.S9S_MB_2U(SCH_1):PAGE39_I9@PURE_QUANTA.SOCKET4677_AZIF0045P001C01CS(CHIPS)':
 'VSS1224': CDS_PINID='VSS1224';
NODE_NAME     U2 ED73
 '@S9S_MB_2U_LIB.S9S_MB_2U(SCH_1):PAGE39_I9@PURE_QUANTA.SOCKET4677_AZIF0045P001C01CS(CHIPS)':
 'VSS1225': CDS_PINID='VSS1225';
NODE_NAME     U2 EE17
 '@S9S_MB_2U_LIB.S9S_MB_2U(SCH_1):PAGE39_I9@PURE_QUANTA.SOCKET4677_AZIF0045P001C01CS(CHIPS)':
 'VSS1232': CDS_PINID='VSS1232';
NODE_NAME     U2 EE39
 '@S9S_MB_2U_LIB.S9S_MB_2U(SCH_1):PAGE39_I9@PURE_QUANTA.SOCKET4677_AZIF0045P001C01CS(CHIPS)':
 'VSS1235': CDS_PINID='VSS1235';
NODE_NAME     U2 EE52
 '@S9S_MB_2U_LIB.S9S_MB_2U(SCH_1):PAGE39_I9@PURE_QUANTA.SOCKET4677_AZIF0045P001C01CS(CHIPS)':
 'VSS1237': CDS_PINID='VSS1237';
NODE_NAME     U2 DW66
 '@S9S_MB_2U_LIB.S9S_MB_2U(SCH_1):PAGE39_I9@PURE_QUANTA.SOCKET4677_AZIF0045P001C01CS(CHIPS)':
 'VSS1257': CDS_PINID='VSS1257';
NODE_NAME     U2 DW68
 '@S9S_MB_2U_LIB.S9S_MB_2U(SCH_1):PAGE39_I9@PURE_QUANTA.SOCKET4677_AZIF0045P001C01CS(CHIPS)':
 'VSS1258': CDS_PINID='VSS1258';
NODE_NAME     U2 DW70
 '@S9S_MB_2U_LIB.S9S_MB_2U(SCH_1):PAGE39_I9@PURE_QUANTA.SOCKET4677_AZIF0045P001C01CS(CHIPS)':
 'VSS1259': CDS_PINID='VSS1259';
NODE_NAME     U2 DW72
 '@S9S_MB_2U_LIB.S9S_MB_2U(SCH_1):PAGE39_I9@PURE_QUANTA.SOCKET4677_AZIF0045P001C01CS(CHIPS)':
 'VSS1260': CDS_PINID='VSS1260';
NODE_NAME     U2 DW74
 '@S9S_MB_2U_LIB.S9S_MB_2U(SCH_1):PAGE39_I9@PURE_QUANTA.SOCKET4677_AZIF0045P001C01CS(CHIPS)':
 'VSS1261': CDS_PINID='VSS1261';
NODE_NAME     U2 DW76
 '@S9S_MB_2U_LIB.S9S_MB_2U(SCH_1):PAGE39_I9@PURE_QUANTA.SOCKET4677_AZIF0045P001C01CS(CHIPS)':
 'VSS1262': CDS_PINID='VSS1262';
NODE_NAME     U2 DW80
 '@S9S_MB_2U_LIB.S9S_MB_2U(SCH_1):PAGE39_I9@PURE_QUANTA.SOCKET4677_AZIF0045P001C01CS(CHIPS)':
 'VSS1263': CDS_PINID='VSS1263';
NODE_NAME     U2 DW82
 '@S9S_MB_2U_LIB.S9S_MB_2U(SCH_1):PAGE39_I9@PURE_QUANTA.SOCKET4677_AZIF0045P001C01CS(CHIPS)':
 'VSS1264': CDS_PINID='VSS1264';
NODE_NAME     U2 EF51
 '@S9S_MB_2U_LIB.S9S_MB_2U(SCH_1):PAGE39_I9@PURE_QUANTA.SOCKET4677_AZIF0045P001C01CS(CHIPS)':
 'VSS1265': CDS_PINID='VSS1265';
NODE_NAME     U2 DW84
 '@S9S_MB_2U_LIB.S9S_MB_2U(SCH_1):PAGE39_I9@PURE_QUANTA.SOCKET4677_AZIF0045P001C01CS(CHIPS)':
 'VSS1266': CDS_PINID='VSS1266';
NODE_NAME     U2 DW88
 '@S9S_MB_2U_LIB.S9S_MB_2U(SCH_1):PAGE39_I9@PURE_QUANTA.SOCKET4677_AZIF0045P001C01CS(CHIPS)':
 'VSS1267': CDS_PINID='VSS1267';
NODE_NAME     U2 DY77
 '@S9S_MB_2U_LIB.S9S_MB_2U(SCH_1):PAGE39_I9@PURE_QUANTA.SOCKET4677_AZIF0045P001C01CS(CHIPS)':
 'VSS1269': CDS_PINID='VSS1269';
NODE_NAME     U2 DY8
 '@S9S_MB_2U_LIB.S9S_MB_2U(SCH_1):PAGE39_I9@PURE_QUANTA.SOCKET4677_AZIF0045P001C01CS(CHIPS)':
 'VSS1270': CDS_PINID='VSS1270';
NODE_NAME     U2 EA21
 '@S9S_MB_2U_LIB.S9S_MB_2U(SCH_1):PAGE39_I9@PURE_QUANTA.SOCKET4677_AZIF0045P001C01CS(CHIPS)':
 'VSS1274': CDS_PINID='VSS1274';
NODE_NAME     U2 EA27
 '@S9S_MB_2U_LIB.S9S_MB_2U(SCH_1):PAGE39_I9@PURE_QUANTA.SOCKET4677_AZIF0045P001C01CS(CHIPS)':
 'VSS1275': CDS_PINID='VSS1275';
NODE_NAME     U2 EF73
 '@S9S_MB_2U_LIB.S9S_MB_2U(SCH_1):PAGE39_I9@PURE_QUANTA.SOCKET4677_AZIF0045P001C01CS(CHIPS)':
 'VSS1276': CDS_PINID='VSS1276';
NODE_NAME     U2 EF75
 '@S9S_MB_2U_LIB.S9S_MB_2U(SCH_1):PAGE39_I9@PURE_QUANTA.SOCKET4677_AZIF0045P001C01CS(CHIPS)':
 'VSS1277': CDS_PINID='VSS1277';
NODE_NAME     U2 EA33
 '@S9S_MB_2U_LIB.S9S_MB_2U(SCH_1):PAGE39_I9@PURE_QUANTA.SOCKET4677_AZIF0045P001C01CS(CHIPS)':
 'VSS1278': CDS_PINID='VSS1278';
NODE_NAME     U2 EA70
 '@S9S_MB_2U_LIB.S9S_MB_2U(SCH_1):PAGE39_I9@PURE_QUANTA.SOCKET4677_AZIF0045P001C01CS(CHIPS)':
 'VSS1279': CDS_PINID='VSS1279';
NODE_NAME     U2 EA76
 '@S9S_MB_2U_LIB.S9S_MB_2U(SCH_1):PAGE39_I9@PURE_QUANTA.SOCKET4677_AZIF0045P001C01CS(CHIPS)':
 'VSS1280': CDS_PINID='VSS1280';
NODE_NAME     U2 EA78
 '@S9S_MB_2U_LIB.S9S_MB_2U(SCH_1):PAGE39_I9@PURE_QUANTA.SOCKET4677_AZIF0045P001C01CS(CHIPS)':
 'VSS1281': CDS_PINID='VSS1281';
NODE_NAME     U2 EA80
 '@S9S_MB_2U_LIB.S9S_MB_2U(SCH_1):PAGE39_I9@PURE_QUANTA.SOCKET4677_AZIF0045P001C01CS(CHIPS)':
 'VSS1282': CDS_PINID='VSS1282';
NODE_NAME     U2 EF89
 '@S9S_MB_2U_LIB.S9S_MB_2U(SCH_1):PAGE39_I9@PURE_QUANTA.SOCKET4677_AZIF0045P001C01CS(CHIPS)':
 'VSS1283': CDS_PINID='VSS1283';
NODE_NAME     U2 EG13
 '@S9S_MB_2U_LIB.S9S_MB_2U(SCH_1):PAGE39_I9@PURE_QUANTA.SOCKET4677_AZIF0045P001C01CS(CHIPS)':
 'VSS1284': CDS_PINID='VSS1284';
NODE_NAME     U2 EA84
 '@S9S_MB_2U_LIB.S9S_MB_2U(SCH_1):PAGE39_I9@PURE_QUANTA.SOCKET4677_AZIF0045P001C01CS(CHIPS)':
 'VSS1285': CDS_PINID='VSS1285';
NODE_NAME     U2 EA88
 '@S9S_MB_2U_LIB.S9S_MB_2U(SCH_1):PAGE39_I9@PURE_QUANTA.SOCKET4677_AZIF0045P001C01CS(CHIPS)':
 'VSS1286': CDS_PINID='VSS1286';
NODE_NAME     U2 EB12
 '@S9S_MB_2U_LIB.S9S_MB_2U(SCH_1):PAGE39_I9@PURE_QUANTA.SOCKET4677_AZIF0045P001C01CS(CHIPS)':
 'VSS1287': CDS_PINID='VSS1287';
NODE_NAME     U2 EB22
 '@S9S_MB_2U_LIB.S9S_MB_2U(SCH_1):PAGE39_I9@PURE_QUANTA.SOCKET4677_AZIF0045P001C01CS(CHIPS)':
 'VSS1288': CDS_PINID='VSS1288';
NODE_NAME     U2 EB28
 '@S9S_MB_2U_LIB.S9S_MB_2U(SCH_1):PAGE39_I9@PURE_QUANTA.SOCKET4677_AZIF0045P001C01CS(CHIPS)':
 'VSS1289': CDS_PINID='VSS1289';
NODE_NAME     U2 EG5
 '@S9S_MB_2U_LIB.S9S_MB_2U(SCH_1):PAGE39_I9@PURE_QUANTA.SOCKET4677_AZIF0045P001C01CS(CHIPS)':
 'VSS1290': CDS_PINID='VSS1290';
NODE_NAME     U2 EG52
 '@S9S_MB_2U_LIB.S9S_MB_2U(SCH_1):PAGE39_I9@PURE_QUANTA.SOCKET4677_AZIF0045P001C01CS(CHIPS)':
 'VSS1291': CDS_PINID='VSS1291';
NODE_NAME     U2 EB32
 '@S9S_MB_2U_LIB.S9S_MB_2U(SCH_1):PAGE39_I9@PURE_QUANTA.SOCKET4677_AZIF0045P001C01CS(CHIPS)':
 'VSS1292': CDS_PINID='VSS1292';
NODE_NAME     U2 EB38
 '@S9S_MB_2U_LIB.S9S_MB_2U(SCH_1):PAGE39_I9@PURE_QUANTA.SOCKET4677_AZIF0045P001C01CS(CHIPS)':
 'VSS1293': CDS_PINID='VSS1293';
NODE_NAME     U2 EG7
 '@S9S_MB_2U_LIB.S9S_MB_2U(SCH_1):PAGE39_I9@PURE_QUANTA.SOCKET4677_AZIF0045P001C01CS(CHIPS)':
 'VSS1294': CDS_PINID='VSS1294';
NODE_NAME     U2 EB40
 '@S9S_MB_2U_LIB.S9S_MB_2U(SCH_1):PAGE39_I9@PURE_QUANTA.SOCKET4677_AZIF0045P001C01CS(CHIPS)':
 'VSS1295': CDS_PINID='VSS1295';
NODE_NAME     U2 EB47
 '@S9S_MB_2U_LIB.S9S_MB_2U(SCH_1):PAGE39_I9@PURE_QUANTA.SOCKET4677_AZIF0045P001C01CS(CHIPS)':
 'VSS1296': CDS_PINID='VSS1296';
NODE_NAME     U2 EB57
 '@S9S_MB_2U_LIB.S9S_MB_2U(SCH_1):PAGE39_I9@PURE_QUANTA.SOCKET4677_AZIF0045P001C01CS(CHIPS)':
 'VSS1297': CDS_PINID='VSS1297';
NODE_NAME     U2 EB65
 '@S9S_MB_2U_LIB.S9S_MB_2U(SCH_1):PAGE39_I9@PURE_QUANTA.SOCKET4677_AZIF0045P001C01CS(CHIPS)':
 'VSS1298': CDS_PINID='VSS1298';
NODE_NAME     U2 EB69
 '@S9S_MB_2U_LIB.S9S_MB_2U(SCH_1):PAGE39_I9@PURE_QUANTA.SOCKET4677_AZIF0045P001C01CS(CHIPS)':
 'VSS1299': CDS_PINID='VSS1299';
NODE_NAME     U2 EB71
 '@S9S_MB_2U_LIB.S9S_MB_2U(SCH_1):PAGE39_I9@PURE_QUANTA.SOCKET4677_AZIF0045P001C01CS(CHIPS)':
 'VSS1300': CDS_PINID='VSS1300';
NODE_NAME     U2 EB75
 '@S9S_MB_2U_LIB.S9S_MB_2U(SCH_1):PAGE39_I9@PURE_QUANTA.SOCKET4677_AZIF0045P001C01CS(CHIPS)':
 'VSS1301': CDS_PINID='VSS1301';
NODE_NAME     U2 EH12
 '@S9S_MB_2U_LIB.S9S_MB_2U(SCH_1):PAGE39_I9@PURE_QUANTA.SOCKET4677_AZIF0045P001C01CS(CHIPS)':
 'VSS1302': CDS_PINID='VSS1302';
NODE_NAME     U2 EH14
 '@S9S_MB_2U_LIB.S9S_MB_2U(SCH_1):PAGE39_I9@PURE_QUANTA.SOCKET4677_AZIF0045P001C01CS(CHIPS)':
 'VSS1303': CDS_PINID='VSS1303';
NODE_NAME     U2 EB79
 '@S9S_MB_2U_LIB.S9S_MB_2U(SCH_1):PAGE39_I9@PURE_QUANTA.SOCKET4677_AZIF0045P001C01CS(CHIPS)':
 'VSS1304': CDS_PINID='VSS1304';
NODE_NAME     U2 EH18
 '@S9S_MB_2U_LIB.S9S_MB_2U(SCH_1):PAGE39_I9@PURE_QUANTA.SOCKET4677_AZIF0045P001C01CS(CHIPS)':
 'VSS1305': CDS_PINID='VSS1305';
NODE_NAME     U2 EB8
 '@S9S_MB_2U_LIB.S9S_MB_2U(SCH_1):PAGE39_I9@PURE_QUANTA.SOCKET4677_AZIF0045P001C01CS(CHIPS)':
 'VSS1306': CDS_PINID='VSS1306';
NODE_NAME     U2 EB83
 '@S9S_MB_2U_LIB.S9S_MB_2U(SCH_1):PAGE39_I9@PURE_QUANTA.SOCKET4677_AZIF0045P001C01CS(CHIPS)':
 'VSS1307': CDS_PINID='VSS1307';
NODE_NAME     U2 EB87
 '@S9S_MB_2U_LIB.S9S_MB_2U(SCH_1):PAGE39_I9@PURE_QUANTA.SOCKET4677_AZIF0045P001C01CS(CHIPS)':
 'VSS1308': CDS_PINID='VSS1308';
NODE_NAME     U2 EC1
 '@S9S_MB_2U_LIB.S9S_MB_2U(SCH_1):PAGE39_I9@PURE_QUANTA.SOCKET4677_AZIF0045P001C01CS(CHIPS)':
 'VSS1309': CDS_PINID='VSS1309';
NODE_NAME     U2 EC13
 '@S9S_MB_2U_LIB.S9S_MB_2U(SCH_1):PAGE39_I9@PURE_QUANTA.SOCKET4677_AZIF0045P001C01CS(CHIPS)':
 'VSS1310': CDS_PINID='VSS1310';
NODE_NAME     U2 EC19
 '@S9S_MB_2U_LIB.S9S_MB_2U(SCH_1):PAGE39_I9@PURE_QUANTA.SOCKET4677_AZIF0045P001C01CS(CHIPS)':
 'VSS1311': CDS_PINID='VSS1311';
NODE_NAME     U2 EC23
 '@S9S_MB_2U_LIB.S9S_MB_2U(SCH_1):PAGE39_I9@PURE_QUANTA.SOCKET4677_AZIF0045P001C01CS(CHIPS)':
 'VSS1313': CDS_PINID='VSS1313';
NODE_NAME     U2 EC29
 '@S9S_MB_2U_LIB.S9S_MB_2U(SCH_1):PAGE39_I9@PURE_QUANTA.SOCKET4677_AZIF0045P001C01CS(CHIPS)':
 'VSS1314': CDS_PINID='VSS1314';
NODE_NAME     U2 EC31
 '@S9S_MB_2U_LIB.S9S_MB_2U(SCH_1):PAGE39_I9@PURE_QUANTA.SOCKET4677_AZIF0045P001C01CS(CHIPS)':
 'VSS1316': CDS_PINID='VSS1316';
NODE_NAME     U2 EC37
 '@S9S_MB_2U_LIB.S9S_MB_2U(SCH_1):PAGE39_I9@PURE_QUANTA.SOCKET4677_AZIF0045P001C01CS(CHIPS)':
 'VSS1317': CDS_PINID='VSS1317';
NODE_NAME     U2 EH6
 '@S9S_MB_2U_LIB.S9S_MB_2U(SCH_1):PAGE39_I9@PURE_QUANTA.SOCKET4677_AZIF0045P001C01CS(CHIPS)':
 'VSS1318': CDS_PINID='VSS1318';
NODE_NAME     U2 EC41
 '@S9S_MB_2U_LIB.S9S_MB_2U(SCH_1):PAGE39_I9@PURE_QUANTA.SOCKET4677_AZIF0045P001C01CS(CHIPS)':
 'VSS1321': CDS_PINID='VSS1321';
NODE_NAME     U2 EC43
 '@S9S_MB_2U_LIB.S9S_MB_2U(SCH_1):PAGE39_I9@PURE_QUANTA.SOCKET4677_AZIF0045P001C01CS(CHIPS)':
 'VSS1323': CDS_PINID='VSS1323';
NODE_NAME     U2 EC48
 '@S9S_MB_2U_LIB.S9S_MB_2U(SCH_1):PAGE39_I9@PURE_QUANTA.SOCKET4677_AZIF0045P001C01CS(CHIPS)':
 'VSS1324': CDS_PINID='VSS1324';
NODE_NAME     U2 EC50
 '@S9S_MB_2U_LIB.S9S_MB_2U(SCH_1):PAGE39_I9@PURE_QUANTA.SOCKET4677_AZIF0045P001C01CS(CHIPS)':
 'VSS1326': CDS_PINID='VSS1326';
NODE_NAME     U2 EC56
 '@S9S_MB_2U_LIB.S9S_MB_2U(SCH_1):PAGE39_I9@PURE_QUANTA.SOCKET4677_AZIF0045P001C01CS(CHIPS)':
 'VSS1327': CDS_PINID='VSS1327';
NODE_NAME     U2 EC66
 '@S9S_MB_2U_LIB.S9S_MB_2U(SCH_1):PAGE39_I9@PURE_QUANTA.SOCKET4677_AZIF0045P001C01CS(CHIPS)':
 'VSS1329': CDS_PINID='VSS1329';
NODE_NAME     U2 EC72
 '@S9S_MB_2U_LIB.S9S_MB_2U(SCH_1):PAGE39_I9@PURE_QUANTA.SOCKET4677_AZIF0045P001C01CS(CHIPS)':
 'VSS1330': CDS_PINID='VSS1330';
NODE_NAME     U2 EC74
 '@S9S_MB_2U_LIB.S9S_MB_2U(SCH_1):PAGE39_I9@PURE_QUANTA.SOCKET4677_AZIF0045P001C01CS(CHIPS)':
 'VSS1332': CDS_PINID='VSS1332';
NODE_NAME     U2 EC82
 '@S9S_MB_2U_LIB.S9S_MB_2U(SCH_1):PAGE39_I9@PURE_QUANTA.SOCKET4677_AZIF0045P001C01CS(CHIPS)':
 'VSS1333': CDS_PINID='VSS1333';
NODE_NAME     U2 EC84
 '@S9S_MB_2U_LIB.S9S_MB_2U(SCH_1):PAGE39_I9@PURE_QUANTA.SOCKET4677_AZIF0045P001C01CS(CHIPS)':
 'VSS1335': CDS_PINID='VSS1335';
NODE_NAME     U2 EC88
 '@S9S_MB_2U_LIB.S9S_MB_2U(SCH_1):PAGE39_I9@PURE_QUANTA.SOCKET4677_AZIF0045P001C01CS(CHIPS)':
 'VSS1336': CDS_PINID='VSS1336';
NODE_NAME     U2 EC9
 '@S9S_MB_2U_LIB.S9S_MB_2U(SCH_1):PAGE39_I9@PURE_QUANTA.SOCKET4677_AZIF0045P001C01CS(CHIPS)':
 'VSS1337': CDS_PINID='VSS1337';
NODE_NAME     U2 ED16
 '@S9S_MB_2U_LIB.S9S_MB_2U(SCH_1):PAGE39_I9@PURE_QUANTA.SOCKET4677_AZIF0045P001C01CS(CHIPS)':
 'VSS1338': CDS_PINID='VSS1338';
NODE_NAME     U2 ED24
 '@S9S_MB_2U_LIB.S9S_MB_2U(SCH_1):PAGE39_I9@PURE_QUANTA.SOCKET4677_AZIF0045P001C01CS(CHIPS)':
 'VSS1339': CDS_PINID='VSS1339';
NODE_NAME     U2 ED30
 '@S9S_MB_2U_LIB.S9S_MB_2U(SCH_1):PAGE39_I9@PURE_QUANTA.SOCKET4677_AZIF0045P001C01CS(CHIPS)':
 'VSS1341': CDS_PINID='VSS1341';
NODE_NAME     U2 ED36
 '@S9S_MB_2U_LIB.S9S_MB_2U(SCH_1):PAGE39_I9@PURE_QUANTA.SOCKET4677_AZIF0045P001C01CS(CHIPS)':
 'VSS1342': CDS_PINID='VSS1342';
NODE_NAME     U2 ED4
 '@S9S_MB_2U_LIB.S9S_MB_2U(SCH_1):PAGE39_I9@PURE_QUANTA.SOCKET4677_AZIF0045P001C01CS(CHIPS)':
 'VSS1344': CDS_PINID='VSS1344';
NODE_NAME     U2 ED49
 '@S9S_MB_2U_LIB.S9S_MB_2U(SCH_1):PAGE39_I9@PURE_QUANTA.SOCKET4677_AZIF0045P001C01CS(CHIPS)':
 'VSS1346': CDS_PINID='VSS1346';
NODE_NAME     U2 ED8
 '@S9S_MB_2U_LIB.S9S_MB_2U(SCH_1):PAGE39_I9@PURE_QUANTA.SOCKET4677_AZIF0045P001C01CS(CHIPS)':
 'VSS1348': CDS_PINID='VSS1348';
NODE_NAME     U2 EE78
 '@S9S_MB_2U_LIB.S9S_MB_2U(SCH_1):PAGE39_I9@PURE_QUANTA.SOCKET4677_AZIF0045P001C01CS(CHIPS)':
 'VSS1349': CDS_PINID='VSS1349';
NODE_NAME     U2 EE80
 '@S9S_MB_2U_LIB.S9S_MB_2U(SCH_1):PAGE39_I9@PURE_QUANTA.SOCKET4677_AZIF0045P001C01CS(CHIPS)':
 'VSS1350': CDS_PINID='VSS1350';
NODE_NAME     U2 EE88
 '@S9S_MB_2U_LIB.S9S_MB_2U(SCH_1):PAGE39_I9@PURE_QUANTA.SOCKET4677_AZIF0045P001C01CS(CHIPS)':
 'VSS1351': CDS_PINID='VSS1351';
NODE_NAME     U2 EF12
 '@S9S_MB_2U_LIB.S9S_MB_2U(SCH_1):PAGE39_I9@PURE_QUANTA.SOCKET4677_AZIF0045P001C01CS(CHIPS)':
 'VSS1352': CDS_PINID='VSS1352';
NODE_NAME     U2 EF16
 '@S9S_MB_2U_LIB.S9S_MB_2U(SCH_1):PAGE39_I9@PURE_QUANTA.SOCKET4677_AZIF0045P001C01CS(CHIPS)':
 'VSS1353': CDS_PINID='VSS1353';
NODE_NAME     U2 EF18
 '@S9S_MB_2U_LIB.S9S_MB_2U(SCH_1):PAGE39_I9@PURE_QUANTA.SOCKET4677_AZIF0045P001C01CS(CHIPS)':
 'VSS1354': CDS_PINID='VSS1354';
NODE_NAME     U2 EF2
 '@S9S_MB_2U_LIB.S9S_MB_2U(SCH_1):PAGE39_I9@PURE_QUANTA.SOCKET4677_AZIF0045P001C01CS(CHIPS)':
 'VSS1356': CDS_PINID='VSS1356';
NODE_NAME     U2 EF20
 '@S9S_MB_2U_LIB.S9S_MB_2U(SCH_1):PAGE39_I9@PURE_QUANTA.SOCKET4677_AZIF0045P001C01CS(CHIPS)':
 'VSS1358': CDS_PINID='VSS1358';
NODE_NAME     U2 EF22
 '@S9S_MB_2U_LIB.S9S_MB_2U(SCH_1):PAGE39_I9@PURE_QUANTA.SOCKET4677_AZIF0045P001C01CS(CHIPS)':
 'VSS1360': CDS_PINID='VSS1360';
NODE_NAME     U2 EF24
 '@S9S_MB_2U_LIB.S9S_MB_2U(SCH_1):PAGE39_I9@PURE_QUANTA.SOCKET4677_AZIF0045P001C01CS(CHIPS)':
 'VSS1361': CDS_PINID='VSS1361';
NODE_NAME     U2 EF26
 '@S9S_MB_2U_LIB.S9S_MB_2U(SCH_1):PAGE39_I9@PURE_QUANTA.SOCKET4677_AZIF0045P001C01CS(CHIPS)':
 'VSS1362': CDS_PINID='VSS1362';
NODE_NAME     U2 EF28
 '@S9S_MB_2U_LIB.S9S_MB_2U(SCH_1):PAGE39_I9@PURE_QUANTA.SOCKET4677_AZIF0045P001C01CS(CHIPS)':
 'VSS1363': CDS_PINID='VSS1363';
NODE_NAME     U2 EF30
 '@S9S_MB_2U_LIB.S9S_MB_2U(SCH_1):PAGE39_I9@PURE_QUANTA.SOCKET4677_AZIF0045P001C01CS(CHIPS)':
 'VSS1364': CDS_PINID='VSS1364';
NODE_NAME     U2 EF32
 '@S9S_MB_2U_LIB.S9S_MB_2U(SCH_1):PAGE39_I9@PURE_QUANTA.SOCKET4677_AZIF0045P001C01CS(CHIPS)':
 'VSS1365': CDS_PINID='VSS1365';
NODE_NAME     U2 EF34
 '@S9S_MB_2U_LIB.S9S_MB_2U(SCH_1):PAGE39_I9@PURE_QUANTA.SOCKET4677_AZIF0045P001C01CS(CHIPS)':
 'VSS1367': CDS_PINID='VSS1367';
NODE_NAME     U2 EF36
 '@S9S_MB_2U_LIB.S9S_MB_2U(SCH_1):PAGE39_I9@PURE_QUANTA.SOCKET4677_AZIF0045P001C01CS(CHIPS)':
 'VSS1370': CDS_PINID='VSS1370';
NODE_NAME     U2 EF38
 '@S9S_MB_2U_LIB.S9S_MB_2U(SCH_1):PAGE39_I9@PURE_QUANTA.SOCKET4677_AZIF0045P001C01CS(CHIPS)':
 'VSS1373': CDS_PINID='VSS1373';
NODE_NAME     U2 EF4
 '@S9S_MB_2U_LIB.S9S_MB_2U(SCH_1):PAGE39_I9@PURE_QUANTA.SOCKET4677_AZIF0045P001C01CS(CHIPS)':
 'VSS1374': CDS_PINID='VSS1374';
NODE_NAME     U2 EF40
 '@S9S_MB_2U_LIB.S9S_MB_2U(SCH_1):PAGE39_I9@PURE_QUANTA.SOCKET4677_AZIF0045P001C01CS(CHIPS)':
 'VSS1376': CDS_PINID='VSS1376';
NODE_NAME     U2 EF42
 '@S9S_MB_2U_LIB.S9S_MB_2U(SCH_1):PAGE39_I9@PURE_QUANTA.SOCKET4677_AZIF0045P001C01CS(CHIPS)':
 'VSS1382': CDS_PINID='VSS1382';
NODE_NAME     U2 EF44
 '@S9S_MB_2U_LIB.S9S_MB_2U(SCH_1):PAGE39_I9@PURE_QUANTA.SOCKET4677_AZIF0045P001C01CS(CHIPS)':
 'VSS1383': CDS_PINID='VSS1383';
NODE_NAME     U2 EF47
 '@S9S_MB_2U_LIB.S9S_MB_2U(SCH_1):PAGE39_I9@PURE_QUANTA.SOCKET4677_AZIF0045P001C01CS(CHIPS)':
 'VSS1384': CDS_PINID='VSS1384';
NODE_NAME     U2 EF49
 '@S9S_MB_2U_LIB.S9S_MB_2U(SCH_1):PAGE39_I9@PURE_QUANTA.SOCKET4677_AZIF0045P001C01CS(CHIPS)':
 'VSS1385': CDS_PINID='VSS1385';
NODE_NAME     U2 EF53
 '@S9S_MB_2U_LIB.S9S_MB_2U(SCH_1):PAGE39_I9@PURE_QUANTA.SOCKET4677_AZIF0045P001C01CS(CHIPS)':
 'VSS1386': CDS_PINID='VSS1386';
NODE_NAME     U2 EF55
 '@S9S_MB_2U_LIB.S9S_MB_2U(SCH_1):PAGE39_I9@PURE_QUANTA.SOCKET4677_AZIF0045P001C01CS(CHIPS)':
 'VSS1387': CDS_PINID='VSS1387';
NODE_NAME     U2 EF57
 '@S9S_MB_2U_LIB.S9S_MB_2U(SCH_1):PAGE39_I9@PURE_QUANTA.SOCKET4677_AZIF0045P001C01CS(CHIPS)':
 'VSS1388': CDS_PINID='VSS1388';
NODE_NAME     U2 EF59
 '@S9S_MB_2U_LIB.S9S_MB_2U(SCH_1):PAGE39_I9@PURE_QUANTA.SOCKET4677_AZIF0045P001C01CS(CHIPS)':
 'VSS1389': CDS_PINID='VSS1389';
NODE_NAME     U2 EF61
 '@S9S_MB_2U_LIB.S9S_MB_2U(SCH_1):PAGE39_I9@PURE_QUANTA.SOCKET4677_AZIF0045P001C01CS(CHIPS)':
 'VSS1390': CDS_PINID='VSS1390';
NODE_NAME     U2 EF63
 '@S9S_MB_2U_LIB.S9S_MB_2U(SCH_1):PAGE39_I9@PURE_QUANTA.SOCKET4677_AZIF0045P001C01CS(CHIPS)':
 'VSS1392': CDS_PINID='VSS1392';
NODE_NAME     U2 EF65
 '@S9S_MB_2U_LIB.S9S_MB_2U(SCH_1):PAGE39_I9@PURE_QUANTA.SOCKET4677_AZIF0045P001C01CS(CHIPS)':
 'VSS1393': CDS_PINID='VSS1393';
NODE_NAME     U2 EF67
 '@S9S_MB_2U_LIB.S9S_MB_2U(SCH_1):PAGE39_I9@PURE_QUANTA.SOCKET4677_AZIF0045P001C01CS(CHIPS)':
 'VSS1395': CDS_PINID='VSS1395';
NODE_NAME     U2 EF69
 '@S9S_MB_2U_LIB.S9S_MB_2U(SCH_1):PAGE39_I9@PURE_QUANTA.SOCKET4677_AZIF0045P001C01CS(CHIPS)':
 'VSS1399': CDS_PINID='VSS1399';
NODE_NAME     U2 EF71
 '@S9S_MB_2U_LIB.S9S_MB_2U(SCH_1):PAGE39_I9@PURE_QUANTA.SOCKET4677_AZIF0045P001C01CS(CHIPS)':
 'VSS1402': CDS_PINID='VSS1402';
NODE_NAME     U2 EF77
 '@S9S_MB_2U_LIB.S9S_MB_2U(SCH_1):PAGE39_I9@PURE_QUANTA.SOCKET4677_AZIF0045P001C01CS(CHIPS)':
 'VSS1403': CDS_PINID='VSS1403';
NODE_NAME     U2 EF8
 '@S9S_MB_2U_LIB.S9S_MB_2U(SCH_1):PAGE39_I9@PURE_QUANTA.SOCKET4677_AZIF0045P001C01CS(CHIPS)':
 'VSS1404': CDS_PINID='VSS1404';
NODE_NAME     U2 EF85
 '@S9S_MB_2U_LIB.S9S_MB_2U(SCH_1):PAGE39_I9@PURE_QUANTA.SOCKET4677_AZIF0045P001C01CS(CHIPS)':
 'VSS1406': CDS_PINID='VSS1406';
NODE_NAME     U2 EF87
 '@S9S_MB_2U_LIB.S9S_MB_2U(SCH_1):PAGE39_I9@PURE_QUANTA.SOCKET4677_AZIF0045P001C01CS(CHIPS)':
 'VSS1407': CDS_PINID='VSS1407';
NODE_NAME     U2 EG39
 '@S9S_MB_2U_LIB.S9S_MB_2U(SCH_1):PAGE39_I9@PURE_QUANTA.SOCKET4677_AZIF0045P001C01CS(CHIPS)':
 'VSS1408': CDS_PINID='VSS1408';
NODE_NAME     U2 EG82
 '@S9S_MB_2U_LIB.S9S_MB_2U(SCH_1):PAGE39_I9@PURE_QUANTA.SOCKET4677_AZIF0045P001C01CS(CHIPS)':
 'VSS1410': CDS_PINID='VSS1410';
NODE_NAME     U2 EG84
 '@S9S_MB_2U_LIB.S9S_MB_2U(SCH_1):PAGE39_I9@PURE_QUANTA.SOCKET4677_AZIF0045P001C01CS(CHIPS)':
 'VSS1411': CDS_PINID='VSS1411';
NODE_NAME     U2 EG86
 '@S9S_MB_2U_LIB.S9S_MB_2U(SCH_1):PAGE39_I9@PURE_QUANTA.SOCKET4677_AZIF0045P001C01CS(CHIPS)':
 'VSS1412': CDS_PINID='VSS1412';
NODE_NAME     U2 EG88
 '@S9S_MB_2U_LIB.S9S_MB_2U(SCH_1):PAGE39_I9@PURE_QUANTA.SOCKET4677_AZIF0045P001C01CS(CHIPS)':
 'VSS1413': CDS_PINID='VSS1413';
NODE_NAME     U2 EG9
 '@S9S_MB_2U_LIB.S9S_MB_2U(SCH_1):PAGE39_I9@PURE_QUANTA.SOCKET4677_AZIF0045P001C01CS(CHIPS)':
 'VSS1414': CDS_PINID='VSS1414';
NODE_NAME     U2 EG90
 '@S9S_MB_2U_LIB.S9S_MB_2U(SCH_1):PAGE39_I9@PURE_QUANTA.SOCKET4677_AZIF0045P001C01CS(CHIPS)':
 'VSS1415': CDS_PINID='VSS1415';
NODE_NAME     U2 EH16
 '@S9S_MB_2U_LIB.S9S_MB_2U(SCH_1):PAGE39_I9@PURE_QUANTA.SOCKET4677_AZIF0045P001C01CS(CHIPS)':
 'VSS1416': CDS_PINID='VSS1416';
NODE_NAME     U2 EH24
 '@S9S_MB_2U_LIB.S9S_MB_2U(SCH_1):PAGE39_I9@PURE_QUANTA.SOCKET4677_AZIF0045P001C01CS(CHIPS)':
 'VSS1417': CDS_PINID='VSS1417';
NODE_NAME     U2 EH30
 '@S9S_MB_2U_LIB.S9S_MB_2U(SCH_1):PAGE39_I9@PURE_QUANTA.SOCKET4677_AZIF0045P001C01CS(CHIPS)':
 'VSS1418': CDS_PINID='VSS1418';
NODE_NAME     U2 EH4
 '@S9S_MB_2U_LIB.S9S_MB_2U(SCH_1):PAGE39_I9@PURE_QUANTA.SOCKET4677_AZIF0045P001C01CS(CHIPS)':
 'VSS1420': CDS_PINID='VSS1420';
NODE_NAME     U2 DM51
 '@S9S_MB_2U_LIB.S9S_MB_2U(SCH_1):PAGE39_I10@PURE_QUANTA.SOCKET4677_AZIF0045P001C01CS(CHIPS)':
 'VSS934': CDS_PINID='VSS934';
NODE_NAME     U2 DM73
 '@S9S_MB_2U_LIB.S9S_MB_2U(SCH_1):PAGE39_I10@PURE_QUANTA.SOCKET4677_AZIF0045P001C01CS(CHIPS)':
 'VSS945': CDS_PINID='VSS945';
NODE_NAME     U2 DN17
 '@S9S_MB_2U_LIB.S9S_MB_2U(SCH_1):PAGE39_I10@PURE_QUANTA.SOCKET4677_AZIF0045P001C01CS(CHIPS)':
 'VSS955': CDS_PINID='VSS955';
NODE_NAME     U2 DN39
 '@S9S_MB_2U_LIB.S9S_MB_2U(SCH_1):PAGE39_I10@PURE_QUANTA.SOCKET4677_AZIF0045P001C01CS(CHIPS)':
 'VSS957': CDS_PINID='VSS957';
NODE_NAME     U2 DN52
 '@S9S_MB_2U_LIB.S9S_MB_2U(SCH_1):PAGE39_I10@PURE_QUANTA.SOCKET4677_AZIF0045P001C01CS(CHIPS)':
 'VSS959': CDS_PINID='VSS959';
NODE_NAME     U2 DP12
 '@S9S_MB_2U_LIB.S9S_MB_2U(SCH_1):PAGE39_I10@PURE_QUANTA.SOCKET4677_AZIF0045P001C01CS(CHIPS)':
 'VSS966': CDS_PINID='VSS966';
NODE_NAME     U2 DP18
 '@S9S_MB_2U_LIB.S9S_MB_2U(SCH_1):PAGE39_I10@PURE_QUANTA.SOCKET4677_AZIF0045P001C01CS(CHIPS)':
 'VSS968': CDS_PINID='VSS968';
NODE_NAME     U2 DP24
 '@S9S_MB_2U_LIB.S9S_MB_2U(SCH_1):PAGE39_I10@PURE_QUANTA.SOCKET4677_AZIF0045P001C01CS(CHIPS)':
 'VSS969': CDS_PINID='VSS969';
NODE_NAME     U2 DP42
 '@S9S_MB_2U_LIB.S9S_MB_2U(SCH_1):PAGE39_I10@PURE_QUANTA.SOCKET4677_AZIF0045P001C01CS(CHIPS)':
 'VSS973': CDS_PINID='VSS973';
NODE_NAME     U2 DP55
 '@S9S_MB_2U_LIB.S9S_MB_2U(SCH_1):PAGE39_I10@PURE_QUANTA.SOCKET4677_AZIF0045P001C01CS(CHIPS)':
 'VSS976': CDS_PINID='VSS976';
NODE_NAME     U2 DP61
 '@S9S_MB_2U_LIB.S9S_MB_2U(SCH_1):PAGE39_I10@PURE_QUANTA.SOCKET4677_AZIF0045P001C01CS(CHIPS)':
 'VSS979': CDS_PINID='VSS979';
NODE_NAME     U2 DP67
 '@S9S_MB_2U_LIB.S9S_MB_2U(SCH_1):PAGE39_I10@PURE_QUANTA.SOCKET4677_AZIF0045P001C01CS(CHIPS)':
 'VSS980': CDS_PINID='VSS980';
NODE_NAME     U2 DP91
 '@S9S_MB_2U_LIB.S9S_MB_2U(SCH_1):PAGE39_I10@PURE_QUANTA.SOCKET4677_AZIF0045P001C01CS(CHIPS)':
 'VSS985': CDS_PINID='VSS985';
NODE_NAME     U2 DR25
 '@S9S_MB_2U_LIB.S9S_MB_2U(SCH_1):PAGE39_I10@PURE_QUANTA.SOCKET4677_AZIF0045P001C01CS(CHIPS)':
 'VSS990': CDS_PINID='VSS990';
NODE_NAME     U2 DR35
 '@S9S_MB_2U_LIB.S9S_MB_2U(SCH_1):PAGE39_I10@PURE_QUANTA.SOCKET4677_AZIF0045P001C01CS(CHIPS)':
 'VSS993': CDS_PINID='VSS993';
NODE_NAME     U2 DR5
 '@S9S_MB_2U_LIB.S9S_MB_2U(SCH_1):PAGE39_I10@PURE_QUANTA.SOCKET4677_AZIF0045P001C01CS(CHIPS)':
 'VSS998': CDS_PINID='VSS998';
NODE_NAME     U2 DR54
 '@S9S_MB_2U_LIB.S9S_MB_2U(SCH_1):PAGE39_I10@PURE_QUANTA.SOCKET4677_AZIF0045P001C01CS(CHIPS)':
 'VSS1000': CDS_PINID='VSS1000';
NODE_NAME     U2 DR60
 '@S9S_MB_2U_LIB.S9S_MB_2U(SCH_1):PAGE39_I10@PURE_QUANTA.SOCKET4677_AZIF0045P001C01CS(CHIPS)':
 'VSS1002': CDS_PINID='VSS1002';
NODE_NAME     U2 DR62
 '@S9S_MB_2U_LIB.S9S_MB_2U(SCH_1):PAGE39_I10@PURE_QUANTA.SOCKET4677_AZIF0045P001C01CS(CHIPS)':
 'VSS1003': CDS_PINID='VSS1003';
NODE_NAME     U2 DR68
 '@S9S_MB_2U_LIB.S9S_MB_2U(SCH_1):PAGE39_I10@PURE_QUANTA.SOCKET4677_AZIF0045P001C01CS(CHIPS)':
 'VSS1005': CDS_PINID='VSS1005';
NODE_NAME     U2 DR72
 '@S9S_MB_2U_LIB.S9S_MB_2U(SCH_1):PAGE39_I10@PURE_QUANTA.SOCKET4677_AZIF0045P001C01CS(CHIPS)':
 'VSS1006': CDS_PINID='VSS1006';
NODE_NAME     U2 DT16
 '@S9S_MB_2U_LIB.S9S_MB_2U(SCH_1):PAGE39_I10@PURE_QUANTA.SOCKET4677_AZIF0045P001C01CS(CHIPS)':
 'VSS1013': CDS_PINID='VSS1013';
NODE_NAME     U2 DT20
 '@S9S_MB_2U_LIB.S9S_MB_2U(SCH_1):PAGE39_I10@PURE_QUANTA.SOCKET4677_AZIF0045P001C01CS(CHIPS)':
 'VSS1014': CDS_PINID='VSS1014';
NODE_NAME     U2 DT26
 '@S9S_MB_2U_LIB.S9S_MB_2U(SCH_1):PAGE39_I10@PURE_QUANTA.SOCKET4677_AZIF0045P001C01CS(CHIPS)':
 'VSS1016': CDS_PINID='VSS1016';
NODE_NAME     U2 DT4
 '@S9S_MB_2U_LIB.S9S_MB_2U(SCH_1):PAGE39_I10@PURE_QUANTA.SOCKET4677_AZIF0045P001C01CS(CHIPS)':
 'VSS1021': CDS_PINID='VSS1021';
NODE_NAME     U2 DT44
 '@S9S_MB_2U_LIB.S9S_MB_2U(SCH_1):PAGE39_I10@PURE_QUANTA.SOCKET4677_AZIF0045P001C01CS(CHIPS)':
 'VSS1023': CDS_PINID='VSS1023';
NODE_NAME     U2 DT51
 '@S9S_MB_2U_LIB.S9S_MB_2U(SCH_1):PAGE39_I10@PURE_QUANTA.SOCKET4677_AZIF0045P001C01CS(CHIPS)':
 'VSS1025': CDS_PINID='VSS1025';
NODE_NAME     U2 DT53
 '@S9S_MB_2U_LIB.S9S_MB_2U(SCH_1):PAGE39_I10@PURE_QUANTA.SOCKET4677_AZIF0045P001C01CS(CHIPS)':
 'VSS1026': CDS_PINID='VSS1026';
NODE_NAME     U2 DT59
 '@S9S_MB_2U_LIB.S9S_MB_2U(SCH_1):PAGE39_I10@PURE_QUANTA.SOCKET4677_AZIF0045P001C01CS(CHIPS)':
 'VSS1028': CDS_PINID='VSS1028';
NODE_NAME     U2 DT63
 '@S9S_MB_2U_LIB.S9S_MB_2U(SCH_1):PAGE39_I10@PURE_QUANTA.SOCKET4677_AZIF0045P001C01CS(CHIPS)':
 'VSS1029': CDS_PINID='VSS1029';
NODE_NAME     U2 DT83
 '@S9S_MB_2U_LIB.S9S_MB_2U(SCH_1):PAGE39_I10@PURE_QUANTA.SOCKET4677_AZIF0045P001C01CS(CHIPS)':
 'VSS1036': CDS_PINID='VSS1036';
NODE_NAME     U2 DU39
 '@S9S_MB_2U_LIB.S9S_MB_2U(SCH_1):PAGE39_I10@PURE_QUANTA.SOCKET4677_AZIF0045P001C01CS(CHIPS)':
 'VSS1047': CDS_PINID='VSS1047';
NODE_NAME     U2 DU45
 '@S9S_MB_2U_LIB.S9S_MB_2U(SCH_1):PAGE39_I10@PURE_QUANTA.SOCKET4677_AZIF0045P001C01CS(CHIPS)':
 'VSS1048': CDS_PINID='VSS1048';
NODE_NAME     U2 DU52
 '@S9S_MB_2U_LIB.S9S_MB_2U(SCH_1):PAGE39_I10@PURE_QUANTA.SOCKET4677_AZIF0045P001C01CS(CHIPS)':
 'VSS1050': CDS_PINID='VSS1050';
NODE_NAME     U2 DU58
 '@S9S_MB_2U_LIB.S9S_MB_2U(SCH_1):PAGE39_I10@PURE_QUANTA.SOCKET4677_AZIF0045P001C01CS(CHIPS)':
 'VSS1051': CDS_PINID='VSS1051';
NODE_NAME     U2 DU64
 '@S9S_MB_2U_LIB.S9S_MB_2U(SCH_1):PAGE39_I10@PURE_QUANTA.SOCKET4677_AZIF0045P001C01CS(CHIPS)':
 'VSS1052': CDS_PINID='VSS1052';
NODE_NAME     U2 DU70
 '@S9S_MB_2U_LIB.S9S_MB_2U(SCH_1):PAGE39_I10@PURE_QUANTA.SOCKET4677_AZIF0045P001C01CS(CHIPS)':
 'VSS1054': CDS_PINID='VSS1054';
NODE_NAME     U2 DV12
 '@S9S_MB_2U_LIB.S9S_MB_2U(SCH_1):PAGE39_I10@PURE_QUANTA.SOCKET4677_AZIF0045P001C01CS(CHIPS)':
 'VSS1059': CDS_PINID='VSS1059';
NODE_NAME     U2 DV16
 '@S9S_MB_2U_LIB.S9S_MB_2U(SCH_1):PAGE39_I10@PURE_QUANTA.SOCKET4677_AZIF0045P001C01CS(CHIPS)':
 'VSS1060': CDS_PINID='VSS1060';
NODE_NAME     U2 DV4
 '@S9S_MB_2U_LIB.S9S_MB_2U(SCH_1):PAGE39_I10@PURE_QUANTA.SOCKET4677_AZIF0045P001C01CS(CHIPS)':
 'VSS1063': CDS_PINID='VSS1063';
NODE_NAME     U2 DV42
 '@S9S_MB_2U_LIB.S9S_MB_2U(SCH_1):PAGE39_I10@PURE_QUANTA.SOCKET4677_AZIF0045P001C01CS(CHIPS)':
 'VSS1064': CDS_PINID='VSS1064';
NODE_NAME     U2 DW21
 '@S9S_MB_2U_LIB.S9S_MB_2U(SCH_1):PAGE39_I10@PURE_QUANTA.SOCKET4677_AZIF0045P001C01CS(CHIPS)':
 'VSS1077': CDS_PINID='VSS1077';
NODE_NAME     U2 DW60
 '@S9S_MB_2U_LIB.S9S_MB_2U(SCH_1):PAGE39_I10@PURE_QUANTA.SOCKET4677_AZIF0045P001C01CS(CHIPS)':
 'VSS1097': CDS_PINID='VSS1097';
NODE_NAME     U2 DM12
 '@S9S_MB_2U_LIB.S9S_MB_2U(SCH_1):PAGE39_I10@PURE_QUANTA.SOCKET4677_AZIF0045P001C01CS(CHIPS)':
 'VSS1100': CDS_PINID='VSS1100';
NODE_NAME     U2 DM16
 '@S9S_MB_2U_LIB.S9S_MB_2U(SCH_1):PAGE39_I10@PURE_QUANTA.SOCKET4677_AZIF0045P001C01CS(CHIPS)':
 'VSS1101': CDS_PINID='VSS1101';
NODE_NAME     U2 DM18
 '@S9S_MB_2U_LIB.S9S_MB_2U(SCH_1):PAGE39_I10@PURE_QUANTA.SOCKET4677_AZIF0045P001C01CS(CHIPS)':
 'VSS1102': CDS_PINID='VSS1102';
NODE_NAME     U2 DM20
 '@S9S_MB_2U_LIB.S9S_MB_2U(SCH_1):PAGE39_I10@PURE_QUANTA.SOCKET4677_AZIF0045P001C01CS(CHIPS)':
 'VSS1103': CDS_PINID='VSS1103';
NODE_NAME     U2 DM22
 '@S9S_MB_2U_LIB.S9S_MB_2U(SCH_1):PAGE39_I10@PURE_QUANTA.SOCKET4677_AZIF0045P001C01CS(CHIPS)':
 'VSS1104': CDS_PINID='VSS1104';
NODE_NAME     U2 DM24
 '@S9S_MB_2U_LIB.S9S_MB_2U(SCH_1):PAGE39_I10@PURE_QUANTA.SOCKET4677_AZIF0045P001C01CS(CHIPS)':
 'VSS1105': CDS_PINID='VSS1105';
NODE_NAME     U2 DM26
 '@S9S_MB_2U_LIB.S9S_MB_2U(SCH_1):PAGE39_I10@PURE_QUANTA.SOCKET4677_AZIF0045P001C01CS(CHIPS)':
 'VSS1106': CDS_PINID='VSS1106';
NODE_NAME     U2 DM28
 '@S9S_MB_2U_LIB.S9S_MB_2U(SCH_1):PAGE39_I10@PURE_QUANTA.SOCKET4677_AZIF0045P001C01CS(CHIPS)':
 'VSS1107': CDS_PINID='VSS1107';
NODE_NAME     U2 DM30
 '@S9S_MB_2U_LIB.S9S_MB_2U(SCH_1):PAGE39_I10@PURE_QUANTA.SOCKET4677_AZIF0045P001C01CS(CHIPS)':
 'VSS1108': CDS_PINID='VSS1108';
NODE_NAME     U2 DM32
 '@S9S_MB_2U_LIB.S9S_MB_2U(SCH_1):PAGE39_I10@PURE_QUANTA.SOCKET4677_AZIF0045P001C01CS(CHIPS)':
 'VSS1109': CDS_PINID='VSS1109';
NODE_NAME     U2 DM34
 '@S9S_MB_2U_LIB.S9S_MB_2U(SCH_1):PAGE39_I10@PURE_QUANTA.SOCKET4677_AZIF0045P001C01CS(CHIPS)':
 'VSS1110': CDS_PINID='VSS1110';
NODE_NAME     U2 DM36
 '@S9S_MB_2U_LIB.S9S_MB_2U(SCH_1):PAGE39_I10@PURE_QUANTA.SOCKET4677_AZIF0045P001C01CS(CHIPS)':
 'VSS1113': CDS_PINID='VSS1113';
NODE_NAME     U2 DM38
 '@S9S_MB_2U_LIB.S9S_MB_2U(SCH_1):PAGE39_I10@PURE_QUANTA.SOCKET4677_AZIF0045P001C01CS(CHIPS)':
 'VSS1114': CDS_PINID='VSS1114';
NODE_NAME     U2 DM4
 '@S9S_MB_2U_LIB.S9S_MB_2U(SCH_1):PAGE39_I10@PURE_QUANTA.SOCKET4677_AZIF0045P001C01CS(CHIPS)':
 'VSS1117': CDS_PINID='VSS1117';
NODE_NAME     U2 DM40
 '@S9S_MB_2U_LIB.S9S_MB_2U(SCH_1):PAGE39_I10@PURE_QUANTA.SOCKET4677_AZIF0045P001C01CS(CHIPS)':
 'VSS1118': CDS_PINID='VSS1118';
NODE_NAME     U2 DM42
 '@S9S_MB_2U_LIB.S9S_MB_2U(SCH_1):PAGE39_I10@PURE_QUANTA.SOCKET4677_AZIF0045P001C01CS(CHIPS)':
 'VSS1119': CDS_PINID='VSS1119';
NODE_NAME     U2 DM44
 '@S9S_MB_2U_LIB.S9S_MB_2U(SCH_1):PAGE39_I10@PURE_QUANTA.SOCKET4677_AZIF0045P001C01CS(CHIPS)':
 'VSS1120': CDS_PINID='VSS1120';
NODE_NAME     U2 DM47
 '@S9S_MB_2U_LIB.S9S_MB_2U(SCH_1):PAGE39_I10@PURE_QUANTA.SOCKET4677_AZIF0045P001C01CS(CHIPS)':
 'VSS1121': CDS_PINID='VSS1121';
NODE_NAME     U2 DM49
 '@S9S_MB_2U_LIB.S9S_MB_2U(SCH_1):PAGE39_I10@PURE_QUANTA.SOCKET4677_AZIF0045P001C01CS(CHIPS)':
 'VSS1122': CDS_PINID='VSS1122';
NODE_NAME     U2 DM53
 '@S9S_MB_2U_LIB.S9S_MB_2U(SCH_1):PAGE39_I10@PURE_QUANTA.SOCKET4677_AZIF0045P001C01CS(CHIPS)':
 'VSS1123': CDS_PINID='VSS1123';
NODE_NAME     U2 DM55
 '@S9S_MB_2U_LIB.S9S_MB_2U(SCH_1):PAGE39_I10@PURE_QUANTA.SOCKET4677_AZIF0045P001C01CS(CHIPS)':
 'VSS1124': CDS_PINID='VSS1124';
NODE_NAME     U2 DM57
 '@S9S_MB_2U_LIB.S9S_MB_2U(SCH_1):PAGE39_I10@PURE_QUANTA.SOCKET4677_AZIF0045P001C01CS(CHIPS)':
 'VSS1127': CDS_PINID='VSS1127';
NODE_NAME     U2 DM59
 '@S9S_MB_2U_LIB.S9S_MB_2U(SCH_1):PAGE39_I10@PURE_QUANTA.SOCKET4677_AZIF0045P001C01CS(CHIPS)':
 'VSS1128': CDS_PINID='VSS1128';
NODE_NAME     U2 DM61
 '@S9S_MB_2U_LIB.S9S_MB_2U(SCH_1):PAGE39_I10@PURE_QUANTA.SOCKET4677_AZIF0045P001C01CS(CHIPS)':
 'VSS1130': CDS_PINID='VSS1130';
NODE_NAME     U2 DM63
 '@S9S_MB_2U_LIB.S9S_MB_2U(SCH_1):PAGE39_I10@PURE_QUANTA.SOCKET4677_AZIF0045P001C01CS(CHIPS)':
 'VSS1132': CDS_PINID='VSS1132';
NODE_NAME     U2 DM65
 '@S9S_MB_2U_LIB.S9S_MB_2U(SCH_1):PAGE39_I10@PURE_QUANTA.SOCKET4677_AZIF0045P001C01CS(CHIPS)':
 'VSS1133': CDS_PINID='VSS1133';
NODE_NAME     U2 DM67
 '@S9S_MB_2U_LIB.S9S_MB_2U(SCH_1):PAGE39_I10@PURE_QUANTA.SOCKET4677_AZIF0045P001C01CS(CHIPS)':
 'VSS1134': CDS_PINID='VSS1134';
NODE_NAME     U2 DM69
 '@S9S_MB_2U_LIB.S9S_MB_2U(SCH_1):PAGE39_I10@PURE_QUANTA.SOCKET4677_AZIF0045P001C01CS(CHIPS)':
 'VSS1135': CDS_PINID='VSS1135';
NODE_NAME     U2 DM71
 '@S9S_MB_2U_LIB.S9S_MB_2U(SCH_1):PAGE39_I10@PURE_QUANTA.SOCKET4677_AZIF0045P001C01CS(CHIPS)':
 'VSS1136': CDS_PINID='VSS1136';
NODE_NAME     U2 DM75
 '@S9S_MB_2U_LIB.S9S_MB_2U(SCH_1):PAGE39_I10@PURE_QUANTA.SOCKET4677_AZIF0045P001C01CS(CHIPS)':
 'VSS1137': CDS_PINID='VSS1137';
NODE_NAME     U2 DM77
 '@S9S_MB_2U_LIB.S9S_MB_2U(SCH_1):PAGE39_I10@PURE_QUANTA.SOCKET4677_AZIF0045P001C01CS(CHIPS)':
 'VSS1138': CDS_PINID='VSS1138';
NODE_NAME     U2 DM79
 '@S9S_MB_2U_LIB.S9S_MB_2U(SCH_1):PAGE39_I10@PURE_QUANTA.SOCKET4677_AZIF0045P001C01CS(CHIPS)':
 'VSS1139': CDS_PINID='VSS1139';
NODE_NAME     U2 DM8
 '@S9S_MB_2U_LIB.S9S_MB_2U(SCH_1):PAGE39_I10@PURE_QUANTA.SOCKET4677_AZIF0045P001C01CS(CHIPS)':
 'VSS1140': CDS_PINID='VSS1140';
NODE_NAME     U2 DN78
 '@S9S_MB_2U_LIB.S9S_MB_2U(SCH_1):PAGE39_I10@PURE_QUANTA.SOCKET4677_AZIF0045P001C01CS(CHIPS)':
 'VSS1143': CDS_PINID='VSS1143';
NODE_NAME     U2 DN84
 '@S9S_MB_2U_LIB.S9S_MB_2U(SCH_1):PAGE39_I10@PURE_QUANTA.SOCKET4677_AZIF0045P001C01CS(CHIPS)':
 'VSS1147': CDS_PINID='VSS1147';
NODE_NAME     U2 DN88
 '@S9S_MB_2U_LIB.S9S_MB_2U(SCH_1):PAGE39_I10@PURE_QUANTA.SOCKET4677_AZIF0045P001C01CS(CHIPS)':
 'VSS1148': CDS_PINID='VSS1148';
NODE_NAME     U2 DP16
 '@S9S_MB_2U_LIB.S9S_MB_2U(SCH_1):PAGE39_I10@PURE_QUANTA.SOCKET4677_AZIF0045P001C01CS(CHIPS)':
 'VSS1149': CDS_PINID='VSS1149';
NODE_NAME     U2 DP30
 '@S9S_MB_2U_LIB.S9S_MB_2U(SCH_1):PAGE39_I10@PURE_QUANTA.SOCKET4677_AZIF0045P001C01CS(CHIPS)':
 'VSS1150': CDS_PINID='VSS1150';
NODE_NAME     U2 DP36
 '@S9S_MB_2U_LIB.S9S_MB_2U(SCH_1):PAGE39_I10@PURE_QUANTA.SOCKET4677_AZIF0045P001C01CS(CHIPS)':
 'VSS1151': CDS_PINID='VSS1151';
NODE_NAME     U2 DP4
 '@S9S_MB_2U_LIB.S9S_MB_2U(SCH_1):PAGE39_I10@PURE_QUANTA.SOCKET4677_AZIF0045P001C01CS(CHIPS)':
 'VSS1152': CDS_PINID='VSS1152';
NODE_NAME     U2 DP49
 '@S9S_MB_2U_LIB.S9S_MB_2U(SCH_1):PAGE39_I10@PURE_QUANTA.SOCKET4677_AZIF0045P001C01CS(CHIPS)':
 'VSS1153': CDS_PINID='VSS1153';
NODE_NAME     U2 DP73
 '@S9S_MB_2U_LIB.S9S_MB_2U(SCH_1):PAGE39_I10@PURE_QUANTA.SOCKET4677_AZIF0045P001C01CS(CHIPS)':
 'VSS1154': CDS_PINID='VSS1154';
NODE_NAME     U2 DP8
 '@S9S_MB_2U_LIB.S9S_MB_2U(SCH_1):PAGE39_I10@PURE_QUANTA.SOCKET4677_AZIF0045P001C01CS(CHIPS)':
 'VSS1157': CDS_PINID='VSS1157';
NODE_NAME     U2 DP81
 '@S9S_MB_2U_LIB.S9S_MB_2U(SCH_1):PAGE39_I10@PURE_QUANTA.SOCKET4677_AZIF0045P001C01CS(CHIPS)':
 'VSS1159': CDS_PINID='VSS1159';
NODE_NAME     U2 DP87
 '@S9S_MB_2U_LIB.S9S_MB_2U(SCH_1):PAGE39_I10@PURE_QUANTA.SOCKET4677_AZIF0045P001C01CS(CHIPS)':
 'VSS1160': CDS_PINID='VSS1160';
NODE_NAME     U2 DR1
 '@S9S_MB_2U_LIB.S9S_MB_2U(SCH_1):PAGE39_I10@PURE_QUANTA.SOCKET4677_AZIF0045P001C01CS(CHIPS)':
 'VSS1162': CDS_PINID='VSS1162';
NODE_NAME     U2 DR13
 '@S9S_MB_2U_LIB.S9S_MB_2U(SCH_1):PAGE39_I10@PURE_QUANTA.SOCKET4677_AZIF0045P001C01CS(CHIPS)':
 'VSS1164': CDS_PINID='VSS1164';
NODE_NAME     U2 DR19
 '@S9S_MB_2U_LIB.S9S_MB_2U(SCH_1):PAGE39_I10@PURE_QUANTA.SOCKET4677_AZIF0045P001C01CS(CHIPS)':
 'VSS1166': CDS_PINID='VSS1166';
NODE_NAME     U2 DR23
 '@S9S_MB_2U_LIB.S9S_MB_2U(SCH_1):PAGE39_I10@PURE_QUANTA.SOCKET4677_AZIF0045P001C01CS(CHIPS)':
 'VSS1169': CDS_PINID='VSS1169';
NODE_NAME     U2 DR29
 '@S9S_MB_2U_LIB.S9S_MB_2U(SCH_1):PAGE39_I10@PURE_QUANTA.SOCKET4677_AZIF0045P001C01CS(CHIPS)':
 'VSS1172': CDS_PINID='VSS1172';
NODE_NAME     U2 DR31
 '@S9S_MB_2U_LIB.S9S_MB_2U(SCH_1):PAGE39_I10@PURE_QUANTA.SOCKET4677_AZIF0045P001C01CS(CHIPS)':
 'VSS1173': CDS_PINID='VSS1173';
NODE_NAME     U2 DR37
 '@S9S_MB_2U_LIB.S9S_MB_2U(SCH_1):PAGE39_I10@PURE_QUANTA.SOCKET4677_AZIF0045P001C01CS(CHIPS)':
 'VSS1174': CDS_PINID='VSS1174';
NODE_NAME     U2 DR41
 '@S9S_MB_2U_LIB.S9S_MB_2U(SCH_1):PAGE39_I10@PURE_QUANTA.SOCKET4677_AZIF0045P001C01CS(CHIPS)':
 'VSS1175': CDS_PINID='VSS1175';
NODE_NAME     U2 DR43
 '@S9S_MB_2U_LIB.S9S_MB_2U(SCH_1):PAGE39_I10@PURE_QUANTA.SOCKET4677_AZIF0045P001C01CS(CHIPS)':
 'VSS1176': CDS_PINID='VSS1176';
NODE_NAME     U2 DR48
 '@S9S_MB_2U_LIB.S9S_MB_2U(SCH_1):PAGE39_I10@PURE_QUANTA.SOCKET4677_AZIF0045P001C01CS(CHIPS)':
 'VSS1177': CDS_PINID='VSS1177';
NODE_NAME     U2 DR50
 '@S9S_MB_2U_LIB.S9S_MB_2U(SCH_1):PAGE39_I10@PURE_QUANTA.SOCKET4677_AZIF0045P001C01CS(CHIPS)':
 'VSS1178': CDS_PINID='VSS1178';
NODE_NAME     U2 DR56
 '@S9S_MB_2U_LIB.S9S_MB_2U(SCH_1):PAGE39_I10@PURE_QUANTA.SOCKET4677_AZIF0045P001C01CS(CHIPS)':
 'VSS1179': CDS_PINID='VSS1179';
NODE_NAME     U2 DR66
 '@S9S_MB_2U_LIB.S9S_MB_2U(SCH_1):PAGE39_I10@PURE_QUANTA.SOCKET4677_AZIF0045P001C01CS(CHIPS)':
 'VSS1181': CDS_PINID='VSS1181';
NODE_NAME     U2 DR74
 '@S9S_MB_2U_LIB.S9S_MB_2U(SCH_1):PAGE39_I10@PURE_QUANTA.SOCKET4677_AZIF0045P001C01CS(CHIPS)':
 'VSS1182': CDS_PINID='VSS1182';
NODE_NAME     U2 DR78
 '@S9S_MB_2U_LIB.S9S_MB_2U(SCH_1):PAGE39_I10@PURE_QUANTA.SOCKET4677_AZIF0045P001C01CS(CHIPS)':
 'VSS1183': CDS_PINID='VSS1183';
NODE_NAME     U2 DR84
 '@S9S_MB_2U_LIB.S9S_MB_2U(SCH_1):PAGE39_I10@PURE_QUANTA.SOCKET4677_AZIF0045P001C01CS(CHIPS)':
 'VSS1184': CDS_PINID='VSS1184';
NODE_NAME     U2 DR88
 '@S9S_MB_2U_LIB.S9S_MB_2U(SCH_1):PAGE39_I10@PURE_QUANTA.SOCKET4677_AZIF0045P001C01CS(CHIPS)':
 'VSS1186': CDS_PINID='VSS1186';
NODE_NAME     U2 DR9
 '@S9S_MB_2U_LIB.S9S_MB_2U(SCH_1):PAGE39_I10@PURE_QUANTA.SOCKET4677_AZIF0045P001C01CS(CHIPS)':
 'VSS1187': CDS_PINID='VSS1187';
NODE_NAME     U2 DT12
 '@S9S_MB_2U_LIB.S9S_MB_2U(SCH_1):PAGE39_I10@PURE_QUANTA.SOCKET4677_AZIF0045P001C01CS(CHIPS)':
 'VSS1189': CDS_PINID='VSS1189';
NODE_NAME     U2 DT22
 '@S9S_MB_2U_LIB.S9S_MB_2U(SCH_1):PAGE39_I10@PURE_QUANTA.SOCKET4677_AZIF0045P001C01CS(CHIPS)':
 'VSS1190': CDS_PINID='VSS1190';
NODE_NAME     U2 DT28
 '@S9S_MB_2U_LIB.S9S_MB_2U(SCH_1):PAGE39_I10@PURE_QUANTA.SOCKET4677_AZIF0045P001C01CS(CHIPS)':
 'VSS1191': CDS_PINID='VSS1191';
NODE_NAME     U2 DT32
 '@S9S_MB_2U_LIB.S9S_MB_2U(SCH_1):PAGE39_I10@PURE_QUANTA.SOCKET4677_AZIF0045P001C01CS(CHIPS)':
 'VSS1192': CDS_PINID='VSS1192';
NODE_NAME     U2 DT34
 '@S9S_MB_2U_LIB.S9S_MB_2U(SCH_1):PAGE39_I10@PURE_QUANTA.SOCKET4677_AZIF0045P001C01CS(CHIPS)':
 'VSS1194': CDS_PINID='VSS1194';
NODE_NAME     U2 DT38
 '@S9S_MB_2U_LIB.S9S_MB_2U(SCH_1):PAGE39_I10@PURE_QUANTA.SOCKET4677_AZIF0045P001C01CS(CHIPS)':
 'VSS1196': CDS_PINID='VSS1196';
NODE_NAME     U2 DT40
 '@S9S_MB_2U_LIB.S9S_MB_2U(SCH_1):PAGE39_I10@PURE_QUANTA.SOCKET4677_AZIF0045P001C01CS(CHIPS)':
 'VSS1199': CDS_PINID='VSS1199';
NODE_NAME     U2 DT47
 '@S9S_MB_2U_LIB.S9S_MB_2U(SCH_1):PAGE39_I10@PURE_QUANTA.SOCKET4677_AZIF0045P001C01CS(CHIPS)':
 'VSS1201': CDS_PINID='VSS1201';
NODE_NAME     U2 DT57
 '@S9S_MB_2U_LIB.S9S_MB_2U(SCH_1):PAGE39_I10@PURE_QUANTA.SOCKET4677_AZIF0045P001C01CS(CHIPS)':
 'VSS1202': CDS_PINID='VSS1202';
NODE_NAME     U2 DT65
 '@S9S_MB_2U_LIB.S9S_MB_2U(SCH_1):PAGE39_I10@PURE_QUANTA.SOCKET4677_AZIF0045P001C01CS(CHIPS)':
 'VSS1203': CDS_PINID='VSS1203';
NODE_NAME     U2 DT69
 '@S9S_MB_2U_LIB.S9S_MB_2U(SCH_1):PAGE39_I10@PURE_QUANTA.SOCKET4677_AZIF0045P001C01CS(CHIPS)':
 'VSS1204': CDS_PINID='VSS1204';
NODE_NAME     U2 DT71
 '@S9S_MB_2U_LIB.S9S_MB_2U(SCH_1):PAGE39_I10@PURE_QUANTA.SOCKET4677_AZIF0045P001C01CS(CHIPS)':
 'VSS1205': CDS_PINID='VSS1205';
NODE_NAME     U2 DT75
 '@S9S_MB_2U_LIB.S9S_MB_2U(SCH_1):PAGE39_I10@PURE_QUANTA.SOCKET4677_AZIF0045P001C01CS(CHIPS)':
 'VSS1206': CDS_PINID='VSS1206';
NODE_NAME     U2 DT8
 '@S9S_MB_2U_LIB.S9S_MB_2U(SCH_1):PAGE39_I10@PURE_QUANTA.SOCKET4677_AZIF0045P001C01CS(CHIPS)':
 'VSS1207': CDS_PINID='VSS1207';
NODE_NAME     U2 DU21
 '@S9S_MB_2U_LIB.S9S_MB_2U(SCH_1):PAGE39_I10@PURE_QUANTA.SOCKET4677_AZIF0045P001C01CS(CHIPS)':
 'VSS1209': CDS_PINID='VSS1209';
NODE_NAME     U2 DU27
 '@S9S_MB_2U_LIB.S9S_MB_2U(SCH_1):PAGE39_I10@PURE_QUANTA.SOCKET4677_AZIF0045P001C01CS(CHIPS)':
 'VSS1211': CDS_PINID='VSS1211';
NODE_NAME     U2 DU33
 '@S9S_MB_2U_LIB.S9S_MB_2U(SCH_1):PAGE39_I10@PURE_QUANTA.SOCKET4677_AZIF0045P001C01CS(CHIPS)':
 'VSS1212': CDS_PINID='VSS1212';
NODE_NAME     U2 DU76
 '@S9S_MB_2U_LIB.S9S_MB_2U(SCH_1):PAGE39_I10@PURE_QUANTA.SOCKET4677_AZIF0045P001C01CS(CHIPS)':
 'VSS1213': CDS_PINID='VSS1213';
NODE_NAME     U2 DU78
 '@S9S_MB_2U_LIB.S9S_MB_2U(SCH_1):PAGE39_I10@PURE_QUANTA.SOCKET4677_AZIF0045P001C01CS(CHIPS)':
 'VSS1214': CDS_PINID='VSS1214';
NODE_NAME     U2 DU84
 '@S9S_MB_2U_LIB.S9S_MB_2U(SCH_1):PAGE39_I10@PURE_QUANTA.SOCKET4677_AZIF0045P001C01CS(CHIPS)':
 'VSS1215': CDS_PINID='VSS1215';
NODE_NAME     U2 DU88
 '@S9S_MB_2U_LIB.S9S_MB_2U(SCH_1):PAGE39_I10@PURE_QUANTA.SOCKET4677_AZIF0045P001C01CS(CHIPS)':
 'VSS1216': CDS_PINID='VSS1216';
NODE_NAME     U2 DV77
 '@S9S_MB_2U_LIB.S9S_MB_2U(SCH_1):PAGE39_I10@PURE_QUANTA.SOCKET4677_AZIF0045P001C01CS(CHIPS)':
 'VSS1218': CDS_PINID='VSS1218';
NODE_NAME     U2 DV79
 '@S9S_MB_2U_LIB.S9S_MB_2U(SCH_1):PAGE39_I10@PURE_QUANTA.SOCKET4677_AZIF0045P001C01CS(CHIPS)':
 'VSS1219': CDS_PINID='VSS1219';
NODE_NAME     U2 DV8
 '@S9S_MB_2U_LIB.S9S_MB_2U(SCH_1):PAGE39_I10@PURE_QUANTA.SOCKET4677_AZIF0045P001C01CS(CHIPS)':
 'VSS1221': CDS_PINID='VSS1221';
NODE_NAME     U2 DV81
 '@S9S_MB_2U_LIB.S9S_MB_2U(SCH_1):PAGE39_I10@PURE_QUANTA.SOCKET4677_AZIF0045P001C01CS(CHIPS)':
 'VSS1222': CDS_PINID='VSS1222';
NODE_NAME     U2 DV83
 '@S9S_MB_2U_LIB.S9S_MB_2U(SCH_1):PAGE39_I10@PURE_QUANTA.SOCKET4677_AZIF0045P001C01CS(CHIPS)':
 'VSS1226': CDS_PINID='VSS1226';
NODE_NAME     U2 DV87
 '@S9S_MB_2U_LIB.S9S_MB_2U(SCH_1):PAGE39_I10@PURE_QUANTA.SOCKET4677_AZIF0045P001C01CS(CHIPS)':
 'VSS1227': CDS_PINID='VSS1227';
NODE_NAME     U2 DV91
 '@S9S_MB_2U_LIB.S9S_MB_2U(SCH_1):PAGE39_I10@PURE_QUANTA.SOCKET4677_AZIF0045P001C01CS(CHIPS)':
 'VSS1228': CDS_PINID='VSS1228';
NODE_NAME     U2 DW1
 '@S9S_MB_2U_LIB.S9S_MB_2U(SCH_1):PAGE39_I10@PURE_QUANTA.SOCKET4677_AZIF0045P001C01CS(CHIPS)':
 'VSS1229': CDS_PINID='VSS1229';
NODE_NAME     U2 DW13
 '@S9S_MB_2U_LIB.S9S_MB_2U(SCH_1):PAGE39_I10@PURE_QUANTA.SOCKET4677_AZIF0045P001C01CS(CHIPS)':
 'VSS1230': CDS_PINID='VSS1230';
NODE_NAME     U2 DW17
 '@S9S_MB_2U_LIB.S9S_MB_2U(SCH_1):PAGE39_I10@PURE_QUANTA.SOCKET4677_AZIF0045P001C01CS(CHIPS)':
 'VSS1231': CDS_PINID='VSS1231';
NODE_NAME     U2 DW19
 '@S9S_MB_2U_LIB.S9S_MB_2U(SCH_1):PAGE39_I10@PURE_QUANTA.SOCKET4677_AZIF0045P001C01CS(CHIPS)':
 'VSS1233': CDS_PINID='VSS1233';
NODE_NAME     U2 DW23
 '@S9S_MB_2U_LIB.S9S_MB_2U(SCH_1):PAGE39_I10@PURE_QUANTA.SOCKET4677_AZIF0045P001C01CS(CHIPS)':
 'VSS1234': CDS_PINID='VSS1234';
NODE_NAME     U2 DW25
 '@S9S_MB_2U_LIB.S9S_MB_2U(SCH_1):PAGE39_I10@PURE_QUANTA.SOCKET4677_AZIF0045P001C01CS(CHIPS)':
 'VSS1236': CDS_PINID='VSS1236';
NODE_NAME     U2 DW27
 '@S9S_MB_2U_LIB.S9S_MB_2U(SCH_1):PAGE39_I10@PURE_QUANTA.SOCKET4677_AZIF0045P001C01CS(CHIPS)':
 'VSS1238': CDS_PINID='VSS1238';
NODE_NAME     U2 DW29
 '@S9S_MB_2U_LIB.S9S_MB_2U(SCH_1):PAGE39_I10@PURE_QUANTA.SOCKET4677_AZIF0045P001C01CS(CHIPS)':
 'VSS1239': CDS_PINID='VSS1239';
NODE_NAME     U2 DW31
 '@S9S_MB_2U_LIB.S9S_MB_2U(SCH_1):PAGE39_I10@PURE_QUANTA.SOCKET4677_AZIF0045P001C01CS(CHIPS)':
 'VSS1240': CDS_PINID='VSS1240';
NODE_NAME     U2 DW33
 '@S9S_MB_2U_LIB.S9S_MB_2U(SCH_1):PAGE39_I10@PURE_QUANTA.SOCKET4677_AZIF0045P001C01CS(CHIPS)':
 'VSS1241': CDS_PINID='VSS1241';
NODE_NAME     U2 DW35
 '@S9S_MB_2U_LIB.S9S_MB_2U(SCH_1):PAGE39_I10@PURE_QUANTA.SOCKET4677_AZIF0045P001C01CS(CHIPS)':
 'VSS1242': CDS_PINID='VSS1242';
NODE_NAME     U2 DW37
 '@S9S_MB_2U_LIB.S9S_MB_2U(SCH_1):PAGE39_I10@PURE_QUANTA.SOCKET4677_AZIF0045P001C01CS(CHIPS)':
 'VSS1243': CDS_PINID='VSS1243';
NODE_NAME     U2 DW39
 '@S9S_MB_2U_LIB.S9S_MB_2U(SCH_1):PAGE39_I10@PURE_QUANTA.SOCKET4677_AZIF0045P001C01CS(CHIPS)':
 'VSS1244': CDS_PINID='VSS1244';
NODE_NAME     U2 DW41
 '@S9S_MB_2U_LIB.S9S_MB_2U(SCH_1):PAGE39_I10@PURE_QUANTA.SOCKET4677_AZIF0045P001C01CS(CHIPS)':
 'VSS1245': CDS_PINID='VSS1245';
NODE_NAME     U2 DW43
 '@S9S_MB_2U_LIB.S9S_MB_2U(SCH_1):PAGE39_I10@PURE_QUANTA.SOCKET4677_AZIF0045P001C01CS(CHIPS)':
 'VSS1246': CDS_PINID='VSS1246';
NODE_NAME     U2 DW45
 '@S9S_MB_2U_LIB.S9S_MB_2U(SCH_1):PAGE39_I10@PURE_QUANTA.SOCKET4677_AZIF0045P001C01CS(CHIPS)':
 'VSS1247': CDS_PINID='VSS1247';
NODE_NAME     U2 DW48
 '@S9S_MB_2U_LIB.S9S_MB_2U(SCH_1):PAGE39_I10@PURE_QUANTA.SOCKET4677_AZIF0045P001C01CS(CHIPS)':
 'VSS1248': CDS_PINID='VSS1248';
NODE_NAME     U2 DW5
 '@S9S_MB_2U_LIB.S9S_MB_2U(SCH_1):PAGE39_I10@PURE_QUANTA.SOCKET4677_AZIF0045P001C01CS(CHIPS)':
 'VSS1249': CDS_PINID='VSS1249';
NODE_NAME     U2 DW50
 '@S9S_MB_2U_LIB.S9S_MB_2U(SCH_1):PAGE39_I10@PURE_QUANTA.SOCKET4677_AZIF0045P001C01CS(CHIPS)':
 'VSS1250': CDS_PINID='VSS1250';
NODE_NAME     U2 DW52
 '@S9S_MB_2U_LIB.S9S_MB_2U(SCH_1):PAGE39_I10@PURE_QUANTA.SOCKET4677_AZIF0045P001C01CS(CHIPS)':
 'VSS1251': CDS_PINID='VSS1251';
NODE_NAME     U2 DW54
 '@S9S_MB_2U_LIB.S9S_MB_2U(SCH_1):PAGE39_I10@PURE_QUANTA.SOCKET4677_AZIF0045P001C01CS(CHIPS)':
 'VSS1252': CDS_PINID='VSS1252';
NODE_NAME     U2 DW56
 '@S9S_MB_2U_LIB.S9S_MB_2U(SCH_1):PAGE39_I10@PURE_QUANTA.SOCKET4677_AZIF0045P001C01CS(CHIPS)':
 'VSS1253': CDS_PINID='VSS1253';
NODE_NAME     U2 DW58
 '@S9S_MB_2U_LIB.S9S_MB_2U(SCH_1):PAGE39_I10@PURE_QUANTA.SOCKET4677_AZIF0045P001C01CS(CHIPS)':
 'VSS1254': CDS_PINID='VSS1254';
NODE_NAME     U2 DW62
 '@S9S_MB_2U_LIB.S9S_MB_2U(SCH_1):PAGE39_I10@PURE_QUANTA.SOCKET4677_AZIF0045P001C01CS(CHIPS)':
 'VSS1255': CDS_PINID='VSS1255';
NODE_NAME     U2 DW64
 '@S9S_MB_2U_LIB.S9S_MB_2U(SCH_1):PAGE39_I10@PURE_QUANTA.SOCKET4677_AZIF0045P001C01CS(CHIPS)':
 'VSS1256': CDS_PINID='VSS1256';
NODE_NAME     U2 DW9
 '@S9S_MB_2U_LIB.S9S_MB_2U(SCH_1):PAGE39_I10@PURE_QUANTA.SOCKET4677_AZIF0045P001C01CS(CHIPS)':
 'VSS1268': CDS_PINID='VSS1268';
NODE_NAME     U2 DB91
 '@S9S_MB_2U_LIB.S9S_MB_2U(SCH_1):PAGE40_I10@PURE_QUANTA.SOCKET4677_AZIF0045P001C01CS(CHIPS)':
 'VSS723': CDS_PINID='VSS723';
NODE_NAME     U2 DC1
 '@S9S_MB_2U_LIB.S9S_MB_2U(SCH_1):PAGE40_I10@PURE_QUANTA.SOCKET4677_AZIF0045P001C01CS(CHIPS)':
 'VSS724': CDS_PINID='VSS724';
NODE_NAME     U2 DC13
 '@S9S_MB_2U_LIB.S9S_MB_2U(SCH_1):PAGE40_I10@PURE_QUANTA.SOCKET4677_AZIF0045P001C01CS(CHIPS)':
 'VSS725': CDS_PINID='VSS725';
NODE_NAME     U2 DC21
 '@S9S_MB_2U_LIB.S9S_MB_2U(SCH_1):PAGE40_I10@PURE_QUANTA.SOCKET4677_AZIF0045P001C01CS(CHIPS)':
 'VSS726': CDS_PINID='VSS726';
NODE_NAME     U2 DC52
 '@S9S_MB_2U_LIB.S9S_MB_2U(SCH_1):PAGE40_I10@PURE_QUANTA.SOCKET4677_AZIF0045P001C01CS(CHIPS)':
 'VSS735': CDS_PINID='VSS735';
NODE_NAME     U2 DC58
 '@S9S_MB_2U_LIB.S9S_MB_2U(SCH_1):PAGE40_I10@PURE_QUANTA.SOCKET4677_AZIF0045P001C01CS(CHIPS)':
 'VSS738': CDS_PINID='VSS738';
NODE_NAME     U2 DC64
 '@S9S_MB_2U_LIB.S9S_MB_2U(SCH_1):PAGE40_I10@PURE_QUANTA.SOCKET4677_AZIF0045P001C01CS(CHIPS)':
 'VSS739': CDS_PINID='VSS739';
NODE_NAME     U2 DD12
 '@S9S_MB_2U_LIB.S9S_MB_2U(SCH_1):PAGE40_I10@PURE_QUANTA.SOCKET4677_AZIF0045P001C01CS(CHIPS)':
 'VSS747': CDS_PINID='VSS747';
NODE_NAME     U2 DD16
 '@S9S_MB_2U_LIB.S9S_MB_2U(SCH_1):PAGE40_I10@PURE_QUANTA.SOCKET4677_AZIF0045P001C01CS(CHIPS)':
 'VSS748': CDS_PINID='VSS748';
NODE_NAME     U2 DD49
 '@S9S_MB_2U_LIB.S9S_MB_2U(SCH_1):PAGE40_I10@PURE_QUANTA.SOCKET4677_AZIF0045P001C01CS(CHIPS)':
 'VSS753': CDS_PINID='VSS753';
NODE_NAME     U2 DE39
 '@S9S_MB_2U_LIB.S9S_MB_2U(SCH_1):PAGE40_I10@PURE_QUANTA.SOCKET4677_AZIF0045P001C01CS(CHIPS)':
 'VSS776': CDS_PINID='VSS776';
NODE_NAME     U2 DE70
 '@S9S_MB_2U_LIB.S9S_MB_2U(SCH_1):PAGE40_I10@PURE_QUANTA.SOCKET4677_AZIF0045P001C01CS(CHIPS)':
 'VSS791': CDS_PINID='VSS791';
NODE_NAME     U2 DF12
 '@S9S_MB_2U_LIB.S9S_MB_2U(SCH_1):PAGE40_I10@PURE_QUANTA.SOCKET4677_AZIF0045P001C01CS(CHIPS)':
 'VSS798': CDS_PINID='VSS798';
NODE_NAME     U2 DF16
 '@S9S_MB_2U_LIB.S9S_MB_2U(SCH_1):PAGE40_I10@PURE_QUANTA.SOCKET4677_AZIF0045P001C01CS(CHIPS)':
 'VSS799': CDS_PINID='VSS799';
NODE_NAME     U2 DF49
 '@S9S_MB_2U_LIB.S9S_MB_2U(SCH_1):PAGE40_I10@PURE_QUANTA.SOCKET4677_AZIF0045P001C01CS(CHIPS)':
 'VSS802': CDS_PINID='VSS802';
NODE_NAME     U2 DF91
 '@S9S_MB_2U_LIB.S9S_MB_2U(SCH_1):PAGE40_I10@PURE_QUANTA.SOCKET4677_AZIF0045P001C01CS(CHIPS)':
 'VSS806': CDS_PINID='VSS806';
NODE_NAME     U2 DG1
 '@S9S_MB_2U_LIB.S9S_MB_2U(SCH_1):PAGE40_I10@PURE_QUANTA.SOCKET4677_AZIF0045P001C01CS(CHIPS)':
 'VSS807': CDS_PINID='VSS807';
NODE_NAME     U2 DG13
 '@S9S_MB_2U_LIB.S9S_MB_2U(SCH_1):PAGE40_I10@PURE_QUANTA.SOCKET4677_AZIF0045P001C01CS(CHIPS)':
 'VSS808': CDS_PINID='VSS808';
NODE_NAME     U2 DG21
 '@S9S_MB_2U_LIB.S9S_MB_2U(SCH_1):PAGE40_I10@PURE_QUANTA.SOCKET4677_AZIF0045P001C01CS(CHIPS)':
 'VSS809': CDS_PINID='VSS809';
NODE_NAME     U2 DG52
 '@S9S_MB_2U_LIB.S9S_MB_2U(SCH_1):PAGE40_I10@PURE_QUANTA.SOCKET4677_AZIF0045P001C01CS(CHIPS)':
 'VSS817': CDS_PINID='VSS817';
NODE_NAME     U2 DG58
 '@S9S_MB_2U_LIB.S9S_MB_2U(SCH_1):PAGE40_I10@PURE_QUANTA.SOCKET4677_AZIF0045P001C01CS(CHIPS)':
 'VSS820': CDS_PINID='VSS820';
NODE_NAME     U2 DG64
 '@S9S_MB_2U_LIB.S9S_MB_2U(SCH_1):PAGE40_I10@PURE_QUANTA.SOCKET4677_AZIF0045P001C01CS(CHIPS)':
 'VSS821': CDS_PINID='VSS821';
NODE_NAME     U2 DH16
 '@S9S_MB_2U_LIB.S9S_MB_2U(SCH_1):PAGE40_I10@PURE_QUANTA.SOCKET4677_AZIF0045P001C01CS(CHIPS)':
 'VSS829': CDS_PINID='VSS829';
NODE_NAME     U2 DH20
 '@S9S_MB_2U_LIB.S9S_MB_2U(SCH_1):PAGE40_I10@PURE_QUANTA.SOCKET4677_AZIF0045P001C01CS(CHIPS)':
 'VSS830': CDS_PINID='VSS830';
NODE_NAME     U2 DH26
 '@S9S_MB_2U_LIB.S9S_MB_2U(SCH_1):PAGE40_I10@PURE_QUANTA.SOCKET4677_AZIF0045P001C01CS(CHIPS)':
 'VSS832': CDS_PINID='VSS832';
NODE_NAME     U2 DH34
 '@S9S_MB_2U_LIB.S9S_MB_2U(SCH_1):PAGE40_I10@PURE_QUANTA.SOCKET4677_AZIF0045P001C01CS(CHIPS)':
 'VSS835': CDS_PINID='VSS835';
NODE_NAME     U2 DH44
 '@S9S_MB_2U_LIB.S9S_MB_2U(SCH_1):PAGE40_I10@PURE_QUANTA.SOCKET4677_AZIF0045P001C01CS(CHIPS)':
 'VSS839': CDS_PINID='VSS839';
NODE_NAME     U2 DH51
 '@S9S_MB_2U_LIB.S9S_MB_2U(SCH_1):PAGE40_I10@PURE_QUANTA.SOCKET4677_AZIF0045P001C01CS(CHIPS)':
 'VSS841': CDS_PINID='VSS841';
NODE_NAME     U2 DH53
 '@S9S_MB_2U_LIB.S9S_MB_2U(SCH_1):PAGE40_I10@PURE_QUANTA.SOCKET4677_AZIF0045P001C01CS(CHIPS)':
 'VSS842': CDS_PINID='VSS842';
NODE_NAME     U2 DH59
 '@S9S_MB_2U_LIB.S9S_MB_2U(SCH_1):PAGE40_I10@PURE_QUANTA.SOCKET4677_AZIF0045P001C01CS(CHIPS)':
 'VSS844': CDS_PINID='VSS844';
NODE_NAME     U2 DH63
 '@S9S_MB_2U_LIB.S9S_MB_2U(SCH_1):PAGE40_I10@PURE_QUANTA.SOCKET4677_AZIF0045P001C01CS(CHIPS)':
 'VSS845': CDS_PINID='VSS845';
NODE_NAME     U2 DH69
 '@S9S_MB_2U_LIB.S9S_MB_2U(SCH_1):PAGE40_I10@PURE_QUANTA.SOCKET4677_AZIF0045P001C01CS(CHIPS)':
 'VSS847': CDS_PINID='VSS847';
NODE_NAME     U2 DH75
 '@S9S_MB_2U_LIB.S9S_MB_2U(SCH_1):PAGE40_I10@PURE_QUANTA.SOCKET4677_AZIF0045P001C01CS(CHIPS)':
 'VSS849': CDS_PINID='VSS849';
NODE_NAME     U2 DJ25
 '@S9S_MB_2U_LIB.S9S_MB_2U(SCH_1):PAGE40_I10@PURE_QUANTA.SOCKET4677_AZIF0045P001C01CS(CHIPS)':
 'VSS857': CDS_PINID='VSS857';
NODE_NAME     U2 DJ35
 '@S9S_MB_2U_LIB.S9S_MB_2U(SCH_1):PAGE40_I10@PURE_QUANTA.SOCKET4677_AZIF0045P001C01CS(CHIPS)':
 'VSS861': CDS_PINID='VSS861';
NODE_NAME     U2 DJ54
 '@S9S_MB_2U_LIB.S9S_MB_2U(SCH_1):PAGE40_I10@PURE_QUANTA.SOCKET4677_AZIF0045P001C01CS(CHIPS)':
 'VSS867': CDS_PINID='VSS867';
NODE_NAME     U2 DJ62
 '@S9S_MB_2U_LIB.S9S_MB_2U(SCH_1):PAGE40_I10@PURE_QUANTA.SOCKET4677_AZIF0045P001C01CS(CHIPS)':
 'VSS870': CDS_PINID='VSS870';
NODE_NAME     U2 DJ68
 '@S9S_MB_2U_LIB.S9S_MB_2U(SCH_1):PAGE40_I10@PURE_QUANTA.SOCKET4677_AZIF0045P001C01CS(CHIPS)':
 'VSS872': CDS_PINID='VSS872';
NODE_NAME     U2 DK12
 '@S9S_MB_2U_LIB.S9S_MB_2U(SCH_1):PAGE40_I10@PURE_QUANTA.SOCKET4677_AZIF0045P001C01CS(CHIPS)':
 'VSS880': CDS_PINID='VSS880';
NODE_NAME     U2 DK18
 '@S9S_MB_2U_LIB.S9S_MB_2U(SCH_1):PAGE40_I10@PURE_QUANTA.SOCKET4677_AZIF0045P001C01CS(CHIPS)':
 'VSS882': CDS_PINID='VSS882';
NODE_NAME     U2 DK24
 '@S9S_MB_2U_LIB.S9S_MB_2U(SCH_1):PAGE40_I10@PURE_QUANTA.SOCKET4677_AZIF0045P001C01CS(CHIPS)':
 'VSS883': CDS_PINID='VSS883';
NODE_NAME     U2 DK42
 '@S9S_MB_2U_LIB.S9S_MB_2U(SCH_1):PAGE40_I10@PURE_QUANTA.SOCKET4677_AZIF0045P001C01CS(CHIPS)':
 'VSS887': CDS_PINID='VSS887';
NODE_NAME     U2 DK55
 '@S9S_MB_2U_LIB.S9S_MB_2U(SCH_1):PAGE40_I10@PURE_QUANTA.SOCKET4677_AZIF0045P001C01CS(CHIPS)':
 'VSS890': CDS_PINID='VSS890';
NODE_NAME     U2 DK61
 '@S9S_MB_2U_LIB.S9S_MB_2U(SCH_1):PAGE40_I10@PURE_QUANTA.SOCKET4677_AZIF0045P001C01CS(CHIPS)':
 'VSS893': CDS_PINID='VSS893';
NODE_NAME     U2 DK67
 '@S9S_MB_2U_LIB.S9S_MB_2U(SCH_1):PAGE40_I10@PURE_QUANTA.SOCKET4677_AZIF0045P001C01CS(CHIPS)':
 'VSS894': CDS_PINID='VSS894';
NODE_NAME     U2 DL1
 '@S9S_MB_2U_LIB.S9S_MB_2U(SCH_1):PAGE40_I10@PURE_QUANTA.SOCKET4677_AZIF0045P001C01CS(CHIPS)':
 'VSS903': CDS_PINID='VSS903';
NODE_NAME     U2 DL13
 '@S9S_MB_2U_LIB.S9S_MB_2U(SCH_1):PAGE40_I10@PURE_QUANTA.SOCKET4677_AZIF0045P001C01CS(CHIPS)':
 'VSS904': CDS_PINID='VSS904';
NODE_NAME     U2 DL17
 '@S9S_MB_2U_LIB.S9S_MB_2U(SCH_1):PAGE40_I10@PURE_QUANTA.SOCKET4677_AZIF0045P001C01CS(CHIPS)':
 'VSS905': CDS_PINID='VSS905';
NODE_NAME     U2 DL5
 '@S9S_MB_2U_LIB.S9S_MB_2U(SCH_1):PAGE40_I10@PURE_QUANTA.SOCKET4677_AZIF0045P001C01CS(CHIPS)':
 'VSS908': CDS_PINID='VSS908';
NODE_NAME     U2 DL52
 '@S9S_MB_2U_LIB.S9S_MB_2U(SCH_1):PAGE40_I10@PURE_QUANTA.SOCKET4677_AZIF0045P001C01CS(CHIPS)':
 'VSS909': CDS_PINID='VSS909';
NODE_NAME     U2 DC27
 '@S9S_MB_2U_LIB.S9S_MB_2U(SCH_1):PAGE40_I10@PURE_QUANTA.SOCKET4677_AZIF0045P001C01CS(CHIPS)':
 'VSS949': CDS_PINID='VSS949';
NODE_NAME     U2 DC33
 '@S9S_MB_2U_LIB.S9S_MB_2U(SCH_1):PAGE40_I10@PURE_QUANTA.SOCKET4677_AZIF0045P001C01CS(CHIPS)':
 'VSS950': CDS_PINID='VSS950';
NODE_NAME     U2 DC39
 '@S9S_MB_2U_LIB.S9S_MB_2U(SCH_1):PAGE40_I10@PURE_QUANTA.SOCKET4677_AZIF0045P001C01CS(CHIPS)':
 'VSS951': CDS_PINID='VSS951';
NODE_NAME     U2 DC45
 '@S9S_MB_2U_LIB.S9S_MB_2U(SCH_1):PAGE40_I10@PURE_QUANTA.SOCKET4677_AZIF0045P001C01CS(CHIPS)':
 'VSS952': CDS_PINID='VSS952';
NODE_NAME     U2 DC5
 '@S9S_MB_2U_LIB.S9S_MB_2U(SCH_1):PAGE40_I10@PURE_QUANTA.SOCKET4677_AZIF0045P001C01CS(CHIPS)':
 'VSS953': CDS_PINID='VSS953';
NODE_NAME     U2 DC70
 '@S9S_MB_2U_LIB.S9S_MB_2U(SCH_1):PAGE40_I10@PURE_QUANTA.SOCKET4677_AZIF0045P001C01CS(CHIPS)':
 'VSS954': CDS_PINID='VSS954';
NODE_NAME     U2 DC76
 '@S9S_MB_2U_LIB.S9S_MB_2U(SCH_1):PAGE40_I10@PURE_QUANTA.SOCKET4677_AZIF0045P001C01CS(CHIPS)':
 'VSS956': CDS_PINID='VSS956';
NODE_NAME     U2 DC78
 '@S9S_MB_2U_LIB.S9S_MB_2U(SCH_1):PAGE40_I10@PURE_QUANTA.SOCKET4677_AZIF0045P001C01CS(CHIPS)':
 'VSS958': CDS_PINID='VSS958';
NODE_NAME     U2 DC80
 '@S9S_MB_2U_LIB.S9S_MB_2U(SCH_1):PAGE40_I10@PURE_QUANTA.SOCKET4677_AZIF0045P001C01CS(CHIPS)':
 'VSS960': CDS_PINID='VSS960';
NODE_NAME     U2 DC84
 '@S9S_MB_2U_LIB.S9S_MB_2U(SCH_1):PAGE40_I10@PURE_QUANTA.SOCKET4677_AZIF0045P001C01CS(CHIPS)':
 'VSS961': CDS_PINID='VSS961';
NODE_NAME     U2 DC88
 '@S9S_MB_2U_LIB.S9S_MB_2U(SCH_1):PAGE40_I10@PURE_QUANTA.SOCKET4677_AZIF0045P001C01CS(CHIPS)':
 'VSS962': CDS_PINID='VSS962';
NODE_NAME     U2 DC9
 '@S9S_MB_2U_LIB.S9S_MB_2U(SCH_1):PAGE40_I10@PURE_QUANTA.SOCKET4677_AZIF0045P001C01CS(CHIPS)':
 'VSS963': CDS_PINID='VSS963';
NODE_NAME     U2 DD4
 '@S9S_MB_2U_LIB.S9S_MB_2U(SCH_1):PAGE40_I10@PURE_QUANTA.SOCKET4677_AZIF0045P001C01CS(CHIPS)':
 'VSS964': CDS_PINID='VSS964';
NODE_NAME     U2 DD79
 '@S9S_MB_2U_LIB.S9S_MB_2U(SCH_1):PAGE40_I10@PURE_QUANTA.SOCKET4677_AZIF0045P001C01CS(CHIPS)':
 'VSS965': CDS_PINID='VSS965';
NODE_NAME     U2 DD8
 '@S9S_MB_2U_LIB.S9S_MB_2U(SCH_1):PAGE40_I10@PURE_QUANTA.SOCKET4677_AZIF0045P001C01CS(CHIPS)':
 'VSS967': CDS_PINID='VSS967';
NODE_NAME     U2 DE17
 '@S9S_MB_2U_LIB.S9S_MB_2U(SCH_1):PAGE40_I10@PURE_QUANTA.SOCKET4677_AZIF0045P001C01CS(CHIPS)':
 'VSS970': CDS_PINID='VSS970';
NODE_NAME     U2 DE19
 '@S9S_MB_2U_LIB.S9S_MB_2U(SCH_1):PAGE40_I10@PURE_QUANTA.SOCKET4677_AZIF0045P001C01CS(CHIPS)':
 'VSS971': CDS_PINID='VSS971';
NODE_NAME     U2 DE21
 '@S9S_MB_2U_LIB.S9S_MB_2U(SCH_1):PAGE40_I10@PURE_QUANTA.SOCKET4677_AZIF0045P001C01CS(CHIPS)':
 'VSS972': CDS_PINID='VSS972';
NODE_NAME     U2 DE23
 '@S9S_MB_2U_LIB.S9S_MB_2U(SCH_1):PAGE40_I10@PURE_QUANTA.SOCKET4677_AZIF0045P001C01CS(CHIPS)':
 'VSS974': CDS_PINID='VSS974';
NODE_NAME     U2 DE25
 '@S9S_MB_2U_LIB.S9S_MB_2U(SCH_1):PAGE40_I10@PURE_QUANTA.SOCKET4677_AZIF0045P001C01CS(CHIPS)':
 'VSS975': CDS_PINID='VSS975';
NODE_NAME     U2 DE27
 '@S9S_MB_2U_LIB.S9S_MB_2U(SCH_1):PAGE40_I10@PURE_QUANTA.SOCKET4677_AZIF0045P001C01CS(CHIPS)':
 'VSS977': CDS_PINID='VSS977';
NODE_NAME     U2 DE29
 '@S9S_MB_2U_LIB.S9S_MB_2U(SCH_1):PAGE40_I10@PURE_QUANTA.SOCKET4677_AZIF0045P001C01CS(CHIPS)':
 'VSS978': CDS_PINID='VSS978';
NODE_NAME     U2 DE31
 '@S9S_MB_2U_LIB.S9S_MB_2U(SCH_1):PAGE40_I10@PURE_QUANTA.SOCKET4677_AZIF0045P001C01CS(CHIPS)':
 'VSS981': CDS_PINID='VSS981';
NODE_NAME     U2 DE33
 '@S9S_MB_2U_LIB.S9S_MB_2U(SCH_1):PAGE40_I10@PURE_QUANTA.SOCKET4677_AZIF0045P001C01CS(CHIPS)':
 'VSS982': CDS_PINID='VSS982';
NODE_NAME     U2 DE35
 '@S9S_MB_2U_LIB.S9S_MB_2U(SCH_1):PAGE40_I10@PURE_QUANTA.SOCKET4677_AZIF0045P001C01CS(CHIPS)':
 'VSS983': CDS_PINID='VSS983';
NODE_NAME     U2 DE37
 '@S9S_MB_2U_LIB.S9S_MB_2U(SCH_1):PAGE40_I10@PURE_QUANTA.SOCKET4677_AZIF0045P001C01CS(CHIPS)':
 'VSS984': CDS_PINID='VSS984';
NODE_NAME     U2 DE41
 '@S9S_MB_2U_LIB.S9S_MB_2U(SCH_1):PAGE40_I10@PURE_QUANTA.SOCKET4677_AZIF0045P001C01CS(CHIPS)':
 'VSS986': CDS_PINID='VSS986';
NODE_NAME     U2 DE43
 '@S9S_MB_2U_LIB.S9S_MB_2U(SCH_1):PAGE40_I10@PURE_QUANTA.SOCKET4677_AZIF0045P001C01CS(CHIPS)':
 'VSS987': CDS_PINID='VSS987';
NODE_NAME     U2 DE45
 '@S9S_MB_2U_LIB.S9S_MB_2U(SCH_1):PAGE40_I10@PURE_QUANTA.SOCKET4677_AZIF0045P001C01CS(CHIPS)':
 'VSS988': CDS_PINID='VSS988';
NODE_NAME     U2 DE48
 '@S9S_MB_2U_LIB.S9S_MB_2U(SCH_1):PAGE40_I10@PURE_QUANTA.SOCKET4677_AZIF0045P001C01CS(CHIPS)':
 'VSS989': CDS_PINID='VSS989';
NODE_NAME     U2 DE50
 '@S9S_MB_2U_LIB.S9S_MB_2U(SCH_1):PAGE40_I10@PURE_QUANTA.SOCKET4677_AZIF0045P001C01CS(CHIPS)':
 'VSS991': CDS_PINID='VSS991';
NODE_NAME     U2 DE52
 '@S9S_MB_2U_LIB.S9S_MB_2U(SCH_1):PAGE40_I10@PURE_QUANTA.SOCKET4677_AZIF0045P001C01CS(CHIPS)':
 'VSS992': CDS_PINID='VSS992';
NODE_NAME     U2 DE54
 '@S9S_MB_2U_LIB.S9S_MB_2U(SCH_1):PAGE40_I10@PURE_QUANTA.SOCKET4677_AZIF0045P001C01CS(CHIPS)':
 'VSS994': CDS_PINID='VSS994';
NODE_NAME     U2 DE56
 '@S9S_MB_2U_LIB.S9S_MB_2U(SCH_1):PAGE40_I10@PURE_QUANTA.SOCKET4677_AZIF0045P001C01CS(CHIPS)':
 'VSS995': CDS_PINID='VSS995';
NODE_NAME     U2 DE58
 '@S9S_MB_2U_LIB.S9S_MB_2U(SCH_1):PAGE40_I10@PURE_QUANTA.SOCKET4677_AZIF0045P001C01CS(CHIPS)':
 'VSS996': CDS_PINID='VSS996';
NODE_NAME     U2 DE60
 '@S9S_MB_2U_LIB.S9S_MB_2U(SCH_1):PAGE40_I10@PURE_QUANTA.SOCKET4677_AZIF0045P001C01CS(CHIPS)':
 'VSS997': CDS_PINID='VSS997';
NODE_NAME     U2 DE62
 '@S9S_MB_2U_LIB.S9S_MB_2U(SCH_1):PAGE40_I10@PURE_QUANTA.SOCKET4677_AZIF0045P001C01CS(CHIPS)':
 'VSS999': CDS_PINID='VSS999';
NODE_NAME     U2 DE64
 '@S9S_MB_2U_LIB.S9S_MB_2U(SCH_1):PAGE40_I10@PURE_QUANTA.SOCKET4677_AZIF0045P001C01CS(CHIPS)':
 'VSS1001': CDS_PINID='VSS1001';
NODE_NAME     U2 DE66
 '@S9S_MB_2U_LIB.S9S_MB_2U(SCH_1):PAGE40_I10@PURE_QUANTA.SOCKET4677_AZIF0045P001C01CS(CHIPS)':
 'VSS1004': CDS_PINID='VSS1004';
NODE_NAME     U2 DE68
 '@S9S_MB_2U_LIB.S9S_MB_2U(SCH_1):PAGE40_I10@PURE_QUANTA.SOCKET4677_AZIF0045P001C01CS(CHIPS)':
 'VSS1007': CDS_PINID='VSS1007';
NODE_NAME     U2 DE72
 '@S9S_MB_2U_LIB.S9S_MB_2U(SCH_1):PAGE40_I10@PURE_QUANTA.SOCKET4677_AZIF0045P001C01CS(CHIPS)':
 'VSS1008': CDS_PINID='VSS1008';
NODE_NAME     U2 DE74
 '@S9S_MB_2U_LIB.S9S_MB_2U(SCH_1):PAGE40_I10@PURE_QUANTA.SOCKET4677_AZIF0045P001C01CS(CHIPS)':
 'VSS1009': CDS_PINID='VSS1009';
NODE_NAME     U2 DE76
 '@S9S_MB_2U_LIB.S9S_MB_2U(SCH_1):PAGE40_I10@PURE_QUANTA.SOCKET4677_AZIF0045P001C01CS(CHIPS)':
 'VSS1010': CDS_PINID='VSS1010';
NODE_NAME     U2 DE82
 '@S9S_MB_2U_LIB.S9S_MB_2U(SCH_1):PAGE40_I10@PURE_QUANTA.SOCKET4677_AZIF0045P001C01CS(CHIPS)':
 'VSS1011': CDS_PINID='VSS1011';
NODE_NAME     U2 DE84
 '@S9S_MB_2U_LIB.S9S_MB_2U(SCH_1):PAGE40_I10@PURE_QUANTA.SOCKET4677_AZIF0045P001C01CS(CHIPS)':
 'VSS1012': CDS_PINID='VSS1012';
NODE_NAME     U2 DE88
 '@S9S_MB_2U_LIB.S9S_MB_2U(SCH_1):PAGE40_I10@PURE_QUANTA.SOCKET4677_AZIF0045P001C01CS(CHIPS)':
 'VSS1015': CDS_PINID='VSS1015';
NODE_NAME     U2 DF4
 '@S9S_MB_2U_LIB.S9S_MB_2U(SCH_1):PAGE40_I10@PURE_QUANTA.SOCKET4677_AZIF0045P001C01CS(CHIPS)':
 'VSS1017': CDS_PINID='VSS1017';
NODE_NAME     U2 DF79
 '@S9S_MB_2U_LIB.S9S_MB_2U(SCH_1):PAGE40_I10@PURE_QUANTA.SOCKET4677_AZIF0045P001C01CS(CHIPS)':
 'VSS1018': CDS_PINID='VSS1018';
NODE_NAME     U2 DF8
 '@S9S_MB_2U_LIB.S9S_MB_2U(SCH_1):PAGE40_I10@PURE_QUANTA.SOCKET4677_AZIF0045P001C01CS(CHIPS)':
 'VSS1019': CDS_PINID='VSS1019';
NODE_NAME     U2 DF87
 '@S9S_MB_2U_LIB.S9S_MB_2U(SCH_1):PAGE40_I10@PURE_QUANTA.SOCKET4677_AZIF0045P001C01CS(CHIPS)':
 'VSS1020': CDS_PINID='VSS1020';
NODE_NAME     U2 DG27
 '@S9S_MB_2U_LIB.S9S_MB_2U(SCH_1):PAGE40_I10@PURE_QUANTA.SOCKET4677_AZIF0045P001C01CS(CHIPS)':
 'VSS1022': CDS_PINID='VSS1022';
NODE_NAME     U2 DG33
 '@S9S_MB_2U_LIB.S9S_MB_2U(SCH_1):PAGE40_I10@PURE_QUANTA.SOCKET4677_AZIF0045P001C01CS(CHIPS)':
 'VSS1024': CDS_PINID='VSS1024';
NODE_NAME     U2 DG39
 '@S9S_MB_2U_LIB.S9S_MB_2U(SCH_1):PAGE40_I10@PURE_QUANTA.SOCKET4677_AZIF0045P001C01CS(CHIPS)':
 'VSS1027': CDS_PINID='VSS1027';
NODE_NAME     U2 DG45
 '@S9S_MB_2U_LIB.S9S_MB_2U(SCH_1):PAGE40_I10@PURE_QUANTA.SOCKET4677_AZIF0045P001C01CS(CHIPS)':
 'VSS1030': CDS_PINID='VSS1030';
NODE_NAME     U2 DG5
 '@S9S_MB_2U_LIB.S9S_MB_2U(SCH_1):PAGE40_I10@PURE_QUANTA.SOCKET4677_AZIF0045P001C01CS(CHIPS)':
 'VSS1031': CDS_PINID='VSS1031';
NODE_NAME     U2 DG70
 '@S9S_MB_2U_LIB.S9S_MB_2U(SCH_1):PAGE40_I10@PURE_QUANTA.SOCKET4677_AZIF0045P001C01CS(CHIPS)':
 'VSS1032': CDS_PINID='VSS1032';
NODE_NAME     U2 DG76
 '@S9S_MB_2U_LIB.S9S_MB_2U(SCH_1):PAGE40_I10@PURE_QUANTA.SOCKET4677_AZIF0045P001C01CS(CHIPS)':
 'VSS1033': CDS_PINID='VSS1033';
NODE_NAME     U2 DG80
 '@S9S_MB_2U_LIB.S9S_MB_2U(SCH_1):PAGE40_I10@PURE_QUANTA.SOCKET4677_AZIF0045P001C01CS(CHIPS)':
 'VSS1034': CDS_PINID='VSS1034';
NODE_NAME     U2 DG84
 '@S9S_MB_2U_LIB.S9S_MB_2U(SCH_1):PAGE40_I10@PURE_QUANTA.SOCKET4677_AZIF0045P001C01CS(CHIPS)':
 'VSS1035': CDS_PINID='VSS1035';
NODE_NAME     U2 DG88
 '@S9S_MB_2U_LIB.S9S_MB_2U(SCH_1):PAGE40_I10@PURE_QUANTA.SOCKET4677_AZIF0045P001C01CS(CHIPS)':
 'VSS1037': CDS_PINID='VSS1037';
NODE_NAME     U2 DG9
 '@S9S_MB_2U_LIB.S9S_MB_2U(SCH_1):PAGE40_I10@PURE_QUANTA.SOCKET4677_AZIF0045P001C01CS(CHIPS)':
 'VSS1038': CDS_PINID='VSS1038';
NODE_NAME     U2 DH12
 '@S9S_MB_2U_LIB.S9S_MB_2U(SCH_1):PAGE40_I10@PURE_QUANTA.SOCKET4677_AZIF0045P001C01CS(CHIPS)':
 'VSS1039': CDS_PINID='VSS1039';
NODE_NAME     U2 DH22
 '@S9S_MB_2U_LIB.S9S_MB_2U(SCH_1):PAGE40_I10@PURE_QUANTA.SOCKET4677_AZIF0045P001C01CS(CHIPS)':
 'VSS1040': CDS_PINID='VSS1040';
NODE_NAME     U2 DH28
 '@S9S_MB_2U_LIB.S9S_MB_2U(SCH_1):PAGE40_I10@PURE_QUANTA.SOCKET4677_AZIF0045P001C01CS(CHIPS)':
 'VSS1041': CDS_PINID='VSS1041';
NODE_NAME     U2 DH32
 '@S9S_MB_2U_LIB.S9S_MB_2U(SCH_1):PAGE40_I10@PURE_QUANTA.SOCKET4677_AZIF0045P001C01CS(CHIPS)':
 'VSS1042': CDS_PINID='VSS1042';
NODE_NAME     U2 DH38
 '@S9S_MB_2U_LIB.S9S_MB_2U(SCH_1):PAGE40_I10@PURE_QUANTA.SOCKET4677_AZIF0045P001C01CS(CHIPS)':
 'VSS1043': CDS_PINID='VSS1043';
NODE_NAME     U2 DH4
 '@S9S_MB_2U_LIB.S9S_MB_2U(SCH_1):PAGE40_I10@PURE_QUANTA.SOCKET4677_AZIF0045P001C01CS(CHIPS)':
 'VSS1044': CDS_PINID='VSS1044';
NODE_NAME     U2 DH40
 '@S9S_MB_2U_LIB.S9S_MB_2U(SCH_1):PAGE40_I10@PURE_QUANTA.SOCKET4677_AZIF0045P001C01CS(CHIPS)':
 'VSS1045': CDS_PINID='VSS1045';
NODE_NAME     U2 DH47
 '@S9S_MB_2U_LIB.S9S_MB_2U(SCH_1):PAGE40_I10@PURE_QUANTA.SOCKET4677_AZIF0045P001C01CS(CHIPS)':
 'VSS1046': CDS_PINID='VSS1046';
NODE_NAME     U2 DH57
 '@S9S_MB_2U_LIB.S9S_MB_2U(SCH_1):PAGE40_I10@PURE_QUANTA.SOCKET4677_AZIF0045P001C01CS(CHIPS)':
 'VSS1049': CDS_PINID='VSS1049';
NODE_NAME     U2 DH65
 '@S9S_MB_2U_LIB.S9S_MB_2U(SCH_1):PAGE40_I10@PURE_QUANTA.SOCKET4677_AZIF0045P001C01CS(CHIPS)':
 'VSS1053': CDS_PINID='VSS1053';
NODE_NAME     U2 DH71
 '@S9S_MB_2U_LIB.S9S_MB_2U(SCH_1):PAGE40_I10@PURE_QUANTA.SOCKET4677_AZIF0045P001C01CS(CHIPS)':
 'VSS1055': CDS_PINID='VSS1055';
NODE_NAME     U2 DH77
 '@S9S_MB_2U_LIB.S9S_MB_2U(SCH_1):PAGE40_I10@PURE_QUANTA.SOCKET4677_AZIF0045P001C01CS(CHIPS)':
 'VSS1056': CDS_PINID='VSS1056';
NODE_NAME     U2 DH8
 '@S9S_MB_2U_LIB.S9S_MB_2U(SCH_1):PAGE40_I10@PURE_QUANTA.SOCKET4677_AZIF0045P001C01CS(CHIPS)':
 'VSS1057': CDS_PINID='VSS1057';
NODE_NAME     U2 DH85
 '@S9S_MB_2U_LIB.S9S_MB_2U(SCH_1):PAGE40_I10@PURE_QUANTA.SOCKET4677_AZIF0045P001C01CS(CHIPS)':
 'VSS1058': CDS_PINID='VSS1058';
NODE_NAME     U2 DJ19
 '@S9S_MB_2U_LIB.S9S_MB_2U(SCH_1):PAGE40_I10@PURE_QUANTA.SOCKET4677_AZIF0045P001C01CS(CHIPS)':
 'VSS1061': CDS_PINID='VSS1061';
NODE_NAME     U2 DJ23
 '@S9S_MB_2U_LIB.S9S_MB_2U(SCH_1):PAGE40_I10@PURE_QUANTA.SOCKET4677_AZIF0045P001C01CS(CHIPS)':
 'VSS1062': CDS_PINID='VSS1062';
NODE_NAME     U2 DJ29
 '@S9S_MB_2U_LIB.S9S_MB_2U(SCH_1):PAGE40_I10@PURE_QUANTA.SOCKET4677_AZIF0045P001C01CS(CHIPS)':
 'VSS1065': CDS_PINID='VSS1065';
NODE_NAME     U2 DJ31
 '@S9S_MB_2U_LIB.S9S_MB_2U(SCH_1):PAGE40_I10@PURE_QUANTA.SOCKET4677_AZIF0045P001C01CS(CHIPS)':
 'VSS1066': CDS_PINID='VSS1066';
NODE_NAME     U2 DJ37
 '@S9S_MB_2U_LIB.S9S_MB_2U(SCH_1):PAGE40_I10@PURE_QUANTA.SOCKET4677_AZIF0045P001C01CS(CHIPS)':
 'VSS1067': CDS_PINID='VSS1067';
NODE_NAME     U2 DJ41
 '@S9S_MB_2U_LIB.S9S_MB_2U(SCH_1):PAGE40_I10@PURE_QUANTA.SOCKET4677_AZIF0045P001C01CS(CHIPS)':
 'VSS1068': CDS_PINID='VSS1068';
NODE_NAME     U2 DJ43
 '@S9S_MB_2U_LIB.S9S_MB_2U(SCH_1):PAGE40_I10@PURE_QUANTA.SOCKET4677_AZIF0045P001C01CS(CHIPS)':
 'VSS1069': CDS_PINID='VSS1069';
NODE_NAME     U2 DJ48
 '@S9S_MB_2U_LIB.S9S_MB_2U(SCH_1):PAGE40_I10@PURE_QUANTA.SOCKET4677_AZIF0045P001C01CS(CHIPS)':
 'VSS1070': CDS_PINID='VSS1070';
NODE_NAME     U2 DJ50
 '@S9S_MB_2U_LIB.S9S_MB_2U(SCH_1):PAGE40_I10@PURE_QUANTA.SOCKET4677_AZIF0045P001C01CS(CHIPS)':
 'VSS1071': CDS_PINID='VSS1071';
NODE_NAME     U2 DJ56
 '@S9S_MB_2U_LIB.S9S_MB_2U(SCH_1):PAGE40_I10@PURE_QUANTA.SOCKET4677_AZIF0045P001C01CS(CHIPS)':
 'VSS1072': CDS_PINID='VSS1072';
NODE_NAME     U2 DJ60
 '@S9S_MB_2U_LIB.S9S_MB_2U(SCH_1):PAGE40_I10@PURE_QUANTA.SOCKET4677_AZIF0045P001C01CS(CHIPS)':
 'VSS1073': CDS_PINID='VSS1073';
NODE_NAME     U2 DJ66
 '@S9S_MB_2U_LIB.S9S_MB_2U(SCH_1):PAGE40_I10@PURE_QUANTA.SOCKET4677_AZIF0045P001C01CS(CHIPS)':
 'VSS1074': CDS_PINID='VSS1074';
NODE_NAME     U2 DJ72
 '@S9S_MB_2U_LIB.S9S_MB_2U(SCH_1):PAGE40_I10@PURE_QUANTA.SOCKET4677_AZIF0045P001C01CS(CHIPS)':
 'VSS1075': CDS_PINID='VSS1075';
NODE_NAME     U2 DJ74
 '@S9S_MB_2U_LIB.S9S_MB_2U(SCH_1):PAGE40_I10@PURE_QUANTA.SOCKET4677_AZIF0045P001C01CS(CHIPS)':
 'VSS1076': CDS_PINID='VSS1076';
NODE_NAME     U2 DJ80
 '@S9S_MB_2U_LIB.S9S_MB_2U(SCH_1):PAGE40_I10@PURE_QUANTA.SOCKET4677_AZIF0045P001C01CS(CHIPS)':
 'VSS1078': CDS_PINID='VSS1078';
NODE_NAME     U2 DJ82
 '@S9S_MB_2U_LIB.S9S_MB_2U(SCH_1):PAGE40_I10@PURE_QUANTA.SOCKET4677_AZIF0045P001C01CS(CHIPS)':
 'VSS1079': CDS_PINID='VSS1079';
NODE_NAME     U2 DJ84
 '@S9S_MB_2U_LIB.S9S_MB_2U(SCH_1):PAGE40_I10@PURE_QUANTA.SOCKET4677_AZIF0045P001C01CS(CHIPS)':
 'VSS1080': CDS_PINID='VSS1080';
NODE_NAME     U2 DJ88
 '@S9S_MB_2U_LIB.S9S_MB_2U(SCH_1):PAGE40_I10@PURE_QUANTA.SOCKET4677_AZIF0045P001C01CS(CHIPS)':
 'VSS1081': CDS_PINID='VSS1081';
NODE_NAME     U2 DK16
 '@S9S_MB_2U_LIB.S9S_MB_2U(SCH_1):PAGE40_I10@PURE_QUANTA.SOCKET4677_AZIF0045P001C01CS(CHIPS)':
 'VSS1082': CDS_PINID='VSS1082';
NODE_NAME     U2 DK30
 '@S9S_MB_2U_LIB.S9S_MB_2U(SCH_1):PAGE40_I10@PURE_QUANTA.SOCKET4677_AZIF0045P001C01CS(CHIPS)':
 'VSS1083': CDS_PINID='VSS1083';
NODE_NAME     U2 DK36
 '@S9S_MB_2U_LIB.S9S_MB_2U(SCH_1):PAGE40_I10@PURE_QUANTA.SOCKET4677_AZIF0045P001C01CS(CHIPS)':
 'VSS1084': CDS_PINID='VSS1084';
NODE_NAME     U2 DK4
 '@S9S_MB_2U_LIB.S9S_MB_2U(SCH_1):PAGE40_I10@PURE_QUANTA.SOCKET4677_AZIF0045P001C01CS(CHIPS)':
 'VSS1085': CDS_PINID='VSS1085';
NODE_NAME     U2 DK49
 '@S9S_MB_2U_LIB.S9S_MB_2U(SCH_1):PAGE40_I10@PURE_QUANTA.SOCKET4677_AZIF0045P001C01CS(CHIPS)':
 'VSS1086': CDS_PINID='VSS1086';
NODE_NAME     U2 DK73
 '@S9S_MB_2U_LIB.S9S_MB_2U(SCH_1):PAGE40_I10@PURE_QUANTA.SOCKET4677_AZIF0045P001C01CS(CHIPS)':
 'VSS1087': CDS_PINID='VSS1087';
NODE_NAME     U2 DK77
 '@S9S_MB_2U_LIB.S9S_MB_2U(SCH_1):PAGE40_I10@PURE_QUANTA.SOCKET4677_AZIF0045P001C01CS(CHIPS)':
 'VSS1088': CDS_PINID='VSS1088';
NODE_NAME     U2 DK79
 '@S9S_MB_2U_LIB.S9S_MB_2U(SCH_1):PAGE40_I10@PURE_QUANTA.SOCKET4677_AZIF0045P001C01CS(CHIPS)':
 'VSS1089': CDS_PINID='VSS1089';
NODE_NAME     U2 DK8
 '@S9S_MB_2U_LIB.S9S_MB_2U(SCH_1):PAGE40_I10@PURE_QUANTA.SOCKET4677_AZIF0045P001C01CS(CHIPS)':
 'VSS1090': CDS_PINID='VSS1090';
NODE_NAME     U2 DK81
 '@S9S_MB_2U_LIB.S9S_MB_2U(SCH_1):PAGE40_I10@PURE_QUANTA.SOCKET4677_AZIF0045P001C01CS(CHIPS)':
 'VSS1091': CDS_PINID='VSS1091';
NODE_NAME     U2 DK83
 '@S9S_MB_2U_LIB.S9S_MB_2U(SCH_1):PAGE40_I10@PURE_QUANTA.SOCKET4677_AZIF0045P001C01CS(CHIPS)':
 'VSS1092': CDS_PINID='VSS1092';
NODE_NAME     U2 DK87
 '@S9S_MB_2U_LIB.S9S_MB_2U(SCH_1):PAGE40_I10@PURE_QUANTA.SOCKET4677_AZIF0045P001C01CS(CHIPS)':
 'VSS1093': CDS_PINID='VSS1093';
NODE_NAME     U2 DK91
 '@S9S_MB_2U_LIB.S9S_MB_2U(SCH_1):PAGE40_I10@PURE_QUANTA.SOCKET4677_AZIF0045P001C01CS(CHIPS)':
 'VSS1094': CDS_PINID='VSS1094';
NODE_NAME     U2 DL39
 '@S9S_MB_2U_LIB.S9S_MB_2U(SCH_1):PAGE40_I10@PURE_QUANTA.SOCKET4677_AZIF0045P001C01CS(CHIPS)':
 'VSS1095': CDS_PINID='VSS1095';
NODE_NAME     U2 DL84
 '@S9S_MB_2U_LIB.S9S_MB_2U(SCH_1):PAGE40_I10@PURE_QUANTA.SOCKET4677_AZIF0045P001C01CS(CHIPS)':
 'VSS1096': CDS_PINID='VSS1096';
NODE_NAME     U2 DL88
 '@S9S_MB_2U_LIB.S9S_MB_2U(SCH_1):PAGE40_I10@PURE_QUANTA.SOCKET4677_AZIF0045P001C01CS(CHIPS)':
 'VSS1098': CDS_PINID='VSS1098';
NODE_NAME     U2 DL9
 '@S9S_MB_2U_LIB.S9S_MB_2U(SCH_1):PAGE40_I10@PURE_QUANTA.SOCKET4677_AZIF0045P001C01CS(CHIPS)':
 'VSS1099': CDS_PINID='VSS1099';
NODE_NAME     U2 CM16
 '@S9S_MB_2U_LIB.S9S_MB_2U(SCH_1):PAGE40_I11@PURE_QUANTA.SOCKET4677_AZIF0045P001C01CS(CHIPS)':
 'VSS436': CDS_PINID='VSS436';
NODE_NAME     U2 CM22
 '@S9S_MB_2U_LIB.S9S_MB_2U(SCH_1):PAGE40_I11@PURE_QUANTA.SOCKET4677_AZIF0045P001C01CS(CHIPS)':
 'VSS438': CDS_PINID='VSS438';
NODE_NAME     U2 CN76
 '@S9S_MB_2U_LIB.S9S_MB_2U(SCH_1):PAGE40_I11@PURE_QUANTA.SOCKET4677_AZIF0045P001C01CS(CHIPS)':
 'VSS471': CDS_PINID='VSS471';
NODE_NAME     U2 CP16
 '@S9S_MB_2U_LIB.S9S_MB_2U(SCH_1):PAGE40_I11@PURE_QUANTA.SOCKET4677_AZIF0045P001C01CS(CHIPS)':
 'VSS478': CDS_PINID='VSS478';
NODE_NAME     U2 CP79
 '@S9S_MB_2U_LIB.S9S_MB_2U(SCH_1):PAGE40_I11@PURE_QUANTA.SOCKET4677_AZIF0045P001C01CS(CHIPS)':
 'VSS493': CDS_PINID='VSS493';
NODE_NAME     U2 CR78
 '@S9S_MB_2U_LIB.S9S_MB_2U(SCH_1):PAGE40_I11@PURE_QUANTA.SOCKET4677_AZIF0045P001C01CS(CHIPS)':
 'VSS514': CDS_PINID='VSS514';
NODE_NAME     U2 CT16
 '@S9S_MB_2U_LIB.S9S_MB_2U(SCH_1):PAGE40_I11@PURE_QUANTA.SOCKET4677_AZIF0045P001C01CS(CHIPS)':
 'VSS521': CDS_PINID='VSS521';
NODE_NAME     U2 CT4
 '@S9S_MB_2U_LIB.S9S_MB_2U(SCH_1):PAGE40_I11@PURE_QUANTA.SOCKET4677_AZIF0045P001C01CS(CHIPS)':
 'VSS526': CDS_PINID='VSS526';
NODE_NAME     U2 CT8
 '@S9S_MB_2U_LIB.S9S_MB_2U(SCH_1):PAGE40_I11@PURE_QUANTA.SOCKET4677_AZIF0045P001C01CS(CHIPS)':
 'VSS534': CDS_PINID='VSS534';
NODE_NAME     U2 CT89
 '@S9S_MB_2U_LIB.S9S_MB_2U(SCH_1):PAGE40_I11@PURE_QUANTA.SOCKET4677_AZIF0045P001C01CS(CHIPS)':
 'VSS537': CDS_PINID='VSS537';
NODE_NAME     U2 CU25
 '@S9S_MB_2U_LIB.S9S_MB_2U(SCH_1):PAGE40_I11@PURE_QUANTA.SOCKET4677_AZIF0045P001C01CS(CHIPS)':
 'VSS544': CDS_PINID='VSS544';
NODE_NAME     U2 CU72
 '@S9S_MB_2U_LIB.S9S_MB_2U(SCH_1):PAGE40_I11@PURE_QUANTA.SOCKET4677_AZIF0045P001C01CS(CHIPS)':
 'VSS553': CDS_PINID='VSS553';
NODE_NAME     U2 CU78
 '@S9S_MB_2U_LIB.S9S_MB_2U(SCH_1):PAGE40_I11@PURE_QUANTA.SOCKET4677_AZIF0045P001C01CS(CHIPS)':
 'VSS554': CDS_PINID='VSS554';
NODE_NAME     U2 CV16
 '@S9S_MB_2U_LIB.S9S_MB_2U(SCH_1):PAGE40_I11@PURE_QUANTA.SOCKET4677_AZIF0045P001C01CS(CHIPS)':
 'VSS558': CDS_PINID='VSS558';
NODE_NAME     U2 CV26
 '@S9S_MB_2U_LIB.S9S_MB_2U(SCH_1):PAGE40_I11@PURE_QUANTA.SOCKET4677_AZIF0045P001C01CS(CHIPS)':
 'VSS562': CDS_PINID='VSS562';
NODE_NAME     U2 CV79
 '@S9S_MB_2U_LIB.S9S_MB_2U(SCH_1):PAGE40_I11@PURE_QUANTA.SOCKET4677_AZIF0045P001C01CS(CHIPS)':
 'VSS571': CDS_PINID='VSS571';
NODE_NAME     U2 CW33
 '@S9S_MB_2U_LIB.S9S_MB_2U(SCH_1):PAGE40_I11@PURE_QUANTA.SOCKET4677_AZIF0045P001C01CS(CHIPS)':
 'VSS583': CDS_PINID='VSS583';
NODE_NAME     U2 CW70
 '@S9S_MB_2U_LIB.S9S_MB_2U(SCH_1):PAGE40_I11@PURE_QUANTA.SOCKET4677_AZIF0045P001C01CS(CHIPS)':
 'VSS595': CDS_PINID='VSS595';
NODE_NAME     U2 CY4
 '@S9S_MB_2U_LIB.S9S_MB_2U(SCH_1):PAGE40_I11@PURE_QUANTA.SOCKET4677_AZIF0045P001C01CS(CHIPS)':
 'VSS611': CDS_PINID='VSS611';
NODE_NAME     U2 DA43
 '@S9S_MB_2U_LIB.S9S_MB_2U(SCH_1):PAGE40_I11@PURE_QUANTA.SOCKET4677_AZIF0045P001C01CS(CHIPS)':
 'VSS679': CDS_PINID='VSS679';
NODE_NAME     U2 DA68
 '@S9S_MB_2U_LIB.S9S_MB_2U(SCH_1):PAGE40_I11@PURE_QUANTA.SOCKET4677_AZIF0045P001C01CS(CHIPS)':
 'VSS690': CDS_PINID='VSS690';
NODE_NAME     U2 DB16
 '@S9S_MB_2U_LIB.S9S_MB_2U(SCH_1):PAGE40_I11@PURE_QUANTA.SOCKET4677_AZIF0045P001C01CS(CHIPS)':
 'VSS699': CDS_PINID='VSS699';
NODE_NAME     U2 DB20
 '@S9S_MB_2U_LIB.S9S_MB_2U(SCH_1):PAGE40_I11@PURE_QUANTA.SOCKET4677_AZIF0045P001C01CS(CHIPS)':
 'VSS700': CDS_PINID='VSS700';
NODE_NAME     U2 DB26
 '@S9S_MB_2U_LIB.S9S_MB_2U(SCH_1):PAGE40_I11@PURE_QUANTA.SOCKET4677_AZIF0045P001C01CS(CHIPS)':
 'VSS702': CDS_PINID='VSS702';
NODE_NAME     U2 DB34
 '@S9S_MB_2U_LIB.S9S_MB_2U(SCH_1):PAGE40_I11@PURE_QUANTA.SOCKET4677_AZIF0045P001C01CS(CHIPS)':
 'VSS705': CDS_PINID='VSS705';
NODE_NAME     U2 DB44
 '@S9S_MB_2U_LIB.S9S_MB_2U(SCH_1):PAGE40_I11@PURE_QUANTA.SOCKET4677_AZIF0045P001C01CS(CHIPS)':
 'VSS709': CDS_PINID='VSS709';
NODE_NAME     U2 DB51
 '@S9S_MB_2U_LIB.S9S_MB_2U(SCH_1):PAGE40_I11@PURE_QUANTA.SOCKET4677_AZIF0045P001C01CS(CHIPS)':
 'VSS711': CDS_PINID='VSS711';
NODE_NAME     U2 DB53
 '@S9S_MB_2U_LIB.S9S_MB_2U(SCH_1):PAGE40_I11@PURE_QUANTA.SOCKET4677_AZIF0045P001C01CS(CHIPS)':
 'VSS712': CDS_PINID='VSS712';
NODE_NAME     U2 DB59
 '@S9S_MB_2U_LIB.S9S_MB_2U(SCH_1):PAGE40_I11@PURE_QUANTA.SOCKET4677_AZIF0045P001C01CS(CHIPS)':
 'VSS714': CDS_PINID='VSS714';
NODE_NAME     U2 DB63
 '@S9S_MB_2U_LIB.S9S_MB_2U(SCH_1):PAGE40_I11@PURE_QUANTA.SOCKET4677_AZIF0045P001C01CS(CHIPS)':
 'VSS715': CDS_PINID='VSS715';
NODE_NAME     U2 DB69
 '@S9S_MB_2U_LIB.S9S_MB_2U(SCH_1):PAGE40_I11@PURE_QUANTA.SOCKET4677_AZIF0045P001C01CS(CHIPS)':
 'VSS717': CDS_PINID='VSS717';
NODE_NAME     U2 DB75
 '@S9S_MB_2U_LIB.S9S_MB_2U(SCH_1):PAGE40_I11@PURE_QUANTA.SOCKET4677_AZIF0045P001C01CS(CHIPS)':
 'VSS719': CDS_PINID='VSS719';
NODE_NAME     U2 CK63
 '@S9S_MB_2U_LIB.S9S_MB_2U(SCH_1):PAGE40_I11@PURE_QUANTA.SOCKET4677_AZIF0045P001C01CS(CHIPS)':
 'VSS744': CDS_PINID='VSS744';
NODE_NAME     U2 CK69
 '@S9S_MB_2U_LIB.S9S_MB_2U(SCH_1):PAGE40_I11@PURE_QUANTA.SOCKET4677_AZIF0045P001C01CS(CHIPS)':
 'VSS745': CDS_PINID='VSS745';
NODE_NAME     U2 CK81
 '@S9S_MB_2U_LIB.S9S_MB_2U(SCH_1):PAGE40_I11@PURE_QUANTA.SOCKET4677_AZIF0045P001C01CS(CHIPS)':
 'VSS749': CDS_PINID='VSS749';
NODE_NAME     U2 CL1
 '@S9S_MB_2U_LIB.S9S_MB_2U(SCH_1):PAGE40_I11@PURE_QUANTA.SOCKET4677_AZIF0045P001C01CS(CHIPS)':
 'VSS750': CDS_PINID='VSS750';
NODE_NAME     U2 CL13
 '@S9S_MB_2U_LIB.S9S_MB_2U(SCH_1):PAGE40_I11@PURE_QUANTA.SOCKET4677_AZIF0045P001C01CS(CHIPS)':
 'VSS751': CDS_PINID='VSS751';
NODE_NAME     U2 CL17
 '@S9S_MB_2U_LIB.S9S_MB_2U(SCH_1):PAGE40_I11@PURE_QUANTA.SOCKET4677_AZIF0045P001C01CS(CHIPS)':
 'VSS752': CDS_PINID='VSS752';
NODE_NAME     U2 CL5
 '@S9S_MB_2U_LIB.S9S_MB_2U(SCH_1):PAGE40_I11@PURE_QUANTA.SOCKET4677_AZIF0045P001C01CS(CHIPS)':
 'VSS754': CDS_PINID='VSS754';
NODE_NAME     U2 CL62
 '@S9S_MB_2U_LIB.S9S_MB_2U(SCH_1):PAGE40_I11@PURE_QUANTA.SOCKET4677_AZIF0045P001C01CS(CHIPS)':
 'VSS755': CDS_PINID='VSS755';
NODE_NAME     U2 CL74
 '@S9S_MB_2U_LIB.S9S_MB_2U(SCH_1):PAGE40_I11@PURE_QUANTA.SOCKET4677_AZIF0045P001C01CS(CHIPS)':
 'VSS756': CDS_PINID='VSS756';
NODE_NAME     U2 CL78
 '@S9S_MB_2U_LIB.S9S_MB_2U(SCH_1):PAGE40_I11@PURE_QUANTA.SOCKET4677_AZIF0045P001C01CS(CHIPS)':
 'VSS757': CDS_PINID='VSS757';
NODE_NAME     U2 CL80
 '@S9S_MB_2U_LIB.S9S_MB_2U(SCH_1):PAGE40_I11@PURE_QUANTA.SOCKET4677_AZIF0045P001C01CS(CHIPS)':
 'VSS758': CDS_PINID='VSS758';
NODE_NAME     U2 CL82
 '@S9S_MB_2U_LIB.S9S_MB_2U(SCH_1):PAGE40_I11@PURE_QUANTA.SOCKET4677_AZIF0045P001C01CS(CHIPS)':
 'VSS759': CDS_PINID='VSS759';
NODE_NAME     U2 CL9
 '@S9S_MB_2U_LIB.S9S_MB_2U(SCH_1):PAGE40_I11@PURE_QUANTA.SOCKET4677_AZIF0045P001C01CS(CHIPS)':
 'VSS760': CDS_PINID='VSS760';
NODE_NAME     U2 CM12
 '@S9S_MB_2U_LIB.S9S_MB_2U(SCH_1):PAGE40_I11@PURE_QUANTA.SOCKET4677_AZIF0045P001C01CS(CHIPS)':
 'VSS761': CDS_PINID='VSS761';
NODE_NAME     U2 CM20
 '@S9S_MB_2U_LIB.S9S_MB_2U(SCH_1):PAGE40_I11@PURE_QUANTA.SOCKET4677_AZIF0045P001C01CS(CHIPS)':
 'VSS762': CDS_PINID='VSS762';
NODE_NAME     U2 CM24
 '@S9S_MB_2U_LIB.S9S_MB_2U(SCH_1):PAGE40_I11@PURE_QUANTA.SOCKET4677_AZIF0045P001C01CS(CHIPS)':
 'VSS763': CDS_PINID='VSS763';
NODE_NAME     U2 CM4
 '@S9S_MB_2U_LIB.S9S_MB_2U(SCH_1):PAGE40_I11@PURE_QUANTA.SOCKET4677_AZIF0045P001C01CS(CHIPS)':
 'VSS764': CDS_PINID='VSS764';
NODE_NAME     U2 CM61
 '@S9S_MB_2U_LIB.S9S_MB_2U(SCH_1):PAGE40_I11@PURE_QUANTA.SOCKET4677_AZIF0045P001C01CS(CHIPS)':
 'VSS765': CDS_PINID='VSS765';
NODE_NAME     U2 CM65
 '@S9S_MB_2U_LIB.S9S_MB_2U(SCH_1):PAGE40_I11@PURE_QUANTA.SOCKET4677_AZIF0045P001C01CS(CHIPS)':
 'VSS766': CDS_PINID='VSS766';
NODE_NAME     U2 CM67
 '@S9S_MB_2U_LIB.S9S_MB_2U(SCH_1):PAGE40_I11@PURE_QUANTA.SOCKET4677_AZIF0045P001C01CS(CHIPS)':
 'VSS767': CDS_PINID='VSS767';
NODE_NAME     U2 CM79
 '@S9S_MB_2U_LIB.S9S_MB_2U(SCH_1):PAGE40_I11@PURE_QUANTA.SOCKET4677_AZIF0045P001C01CS(CHIPS)':
 'VSS768': CDS_PINID='VSS768';
NODE_NAME     U2 CM8
 '@S9S_MB_2U_LIB.S9S_MB_2U(SCH_1):PAGE40_I11@PURE_QUANTA.SOCKET4677_AZIF0045P001C01CS(CHIPS)':
 'VSS769': CDS_PINID='VSS769';
NODE_NAME     U2 CM81
 '@S9S_MB_2U_LIB.S9S_MB_2U(SCH_1):PAGE40_I11@PURE_QUANTA.SOCKET4677_AZIF0045P001C01CS(CHIPS)':
 'VSS770': CDS_PINID='VSS770';
NODE_NAME     U2 CM83
 '@S9S_MB_2U_LIB.S9S_MB_2U(SCH_1):PAGE40_I11@PURE_QUANTA.SOCKET4677_AZIF0045P001C01CS(CHIPS)':
 'VSS771': CDS_PINID='VSS771';
NODE_NAME     U2 CM85
 '@S9S_MB_2U_LIB.S9S_MB_2U(SCH_1):PAGE40_I11@PURE_QUANTA.SOCKET4677_AZIF0045P001C01CS(CHIPS)':
 'VSS772': CDS_PINID='VSS772';
NODE_NAME     U2 CN68
 '@S9S_MB_2U_LIB.S9S_MB_2U(SCH_1):PAGE40_I11@PURE_QUANTA.SOCKET4677_AZIF0045P001C01CS(CHIPS)':
 'VSS773': CDS_PINID='VSS773';
NODE_NAME     U2 CN70
 '@S9S_MB_2U_LIB.S9S_MB_2U(SCH_1):PAGE40_I11@PURE_QUANTA.SOCKET4677_AZIF0045P001C01CS(CHIPS)':
 'VSS774': CDS_PINID='VSS774';
NODE_NAME     U2 CN72
 '@S9S_MB_2U_LIB.S9S_MB_2U(SCH_1):PAGE40_I11@PURE_QUANTA.SOCKET4677_AZIF0045P001C01CS(CHIPS)':
 'VSS775': CDS_PINID='VSS775';
NODE_NAME     U2 CN74
 '@S9S_MB_2U_LIB.S9S_MB_2U(SCH_1):PAGE40_I11@PURE_QUANTA.SOCKET4677_AZIF0045P001C01CS(CHIPS)':
 'VSS777': CDS_PINID='VSS777';
NODE_NAME     U2 CN84
 '@S9S_MB_2U_LIB.S9S_MB_2U(SCH_1):PAGE40_I11@PURE_QUANTA.SOCKET4677_AZIF0045P001C01CS(CHIPS)':
 'VSS778': CDS_PINID='VSS778';
NODE_NAME     U2 CN86
 '@S9S_MB_2U_LIB.S9S_MB_2U(SCH_1):PAGE40_I11@PURE_QUANTA.SOCKET4677_AZIF0045P001C01CS(CHIPS)':
 'VSS779': CDS_PINID='VSS779';
NODE_NAME     U2 CP12
 '@S9S_MB_2U_LIB.S9S_MB_2U(SCH_1):PAGE40_I11@PURE_QUANTA.SOCKET4677_AZIF0045P001C01CS(CHIPS)':
 'VSS780': CDS_PINID='VSS780';
NODE_NAME     U2 CP18
 '@S9S_MB_2U_LIB.S9S_MB_2U(SCH_1):PAGE40_I11@PURE_QUANTA.SOCKET4677_AZIF0045P001C01CS(CHIPS)':
 'VSS781': CDS_PINID='VSS781';
NODE_NAME     U2 CP4
 '@S9S_MB_2U_LIB.S9S_MB_2U(SCH_1):PAGE40_I11@PURE_QUANTA.SOCKET4677_AZIF0045P001C01CS(CHIPS)':
 'VSS782': CDS_PINID='VSS782';
NODE_NAME     U2 CP75
 '@S9S_MB_2U_LIB.S9S_MB_2U(SCH_1):PAGE40_I11@PURE_QUANTA.SOCKET4677_AZIF0045P001C01CS(CHIPS)':
 'VSS783': CDS_PINID='VSS783';
NODE_NAME     U2 CP77
 '@S9S_MB_2U_LIB.S9S_MB_2U(SCH_1):PAGE40_I11@PURE_QUANTA.SOCKET4677_AZIF0045P001C01CS(CHIPS)':
 'VSS784': CDS_PINID='VSS784';
NODE_NAME     U2 CP8
 '@S9S_MB_2U_LIB.S9S_MB_2U(SCH_1):PAGE40_I11@PURE_QUANTA.SOCKET4677_AZIF0045P001C01CS(CHIPS)':
 'VSS785': CDS_PINID='VSS785';
NODE_NAME     U2 CP83
 '@S9S_MB_2U_LIB.S9S_MB_2U(SCH_1):PAGE40_I11@PURE_QUANTA.SOCKET4677_AZIF0045P001C01CS(CHIPS)':
 'VSS786': CDS_PINID='VSS786';
NODE_NAME     U2 CP87
 '@S9S_MB_2U_LIB.S9S_MB_2U(SCH_1):PAGE40_I11@PURE_QUANTA.SOCKET4677_AZIF0045P001C01CS(CHIPS)':
 'VSS787': CDS_PINID='VSS787';
NODE_NAME     U2 CP91
 '@S9S_MB_2U_LIB.S9S_MB_2U(SCH_1):PAGE40_I11@PURE_QUANTA.SOCKET4677_AZIF0045P001C01CS(CHIPS)':
 'VSS788': CDS_PINID='VSS788';
NODE_NAME     U2 CR1
 '@S9S_MB_2U_LIB.S9S_MB_2U(SCH_1):PAGE40_I11@PURE_QUANTA.SOCKET4677_AZIF0045P001C01CS(CHIPS)':
 'VSS789': CDS_PINID='VSS789';
NODE_NAME     U2 CR11
 '@S9S_MB_2U_LIB.S9S_MB_2U(SCH_1):PAGE40_I11@PURE_QUANTA.SOCKET4677_AZIF0045P001C01CS(CHIPS)':
 'VSS790': CDS_PINID='VSS790';
NODE_NAME     U2 CR13
 '@S9S_MB_2U_LIB.S9S_MB_2U(SCH_1):PAGE40_I11@PURE_QUANTA.SOCKET4677_AZIF0045P001C01CS(CHIPS)':
 'VSS792': CDS_PINID='VSS792';
NODE_NAME     U2 CR17
 '@S9S_MB_2U_LIB.S9S_MB_2U(SCH_1):PAGE40_I11@PURE_QUANTA.SOCKET4677_AZIF0045P001C01CS(CHIPS)':
 'VSS793': CDS_PINID='VSS793';
NODE_NAME     U2 CR5
 '@S9S_MB_2U_LIB.S9S_MB_2U(SCH_1):PAGE40_I11@PURE_QUANTA.SOCKET4677_AZIF0045P001C01CS(CHIPS)':
 'VSS794': CDS_PINID='VSS794';
NODE_NAME     U2 CR62
 '@S9S_MB_2U_LIB.S9S_MB_2U(SCH_1):PAGE40_I11@PURE_QUANTA.SOCKET4677_AZIF0045P001C01CS(CHIPS)':
 'VSS795': CDS_PINID='VSS795';
NODE_NAME     U2 CR64
 '@S9S_MB_2U_LIB.S9S_MB_2U(SCH_1):PAGE40_I11@PURE_QUANTA.SOCKET4677_AZIF0045P001C01CS(CHIPS)':
 'VSS796': CDS_PINID='VSS796';
NODE_NAME     U2 CR84
 '@S9S_MB_2U_LIB.S9S_MB_2U(SCH_1):PAGE40_I11@PURE_QUANTA.SOCKET4677_AZIF0045P001C01CS(CHIPS)':
 'VSS797': CDS_PINID='VSS797';
NODE_NAME     U2 CR88
 '@S9S_MB_2U_LIB.S9S_MB_2U(SCH_1):PAGE40_I11@PURE_QUANTA.SOCKET4677_AZIF0045P001C01CS(CHIPS)':
 'VSS800': CDS_PINID='VSS800';
NODE_NAME     U2 CR9
 '@S9S_MB_2U_LIB.S9S_MB_2U(SCH_1):PAGE40_I11@PURE_QUANTA.SOCKET4677_AZIF0045P001C01CS(CHIPS)':
 'VSS801': CDS_PINID='VSS801';
NODE_NAME     U2 CR90
 '@S9S_MB_2U_LIB.S9S_MB_2U(SCH_1):PAGE40_I11@PURE_QUANTA.SOCKET4677_AZIF0045P001C01CS(CHIPS)':
 'VSS803': CDS_PINID='VSS803';
NODE_NAME     U2 CT10
 '@S9S_MB_2U_LIB.S9S_MB_2U(SCH_1):PAGE40_I11@PURE_QUANTA.SOCKET4677_AZIF0045P001C01CS(CHIPS)':
 'VSS804': CDS_PINID='VSS804';
NODE_NAME     U2 CT12
 '@S9S_MB_2U_LIB.S9S_MB_2U(SCH_1):PAGE40_I11@PURE_QUANTA.SOCKET4677_AZIF0045P001C01CS(CHIPS)':
 'VSS805': CDS_PINID='VSS805';
NODE_NAME     U2 CT69
 '@S9S_MB_2U_LIB.S9S_MB_2U(SCH_1):PAGE40_I11@PURE_QUANTA.SOCKET4677_AZIF0045P001C01CS(CHIPS)':
 'VSS810': CDS_PINID='VSS810';
NODE_NAME     U2 CT73
 '@S9S_MB_2U_LIB.S9S_MB_2U(SCH_1):PAGE40_I11@PURE_QUANTA.SOCKET4677_AZIF0045P001C01CS(CHIPS)':
 'VSS811': CDS_PINID='VSS811';
NODE_NAME     U2 CT81
 '@S9S_MB_2U_LIB.S9S_MB_2U(SCH_1):PAGE40_I11@PURE_QUANTA.SOCKET4677_AZIF0045P001C01CS(CHIPS)':
 'VSS812': CDS_PINID='VSS812';
NODE_NAME     U2 CU19
 '@S9S_MB_2U_LIB.S9S_MB_2U(SCH_1):PAGE40_I11@PURE_QUANTA.SOCKET4677_AZIF0045P001C01CS(CHIPS)':
 'VSS813': CDS_PINID='VSS813';
NODE_NAME     U2 CU21
 '@S9S_MB_2U_LIB.S9S_MB_2U(SCH_1):PAGE40_I11@PURE_QUANTA.SOCKET4677_AZIF0045P001C01CS(CHIPS)':
 'VSS814': CDS_PINID='VSS814';
NODE_NAME     U2 CU23
 '@S9S_MB_2U_LIB.S9S_MB_2U(SCH_1):PAGE40_I11@PURE_QUANTA.SOCKET4677_AZIF0045P001C01CS(CHIPS)':
 'VSS815': CDS_PINID='VSS815';
NODE_NAME     U2 CU60
 '@S9S_MB_2U_LIB.S9S_MB_2U(SCH_1):PAGE40_I11@PURE_QUANTA.SOCKET4677_AZIF0045P001C01CS(CHIPS)':
 'VSS816': CDS_PINID='VSS816';
NODE_NAME     U2 CU66
 '@S9S_MB_2U_LIB.S9S_MB_2U(SCH_1):PAGE40_I11@PURE_QUANTA.SOCKET4677_AZIF0045P001C01CS(CHIPS)':
 'VSS818': CDS_PINID='VSS818';
NODE_NAME     U2 CU68
 '@S9S_MB_2U_LIB.S9S_MB_2U(SCH_1):PAGE40_I11@PURE_QUANTA.SOCKET4677_AZIF0045P001C01CS(CHIPS)':
 'VSS819': CDS_PINID='VSS819';
NODE_NAME     U2 CU84
 '@S9S_MB_2U_LIB.S9S_MB_2U(SCH_1):PAGE40_I11@PURE_QUANTA.SOCKET4677_AZIF0045P001C01CS(CHIPS)':
 'VSS822': CDS_PINID='VSS822';
NODE_NAME     U2 CU88
 '@S9S_MB_2U_LIB.S9S_MB_2U(SCH_1):PAGE40_I11@PURE_QUANTA.SOCKET4677_AZIF0045P001C01CS(CHIPS)':
 'VSS823': CDS_PINID='VSS823';
NODE_NAME     U2 CV12
 '@S9S_MB_2U_LIB.S9S_MB_2U(SCH_1):PAGE40_I11@PURE_QUANTA.SOCKET4677_AZIF0045P001C01CS(CHIPS)':
 'VSS824': CDS_PINID='VSS824';
NODE_NAME     U2 CV4
 '@S9S_MB_2U_LIB.S9S_MB_2U(SCH_1):PAGE40_I11@PURE_QUANTA.SOCKET4677_AZIF0045P001C01CS(CHIPS)':
 'VSS825': CDS_PINID='VSS825';
NODE_NAME     U2 CV75
 '@S9S_MB_2U_LIB.S9S_MB_2U(SCH_1):PAGE40_I11@PURE_QUANTA.SOCKET4677_AZIF0045P001C01CS(CHIPS)':
 'VSS826': CDS_PINID='VSS826';
NODE_NAME     U2 CV8
 '@S9S_MB_2U_LIB.S9S_MB_2U(SCH_1):PAGE40_I11@PURE_QUANTA.SOCKET4677_AZIF0045P001C01CS(CHIPS)':
 'VSS827': CDS_PINID='VSS827';
NODE_NAME     U2 CV83
 '@S9S_MB_2U_LIB.S9S_MB_2U(SCH_1):PAGE40_I11@PURE_QUANTA.SOCKET4677_AZIF0045P001C01CS(CHIPS)':
 'VSS828': CDS_PINID='VSS828';
NODE_NAME     U2 CV87
 '@S9S_MB_2U_LIB.S9S_MB_2U(SCH_1):PAGE40_I11@PURE_QUANTA.SOCKET4677_AZIF0045P001C01CS(CHIPS)':
 'VSS831': CDS_PINID='VSS831';
NODE_NAME     U2 CV91
 '@S9S_MB_2U_LIB.S9S_MB_2U(SCH_1):PAGE40_I11@PURE_QUANTA.SOCKET4677_AZIF0045P001C01CS(CHIPS)':
 'VSS833': CDS_PINID='VSS833';
NODE_NAME     U2 CW1
 '@S9S_MB_2U_LIB.S9S_MB_2U(SCH_1):PAGE40_I11@PURE_QUANTA.SOCKET4677_AZIF0045P001C01CS(CHIPS)':
 'VSS834': CDS_PINID='VSS834';
NODE_NAME     U2 CW13
 '@S9S_MB_2U_LIB.S9S_MB_2U(SCH_1):PAGE40_I11@PURE_QUANTA.SOCKET4677_AZIF0045P001C01CS(CHIPS)':
 'VSS836': CDS_PINID='VSS836';
NODE_NAME     U2 CW17
 '@S9S_MB_2U_LIB.S9S_MB_2U(SCH_1):PAGE40_I11@PURE_QUANTA.SOCKET4677_AZIF0045P001C01CS(CHIPS)':
 'VSS837': CDS_PINID='VSS837';
NODE_NAME     U2 CW5
 '@S9S_MB_2U_LIB.S9S_MB_2U(SCH_1):PAGE40_I11@PURE_QUANTA.SOCKET4677_AZIF0045P001C01CS(CHIPS)':
 'VSS838': CDS_PINID='VSS838';
NODE_NAME     U2 CW72
 '@S9S_MB_2U_LIB.S9S_MB_2U(SCH_1):PAGE40_I11@PURE_QUANTA.SOCKET4677_AZIF0045P001C01CS(CHIPS)':
 'VSS840': CDS_PINID='VSS840';
NODE_NAME     U2 CW78
 '@S9S_MB_2U_LIB.S9S_MB_2U(SCH_1):PAGE40_I11@PURE_QUANTA.SOCKET4677_AZIF0045P001C01CS(CHIPS)':
 'VSS843': CDS_PINID='VSS843';
NODE_NAME     U2 CW84
 '@S9S_MB_2U_LIB.S9S_MB_2U(SCH_1):PAGE40_I11@PURE_QUANTA.SOCKET4677_AZIF0045P001C01CS(CHIPS)':
 'VSS846': CDS_PINID='VSS846';
NODE_NAME     U2 CW88
 '@S9S_MB_2U_LIB.S9S_MB_2U(SCH_1):PAGE40_I11@PURE_QUANTA.SOCKET4677_AZIF0045P001C01CS(CHIPS)':
 'VSS848': CDS_PINID='VSS848';
NODE_NAME     U2 CW9
 '@S9S_MB_2U_LIB.S9S_MB_2U(SCH_1):PAGE40_I11@PURE_QUANTA.SOCKET4677_AZIF0045P001C01CS(CHIPS)':
 'VSS850': CDS_PINID='VSS850';
NODE_NAME     U2 CY12
 '@S9S_MB_2U_LIB.S9S_MB_2U(SCH_1):PAGE40_I11@PURE_QUANTA.SOCKET4677_AZIF0045P001C01CS(CHIPS)':
 'VSS851': CDS_PINID='VSS851';
NODE_NAME     U2 CY16
 '@S9S_MB_2U_LIB.S9S_MB_2U(SCH_1):PAGE40_I11@PURE_QUANTA.SOCKET4677_AZIF0045P001C01CS(CHIPS)':
 'VSS852': CDS_PINID='VSS852';
NODE_NAME     U2 CY18
 '@S9S_MB_2U_LIB.S9S_MB_2U(SCH_1):PAGE40_I11@PURE_QUANTA.SOCKET4677_AZIF0045P001C01CS(CHIPS)':
 'VSS853': CDS_PINID='VSS853';
NODE_NAME     U2 CY26
 '@S9S_MB_2U_LIB.S9S_MB_2U(SCH_1):PAGE40_I11@PURE_QUANTA.SOCKET4677_AZIF0045P001C01CS(CHIPS)':
 'VSS854': CDS_PINID='VSS854';
NODE_NAME     U2 CY30
 '@S9S_MB_2U_LIB.S9S_MB_2U(SCH_1):PAGE40_I11@PURE_QUANTA.SOCKET4677_AZIF0045P001C01CS(CHIPS)':
 'VSS855': CDS_PINID='VSS855';
NODE_NAME     U2 CY63
 '@S9S_MB_2U_LIB.S9S_MB_2U(SCH_1):PAGE40_I11@PURE_QUANTA.SOCKET4677_AZIF0045P001C01CS(CHIPS)':
 'VSS856': CDS_PINID='VSS856';
NODE_NAME     U2 CY73
 '@S9S_MB_2U_LIB.S9S_MB_2U(SCH_1):PAGE40_I11@PURE_QUANTA.SOCKET4677_AZIF0045P001C01CS(CHIPS)':
 'VSS858': CDS_PINID='VSS858';
NODE_NAME     U2 CY77
 '@S9S_MB_2U_LIB.S9S_MB_2U(SCH_1):PAGE40_I11@PURE_QUANTA.SOCKET4677_AZIF0045P001C01CS(CHIPS)':
 'VSS859': CDS_PINID='VSS859';
NODE_NAME     U2 CY8
 '@S9S_MB_2U_LIB.S9S_MB_2U(SCH_1):PAGE40_I11@PURE_QUANTA.SOCKET4677_AZIF0045P001C01CS(CHIPS)':
 'VSS860': CDS_PINID='VSS860';
NODE_NAME     U2 CY81
 '@S9S_MB_2U_LIB.S9S_MB_2U(SCH_1):PAGE40_I11@PURE_QUANTA.SOCKET4677_AZIF0045P001C01CS(CHIPS)':
 'VSS862': CDS_PINID='VSS862';
NODE_NAME     U2 CY83
 '@S9S_MB_2U_LIB.S9S_MB_2U(SCH_1):PAGE40_I11@PURE_QUANTA.SOCKET4677_AZIF0045P001C01CS(CHIPS)':
 'VSS863': CDS_PINID='VSS863';
NODE_NAME     U2 DA19
 '@S9S_MB_2U_LIB.S9S_MB_2U(SCH_1):PAGE40_I11@PURE_QUANTA.SOCKET4677_AZIF0045P001C01CS(CHIPS)':
 'VSS910': CDS_PINID='VSS910';
NODE_NAME     U2 DA23
 '@S9S_MB_2U_LIB.S9S_MB_2U(SCH_1):PAGE40_I11@PURE_QUANTA.SOCKET4677_AZIF0045P001C01CS(CHIPS)':
 'VSS911': CDS_PINID='VSS911';
NODE_NAME     U2 DA25
 '@S9S_MB_2U_LIB.S9S_MB_2U(SCH_1):PAGE40_I11@PURE_QUANTA.SOCKET4677_AZIF0045P001C01CS(CHIPS)':
 'VSS912': CDS_PINID='VSS912';
NODE_NAME     U2 DA29
 '@S9S_MB_2U_LIB.S9S_MB_2U(SCH_1):PAGE40_I11@PURE_QUANTA.SOCKET4677_AZIF0045P001C01CS(CHIPS)':
 'VSS913': CDS_PINID='VSS913';
NODE_NAME     U2 DA31
 '@S9S_MB_2U_LIB.S9S_MB_2U(SCH_1):PAGE40_I11@PURE_QUANTA.SOCKET4677_AZIF0045P001C01CS(CHIPS)':
 'VSS914': CDS_PINID='VSS914';
NODE_NAME     U2 DA33
 '@S9S_MB_2U_LIB.S9S_MB_2U(SCH_1):PAGE40_I11@PURE_QUANTA.SOCKET4677_AZIF0045P001C01CS(CHIPS)':
 'VSS915': CDS_PINID='VSS915';
NODE_NAME     U2 DA35
 '@S9S_MB_2U_LIB.S9S_MB_2U(SCH_1):PAGE40_I11@PURE_QUANTA.SOCKET4677_AZIF0045P001C01CS(CHIPS)':
 'VSS916': CDS_PINID='VSS916';
NODE_NAME     U2 DA37
 '@S9S_MB_2U_LIB.S9S_MB_2U(SCH_1):PAGE40_I11@PURE_QUANTA.SOCKET4677_AZIF0045P001C01CS(CHIPS)':
 'VSS917': CDS_PINID='VSS917';
NODE_NAME     U2 DA41
 '@S9S_MB_2U_LIB.S9S_MB_2U(SCH_1):PAGE40_I11@PURE_QUANTA.SOCKET4677_AZIF0045P001C01CS(CHIPS)':
 'VSS918': CDS_PINID='VSS918';
NODE_NAME     U2 DA48
 '@S9S_MB_2U_LIB.S9S_MB_2U(SCH_1):PAGE40_I11@PURE_QUANTA.SOCKET4677_AZIF0045P001C01CS(CHIPS)':
 'VSS919': CDS_PINID='VSS919';
NODE_NAME     U2 DA50
 '@S9S_MB_2U_LIB.S9S_MB_2U(SCH_1):PAGE40_I11@PURE_QUANTA.SOCKET4677_AZIF0045P001C01CS(CHIPS)':
 'VSS920': CDS_PINID='VSS920';
NODE_NAME     U2 DA54
 '@S9S_MB_2U_LIB.S9S_MB_2U(SCH_1):PAGE40_I11@PURE_QUANTA.SOCKET4677_AZIF0045P001C01CS(CHIPS)':
 'VSS921': CDS_PINID='VSS921';
NODE_NAME     U2 DA56
 '@S9S_MB_2U_LIB.S9S_MB_2U(SCH_1):PAGE40_I11@PURE_QUANTA.SOCKET4677_AZIF0045P001C01CS(CHIPS)':
 'VSS922': CDS_PINID='VSS922';
NODE_NAME     U2 DA58
 '@S9S_MB_2U_LIB.S9S_MB_2U(SCH_1):PAGE40_I11@PURE_QUANTA.SOCKET4677_AZIF0045P001C01CS(CHIPS)':
 'VSS923': CDS_PINID='VSS923';
NODE_NAME     U2 DA60
 '@S9S_MB_2U_LIB.S9S_MB_2U(SCH_1):PAGE40_I11@PURE_QUANTA.SOCKET4677_AZIF0045P001C01CS(CHIPS)':
 'VSS924': CDS_PINID='VSS924';
NODE_NAME     U2 DA62
 '@S9S_MB_2U_LIB.S9S_MB_2U(SCH_1):PAGE40_I11@PURE_QUANTA.SOCKET4677_AZIF0045P001C01CS(CHIPS)':
 'VSS925': CDS_PINID='VSS925';
NODE_NAME     U2 DA66
 '@S9S_MB_2U_LIB.S9S_MB_2U(SCH_1):PAGE40_I11@PURE_QUANTA.SOCKET4677_AZIF0045P001C01CS(CHIPS)':
 'VSS926': CDS_PINID='VSS926';
NODE_NAME     U2 DA72
 '@S9S_MB_2U_LIB.S9S_MB_2U(SCH_1):PAGE40_I11@PURE_QUANTA.SOCKET4677_AZIF0045P001C01CS(CHIPS)':
 'VSS927': CDS_PINID='VSS927';
NODE_NAME     U2 DA74
 '@S9S_MB_2U_LIB.S9S_MB_2U(SCH_1):PAGE40_I11@PURE_QUANTA.SOCKET4677_AZIF0045P001C01CS(CHIPS)':
 'VSS928': CDS_PINID='VSS928';
NODE_NAME     U2 DA80
 '@S9S_MB_2U_LIB.S9S_MB_2U(SCH_1):PAGE40_I11@PURE_QUANTA.SOCKET4677_AZIF0045P001C01CS(CHIPS)':
 'VSS929': CDS_PINID='VSS929';
NODE_NAME     U2 DA82
 '@S9S_MB_2U_LIB.S9S_MB_2U(SCH_1):PAGE40_I11@PURE_QUANTA.SOCKET4677_AZIF0045P001C01CS(CHIPS)':
 'VSS930': CDS_PINID='VSS930';
NODE_NAME     U2 DA84
 '@S9S_MB_2U_LIB.S9S_MB_2U(SCH_1):PAGE40_I11@PURE_QUANTA.SOCKET4677_AZIF0045P001C01CS(CHIPS)':
 'VSS931': CDS_PINID='VSS931';
NODE_NAME     U2 DA88
 '@S9S_MB_2U_LIB.S9S_MB_2U(SCH_1):PAGE40_I11@PURE_QUANTA.SOCKET4677_AZIF0045P001C01CS(CHIPS)':
 'VSS932': CDS_PINID='VSS932';
NODE_NAME     U2 DB12
 '@S9S_MB_2U_LIB.S9S_MB_2U(SCH_1):PAGE40_I11@PURE_QUANTA.SOCKET4677_AZIF0045P001C01CS(CHIPS)':
 'VSS933': CDS_PINID='VSS933';
NODE_NAME     U2 DB22
 '@S9S_MB_2U_LIB.S9S_MB_2U(SCH_1):PAGE40_I11@PURE_QUANTA.SOCKET4677_AZIF0045P001C01CS(CHIPS)':
 'VSS935': CDS_PINID='VSS935';
NODE_NAME     U2 DB28
 '@S9S_MB_2U_LIB.S9S_MB_2U(SCH_1):PAGE40_I11@PURE_QUANTA.SOCKET4677_AZIF0045P001C01CS(CHIPS)':
 'VSS936': CDS_PINID='VSS936';
NODE_NAME     U2 DB32
 '@S9S_MB_2U_LIB.S9S_MB_2U(SCH_1):PAGE40_I11@PURE_QUANTA.SOCKET4677_AZIF0045P001C01CS(CHIPS)':
 'VSS937': CDS_PINID='VSS937';
NODE_NAME     U2 DB38
 '@S9S_MB_2U_LIB.S9S_MB_2U(SCH_1):PAGE40_I11@PURE_QUANTA.SOCKET4677_AZIF0045P001C01CS(CHIPS)':
 'VSS938': CDS_PINID='VSS938';
NODE_NAME     U2 DB4
 '@S9S_MB_2U_LIB.S9S_MB_2U(SCH_1):PAGE40_I11@PURE_QUANTA.SOCKET4677_AZIF0045P001C01CS(CHIPS)':
 'VSS939': CDS_PINID='VSS939';
NODE_NAME     U2 DB40
 '@S9S_MB_2U_LIB.S9S_MB_2U(SCH_1):PAGE40_I11@PURE_QUANTA.SOCKET4677_AZIF0045P001C01CS(CHIPS)':
 'VSS940': CDS_PINID='VSS940';
NODE_NAME     U2 DB47
 '@S9S_MB_2U_LIB.S9S_MB_2U(SCH_1):PAGE40_I11@PURE_QUANTA.SOCKET4677_AZIF0045P001C01CS(CHIPS)':
 'VSS941': CDS_PINID='VSS941';
NODE_NAME     U2 DB57
 '@S9S_MB_2U_LIB.S9S_MB_2U(SCH_1):PAGE40_I11@PURE_QUANTA.SOCKET4677_AZIF0045P001C01CS(CHIPS)':
 'VSS942': CDS_PINID='VSS942';
NODE_NAME     U2 DB65
 '@S9S_MB_2U_LIB.S9S_MB_2U(SCH_1):PAGE40_I11@PURE_QUANTA.SOCKET4677_AZIF0045P001C01CS(CHIPS)':
 'VSS943': CDS_PINID='VSS943';
NODE_NAME     U2 DB71
 '@S9S_MB_2U_LIB.S9S_MB_2U(SCH_1):PAGE40_I11@PURE_QUANTA.SOCKET4677_AZIF0045P001C01CS(CHIPS)':
 'VSS944': CDS_PINID='VSS944';
NODE_NAME     U2 DB77
 '@S9S_MB_2U_LIB.S9S_MB_2U(SCH_1):PAGE40_I11@PURE_QUANTA.SOCKET4677_AZIF0045P001C01CS(CHIPS)':
 'VSS946': CDS_PINID='VSS946';
NODE_NAME     U2 DB8
 '@S9S_MB_2U_LIB.S9S_MB_2U(SCH_1):PAGE40_I11@PURE_QUANTA.SOCKET4677_AZIF0045P001C01CS(CHIPS)':
 'VSS947': CDS_PINID='VSS947';
NODE_NAME     U2 DB87
 '@S9S_MB_2U_LIB.S9S_MB_2U(SCH_1):PAGE40_I11@PURE_QUANTA.SOCKET4677_AZIF0045P001C01CS(CHIPS)':
 'VSS948': CDS_PINID='VSS948';
NODE_NAME     U2 CJ76
 '@S9S_MB_2U_LIB.S9S_MB_2U(SCH_1):PAGE40_I12@PURE_QUANTA.SOCKET4677_AZIF0045P001C01CS(CHIPS)':
 'VSS383': CDS_PINID='VSS383';
NODE_NAME     U2 CK4
 '@S9S_MB_2U_LIB.S9S_MB_2U(SCH_1):PAGE40_I12@PURE_QUANTA.SOCKET4677_AZIF0045P001C01CS(CHIPS)':
 'VSS396': CDS_PINID='VSS396';
NODE_NAME     U2 BR35
 '@S9S_MB_2U_LIB.S9S_MB_2U(SCH_1):PAGE40_I12@PURE_QUANTA.SOCKET4677_AZIF0045P001C01CS(CHIPS)':
 'VSS542': CDS_PINID='VSS542';
NODE_NAME     U2 BR37
 '@S9S_MB_2U_LIB.S9S_MB_2U(SCH_1):PAGE40_I12@PURE_QUANTA.SOCKET4677_AZIF0045P001C01CS(CHIPS)':
 'VSS543': CDS_PINID='VSS543';
NODE_NAME     U2 BR39
 '@S9S_MB_2U_LIB.S9S_MB_2U(SCH_1):PAGE40_I12@PURE_QUANTA.SOCKET4677_AZIF0045P001C01CS(CHIPS)':
 'VSS545': CDS_PINID='VSS545';
NODE_NAME     U2 BR41
 '@S9S_MB_2U_LIB.S9S_MB_2U(SCH_1):PAGE40_I12@PURE_QUANTA.SOCKET4677_AZIF0045P001C01CS(CHIPS)':
 'VSS546': CDS_PINID='VSS546';
NODE_NAME     U2 BR43
 '@S9S_MB_2U_LIB.S9S_MB_2U(SCH_1):PAGE40_I12@PURE_QUANTA.SOCKET4677_AZIF0045P001C01CS(CHIPS)':
 'VSS547': CDS_PINID='VSS547';
NODE_NAME     U2 BR45
 '@S9S_MB_2U_LIB.S9S_MB_2U(SCH_1):PAGE40_I12@PURE_QUANTA.SOCKET4677_AZIF0045P001C01CS(CHIPS)':
 'VSS548': CDS_PINID='VSS548';
NODE_NAME     U2 BR48
 '@S9S_MB_2U_LIB.S9S_MB_2U(SCH_1):PAGE40_I12@PURE_QUANTA.SOCKET4677_AZIF0045P001C01CS(CHIPS)':
 'VSS549': CDS_PINID='VSS549';
NODE_NAME     U2 BR50
 '@S9S_MB_2U_LIB.S9S_MB_2U(SCH_1):PAGE40_I12@PURE_QUANTA.SOCKET4677_AZIF0045P001C01CS(CHIPS)':
 'VSS550': CDS_PINID='VSS550';
NODE_NAME     U2 BR52
 '@S9S_MB_2U_LIB.S9S_MB_2U(SCH_1):PAGE40_I12@PURE_QUANTA.SOCKET4677_AZIF0045P001C01CS(CHIPS)':
 'VSS551': CDS_PINID='VSS551';
NODE_NAME     U2 BR54
 '@S9S_MB_2U_LIB.S9S_MB_2U(SCH_1):PAGE40_I12@PURE_QUANTA.SOCKET4677_AZIF0045P001C01CS(CHIPS)':
 'VSS552': CDS_PINID='VSS552';
NODE_NAME     U2 BR56
 '@S9S_MB_2U_LIB.S9S_MB_2U(SCH_1):PAGE40_I12@PURE_QUANTA.SOCKET4677_AZIF0045P001C01CS(CHIPS)':
 'VSS555': CDS_PINID='VSS555';
NODE_NAME     U2 BR58
 '@S9S_MB_2U_LIB.S9S_MB_2U(SCH_1):PAGE40_I12@PURE_QUANTA.SOCKET4677_AZIF0045P001C01CS(CHIPS)':
 'VSS556': CDS_PINID='VSS556';
NODE_NAME     U2 BR64
 '@S9S_MB_2U_LIB.S9S_MB_2U(SCH_1):PAGE40_I12@PURE_QUANTA.SOCKET4677_AZIF0045P001C01CS(CHIPS)':
 'VSS557': CDS_PINID='VSS557';
NODE_NAME     U2 BR66
 '@S9S_MB_2U_LIB.S9S_MB_2U(SCH_1):PAGE40_I12@PURE_QUANTA.SOCKET4677_AZIF0045P001C01CS(CHIPS)':
 'VSS559': CDS_PINID='VSS559';
NODE_NAME     U2 BR68
 '@S9S_MB_2U_LIB.S9S_MB_2U(SCH_1):PAGE40_I12@PURE_QUANTA.SOCKET4677_AZIF0045P001C01CS(CHIPS)':
 'VSS560': CDS_PINID='VSS560';
NODE_NAME     U2 BR70
 '@S9S_MB_2U_LIB.S9S_MB_2U(SCH_1):PAGE40_I12@PURE_QUANTA.SOCKET4677_AZIF0045P001C01CS(CHIPS)':
 'VSS561': CDS_PINID='VSS561';
NODE_NAME     U2 BR72
 '@S9S_MB_2U_LIB.S9S_MB_2U(SCH_1):PAGE40_I12@PURE_QUANTA.SOCKET4677_AZIF0045P001C01CS(CHIPS)':
 'VSS563': CDS_PINID='VSS563';
NODE_NAME     U2 BR74
 '@S9S_MB_2U_LIB.S9S_MB_2U(SCH_1):PAGE40_I12@PURE_QUANTA.SOCKET4677_AZIF0045P001C01CS(CHIPS)':
 'VSS564': CDS_PINID='VSS564';
NODE_NAME     U2 BR76
 '@S9S_MB_2U_LIB.S9S_MB_2U(SCH_1):PAGE40_I12@PURE_QUANTA.SOCKET4677_AZIF0045P001C01CS(CHIPS)':
 'VSS565': CDS_PINID='VSS565';
NODE_NAME     U2 BR80
 '@S9S_MB_2U_LIB.S9S_MB_2U(SCH_1):PAGE40_I12@PURE_QUANTA.SOCKET4677_AZIF0045P001C01CS(CHIPS)':
 'VSS566': CDS_PINID='VSS566';
NODE_NAME     U2 BR82
 '@S9S_MB_2U_LIB.S9S_MB_2U(SCH_1):PAGE40_I12@PURE_QUANTA.SOCKET4677_AZIF0045P001C01CS(CHIPS)':
 'VSS567': CDS_PINID='VSS567';
NODE_NAME     U2 BR84
 '@S9S_MB_2U_LIB.S9S_MB_2U(SCH_1):PAGE40_I12@PURE_QUANTA.SOCKET4677_AZIF0045P001C01CS(CHIPS)':
 'VSS568': CDS_PINID='VSS568';
NODE_NAME     U2 BR86
 '@S9S_MB_2U_LIB.S9S_MB_2U(SCH_1):PAGE40_I12@PURE_QUANTA.SOCKET4677_AZIF0045P001C01CS(CHIPS)':
 'VSS569': CDS_PINID='VSS569';
NODE_NAME     U2 BR88
 '@S9S_MB_2U_LIB.S9S_MB_2U(SCH_1):PAGE40_I12@PURE_QUANTA.SOCKET4677_AZIF0045P001C01CS(CHIPS)':
 'VSS570': CDS_PINID='VSS570';
NODE_NAME     U2 BR90
 '@S9S_MB_2U_LIB.S9S_MB_2U(SCH_1):PAGE40_I12@PURE_QUANTA.SOCKET4677_AZIF0045P001C01CS(CHIPS)':
 'VSS573': CDS_PINID='VSS573';
NODE_NAME     U2 BT12
 '@S9S_MB_2U_LIB.S9S_MB_2U(SCH_1):PAGE40_I12@PURE_QUANTA.SOCKET4677_AZIF0045P001C01CS(CHIPS)':
 'VSS574': CDS_PINID='VSS574';
NODE_NAME     U2 BT16
 '@S9S_MB_2U_LIB.S9S_MB_2U(SCH_1):PAGE40_I12@PURE_QUANTA.SOCKET4677_AZIF0045P001C01CS(CHIPS)':
 'VSS575': CDS_PINID='VSS575';
NODE_NAME     U2 BT20
 '@S9S_MB_2U_LIB.S9S_MB_2U(SCH_1):PAGE40_I12@PURE_QUANTA.SOCKET4677_AZIF0045P001C01CS(CHIPS)':
 'VSS576': CDS_PINID='VSS576';
NODE_NAME     U2 BT4
 '@S9S_MB_2U_LIB.S9S_MB_2U(SCH_1):PAGE40_I12@PURE_QUANTA.SOCKET4677_AZIF0045P001C01CS(CHIPS)':
 'VSS577': CDS_PINID='VSS577';
NODE_NAME     U2 BT8
 '@S9S_MB_2U_LIB.S9S_MB_2U(SCH_1):PAGE40_I12@PURE_QUANTA.SOCKET4677_AZIF0045P001C01CS(CHIPS)':
 'VSS578': CDS_PINID='VSS578';
NODE_NAME     U2 BU15
 '@S9S_MB_2U_LIB.S9S_MB_2U(SCH_1):PAGE40_I12@PURE_QUANTA.SOCKET4677_AZIF0045P001C01CS(CHIPS)':
 'VSS579': CDS_PINID='VSS579';
NODE_NAME     U2 BU19
 '@S9S_MB_2U_LIB.S9S_MB_2U(SCH_1):PAGE40_I12@PURE_QUANTA.SOCKET4677_AZIF0045P001C01CS(CHIPS)':
 'VSS580': CDS_PINID='VSS580';
NODE_NAME     U2 BU21
 '@S9S_MB_2U_LIB.S9S_MB_2U(SCH_1):PAGE40_I12@PURE_QUANTA.SOCKET4677_AZIF0045P001C01CS(CHIPS)':
 'VSS581': CDS_PINID='VSS581';
NODE_NAME     U2 BU23
 '@S9S_MB_2U_LIB.S9S_MB_2U(SCH_1):PAGE40_I12@PURE_QUANTA.SOCKET4677_AZIF0045P001C01CS(CHIPS)':
 'VSS582': CDS_PINID='VSS582';
NODE_NAME     U2 BU25
 '@S9S_MB_2U_LIB.S9S_MB_2U(SCH_1):PAGE40_I12@PURE_QUANTA.SOCKET4677_AZIF0045P001C01CS(CHIPS)':
 'VSS584': CDS_PINID='VSS584';
NODE_NAME     U2 BU31
 '@S9S_MB_2U_LIB.S9S_MB_2U(SCH_1):PAGE40_I12@PURE_QUANTA.SOCKET4677_AZIF0045P001C01CS(CHIPS)':
 'VSS585': CDS_PINID='VSS585';
NODE_NAME     U2 BU7
 '@S9S_MB_2U_LIB.S9S_MB_2U(SCH_1):PAGE40_I12@PURE_QUANTA.SOCKET4677_AZIF0045P001C01CS(CHIPS)':
 'VSS586': CDS_PINID='VSS586';
NODE_NAME     U2 BV12
 '@S9S_MB_2U_LIB.S9S_MB_2U(SCH_1):PAGE40_I12@PURE_QUANTA.SOCKET4677_AZIF0045P001C01CS(CHIPS)':
 'VSS587': CDS_PINID='VSS587';
NODE_NAME     U2 BV16
 '@S9S_MB_2U_LIB.S9S_MB_2U(SCH_1):PAGE40_I12@PURE_QUANTA.SOCKET4677_AZIF0045P001C01CS(CHIPS)':
 'VSS588': CDS_PINID='VSS588';
NODE_NAME     U2 BV18
 '@S9S_MB_2U_LIB.S9S_MB_2U(SCH_1):PAGE40_I12@PURE_QUANTA.SOCKET4677_AZIF0045P001C01CS(CHIPS)':
 'VSS589': CDS_PINID='VSS589';
NODE_NAME     U2 BV2
 '@S9S_MB_2U_LIB.S9S_MB_2U(SCH_1):PAGE40_I12@PURE_QUANTA.SOCKET4677_AZIF0045P001C01CS(CHIPS)':
 'VSS590': CDS_PINID='VSS590';
NODE_NAME     U2 BV20
 '@S9S_MB_2U_LIB.S9S_MB_2U(SCH_1):PAGE40_I12@PURE_QUANTA.SOCKET4677_AZIF0045P001C01CS(CHIPS)':
 'VSS591': CDS_PINID='VSS591';
NODE_NAME     U2 BV4
 '@S9S_MB_2U_LIB.S9S_MB_2U(SCH_1):PAGE40_I12@PURE_QUANTA.SOCKET4677_AZIF0045P001C01CS(CHIPS)':
 'VSS592': CDS_PINID='VSS592';
NODE_NAME     U2 BV6
 '@S9S_MB_2U_LIB.S9S_MB_2U(SCH_1):PAGE40_I12@PURE_QUANTA.SOCKET4677_AZIF0045P001C01CS(CHIPS)':
 'VSS593': CDS_PINID='VSS593';
NODE_NAME     U2 BV8
 '@S9S_MB_2U_LIB.S9S_MB_2U(SCH_1):PAGE40_I12@PURE_QUANTA.SOCKET4677_AZIF0045P001C01CS(CHIPS)':
 'VSS594': CDS_PINID='VSS594';
NODE_NAME     U2 BW13
 '@S9S_MB_2U_LIB.S9S_MB_2U(SCH_1):PAGE40_I12@PURE_QUANTA.SOCKET4677_AZIF0045P001C01CS(CHIPS)':
 'VSS596': CDS_PINID='VSS596';
NODE_NAME     U2 BW17
 '@S9S_MB_2U_LIB.S9S_MB_2U(SCH_1):PAGE40_I12@PURE_QUANTA.SOCKET4677_AZIF0045P001C01CS(CHIPS)':
 'VSS597': CDS_PINID='VSS597';
NODE_NAME     U2 BW27
 '@S9S_MB_2U_LIB.S9S_MB_2U(SCH_1):PAGE40_I12@PURE_QUANTA.SOCKET4677_AZIF0045P001C01CS(CHIPS)':
 'VSS598': CDS_PINID='VSS598';
NODE_NAME     U2 BW29
 '@S9S_MB_2U_LIB.S9S_MB_2U(SCH_1):PAGE40_I12@PURE_QUANTA.SOCKET4677_AZIF0045P001C01CS(CHIPS)':
 'VSS599': CDS_PINID='VSS599';
NODE_NAME     U2 BW3
 '@S9S_MB_2U_LIB.S9S_MB_2U(SCH_1):PAGE40_I12@PURE_QUANTA.SOCKET4677_AZIF0045P001C01CS(CHIPS)':
 'VSS600': CDS_PINID='VSS600';
NODE_NAME     U2 BW31
 '@S9S_MB_2U_LIB.S9S_MB_2U(SCH_1):PAGE40_I12@PURE_QUANTA.SOCKET4677_AZIF0045P001C01CS(CHIPS)':
 'VSS601': CDS_PINID='VSS601';
NODE_NAME     U2 BW5
 '@S9S_MB_2U_LIB.S9S_MB_2U(SCH_1):PAGE40_I12@PURE_QUANTA.SOCKET4677_AZIF0045P001C01CS(CHIPS)':
 'VSS602': CDS_PINID='VSS602';
NODE_NAME     U2 BW9
 '@S9S_MB_2U_LIB.S9S_MB_2U(SCH_1):PAGE40_I12@PURE_QUANTA.SOCKET4677_AZIF0045P001C01CS(CHIPS)':
 'VSS603': CDS_PINID='VSS603';
NODE_NAME     U2 BY12
 '@S9S_MB_2U_LIB.S9S_MB_2U(SCH_1):PAGE40_I12@PURE_QUANTA.SOCKET4677_AZIF0045P001C01CS(CHIPS)':
 'VSS604': CDS_PINID='VSS604';
NODE_NAME     U2 BY16
 '@S9S_MB_2U_LIB.S9S_MB_2U(SCH_1):PAGE40_I12@PURE_QUANTA.SOCKET4677_AZIF0045P001C01CS(CHIPS)':
 'VSS605': CDS_PINID='VSS605';
NODE_NAME     U2 BY20
 '@S9S_MB_2U_LIB.S9S_MB_2U(SCH_1):PAGE40_I12@PURE_QUANTA.SOCKET4677_AZIF0045P001C01CS(CHIPS)':
 'VSS606': CDS_PINID='VSS606';
NODE_NAME     U2 BY4
 '@S9S_MB_2U_LIB.S9S_MB_2U(SCH_1):PAGE40_I12@PURE_QUANTA.SOCKET4677_AZIF0045P001C01CS(CHIPS)':
 'VSS607': CDS_PINID='VSS607';
NODE_NAME     U2 BY8
 '@S9S_MB_2U_LIB.S9S_MB_2U(SCH_1):PAGE40_I12@PURE_QUANTA.SOCKET4677_AZIF0045P001C01CS(CHIPS)':
 'VSS608': CDS_PINID='VSS608';
NODE_NAME     U2 CA3
 '@S9S_MB_2U_LIB.S9S_MB_2U(SCH_1):PAGE40_I12@PURE_QUANTA.SOCKET4677_AZIF0045P001C01CS(CHIPS)':
 'VSS620': CDS_PINID='VSS620';
NODE_NAME     U2 CA31
 '@S9S_MB_2U_LIB.S9S_MB_2U(SCH_1):PAGE40_I12@PURE_QUANTA.SOCKET4677_AZIF0045P001C01CS(CHIPS)':
 'VSS621': CDS_PINID='VSS621';
NODE_NAME     U2 CB12
 '@S9S_MB_2U_LIB.S9S_MB_2U(SCH_1):PAGE40_I12@PURE_QUANTA.SOCKET4677_AZIF0045P001C01CS(CHIPS)':
 'VSS622': CDS_PINID='VSS622';
NODE_NAME     U2 CB16
 '@S9S_MB_2U_LIB.S9S_MB_2U(SCH_1):PAGE40_I12@PURE_QUANTA.SOCKET4677_AZIF0045P001C01CS(CHIPS)':
 'VSS623': CDS_PINID='VSS623';
NODE_NAME     U2 CB20
 '@S9S_MB_2U_LIB.S9S_MB_2U(SCH_1):PAGE40_I12@PURE_QUANTA.SOCKET4677_AZIF0045P001C01CS(CHIPS)':
 'VSS624': CDS_PINID='VSS624';
NODE_NAME     U2 CB22
 '@S9S_MB_2U_LIB.S9S_MB_2U(SCH_1):PAGE40_I12@PURE_QUANTA.SOCKET4677_AZIF0045P001C01CS(CHIPS)':
 'VSS625': CDS_PINID='VSS625';
NODE_NAME     U2 CB24
 '@S9S_MB_2U_LIB.S9S_MB_2U(SCH_1):PAGE40_I12@PURE_QUANTA.SOCKET4677_AZIF0045P001C01CS(CHIPS)':
 'VSS626': CDS_PINID='VSS626';
NODE_NAME     U2 CB26
 '@S9S_MB_2U_LIB.S9S_MB_2U(SCH_1):PAGE40_I12@PURE_QUANTA.SOCKET4677_AZIF0045P001C01CS(CHIPS)':
 'VSS627': CDS_PINID='VSS627';
NODE_NAME     U2 CB28
 '@S9S_MB_2U_LIB.S9S_MB_2U(SCH_1):PAGE40_I12@PURE_QUANTA.SOCKET4677_AZIF0045P001C01CS(CHIPS)':
 'VSS628': CDS_PINID='VSS628';
NODE_NAME     U2 CB32
 '@S9S_MB_2U_LIB.S9S_MB_2U(SCH_1):PAGE40_I12@PURE_QUANTA.SOCKET4677_AZIF0045P001C01CS(CHIPS)':
 'VSS629': CDS_PINID='VSS629';
NODE_NAME     U2 CB34
 '@S9S_MB_2U_LIB.S9S_MB_2U(SCH_1):PAGE40_I12@PURE_QUANTA.SOCKET4677_AZIF0045P001C01CS(CHIPS)':
 'VSS630': CDS_PINID='VSS630';
NODE_NAME     U2 CB36
 '@S9S_MB_2U_LIB.S9S_MB_2U(SCH_1):PAGE40_I12@PURE_QUANTA.SOCKET4677_AZIF0045P001C01CS(CHIPS)':
 'VSS631': CDS_PINID='VSS631';
NODE_NAME     U2 CB38
 '@S9S_MB_2U_LIB.S9S_MB_2U(SCH_1):PAGE40_I12@PURE_QUANTA.SOCKET4677_AZIF0045P001C01CS(CHIPS)':
 'VSS632': CDS_PINID='VSS632';
NODE_NAME     U2 CB4
 '@S9S_MB_2U_LIB.S9S_MB_2U(SCH_1):PAGE40_I12@PURE_QUANTA.SOCKET4677_AZIF0045P001C01CS(CHIPS)':
 'VSS633': CDS_PINID='VSS633';
NODE_NAME     U2 CB40
 '@S9S_MB_2U_LIB.S9S_MB_2U(SCH_1):PAGE40_I12@PURE_QUANTA.SOCKET4677_AZIF0045P001C01CS(CHIPS)':
 'VSS634': CDS_PINID='VSS634';
NODE_NAME     U2 CB42
 '@S9S_MB_2U_LIB.S9S_MB_2U(SCH_1):PAGE40_I12@PURE_QUANTA.SOCKET4677_AZIF0045P001C01CS(CHIPS)':
 'VSS635': CDS_PINID='VSS635';
NODE_NAME     U2 CB44
 '@S9S_MB_2U_LIB.S9S_MB_2U(SCH_1):PAGE40_I12@PURE_QUANTA.SOCKET4677_AZIF0045P001C01CS(CHIPS)':
 'VSS636': CDS_PINID='VSS636';
NODE_NAME     U2 CB47
 '@S9S_MB_2U_LIB.S9S_MB_2U(SCH_1):PAGE40_I12@PURE_QUANTA.SOCKET4677_AZIF0045P001C01CS(CHIPS)':
 'VSS637': CDS_PINID='VSS637';
NODE_NAME     U2 CB49
 '@S9S_MB_2U_LIB.S9S_MB_2U(SCH_1):PAGE40_I12@PURE_QUANTA.SOCKET4677_AZIF0045P001C01CS(CHIPS)':
 'VSS638': CDS_PINID='VSS638';
NODE_NAME     U2 CB51
 '@S9S_MB_2U_LIB.S9S_MB_2U(SCH_1):PAGE40_I12@PURE_QUANTA.SOCKET4677_AZIF0045P001C01CS(CHIPS)':
 'VSS639': CDS_PINID='VSS639';
NODE_NAME     U2 CB53
 '@S9S_MB_2U_LIB.S9S_MB_2U(SCH_1):PAGE40_I12@PURE_QUANTA.SOCKET4677_AZIF0045P001C01CS(CHIPS)':
 'VSS640': CDS_PINID='VSS640';
NODE_NAME     U2 CB55
 '@S9S_MB_2U_LIB.S9S_MB_2U(SCH_1):PAGE40_I12@PURE_QUANTA.SOCKET4677_AZIF0045P001C01CS(CHIPS)':
 'VSS641': CDS_PINID='VSS641';
NODE_NAME     U2 CB57
 '@S9S_MB_2U_LIB.S9S_MB_2U(SCH_1):PAGE40_I12@PURE_QUANTA.SOCKET4677_AZIF0045P001C01CS(CHIPS)':
 'VSS642': CDS_PINID='VSS642';
NODE_NAME     U2 CB59
 '@S9S_MB_2U_LIB.S9S_MB_2U(SCH_1):PAGE40_I12@PURE_QUANTA.SOCKET4677_AZIF0045P001C01CS(CHIPS)':
 'VSS643': CDS_PINID='VSS643';
NODE_NAME     U2 CB63
 '@S9S_MB_2U_LIB.S9S_MB_2U(SCH_1):PAGE40_I12@PURE_QUANTA.SOCKET4677_AZIF0045P001C01CS(CHIPS)':
 'VSS644': CDS_PINID='VSS644';
NODE_NAME     U2 CB65
 '@S9S_MB_2U_LIB.S9S_MB_2U(SCH_1):PAGE40_I12@PURE_QUANTA.SOCKET4677_AZIF0045P001C01CS(CHIPS)':
 'VSS645': CDS_PINID='VSS645';
NODE_NAME     U2 CB67
 '@S9S_MB_2U_LIB.S9S_MB_2U(SCH_1):PAGE40_I12@PURE_QUANTA.SOCKET4677_AZIF0045P001C01CS(CHIPS)':
 'VSS646': CDS_PINID='VSS646';
NODE_NAME     U2 CB69
 '@S9S_MB_2U_LIB.S9S_MB_2U(SCH_1):PAGE40_I12@PURE_QUANTA.SOCKET4677_AZIF0045P001C01CS(CHIPS)':
 'VSS647': CDS_PINID='VSS647';
NODE_NAME     U2 CB71
 '@S9S_MB_2U_LIB.S9S_MB_2U(SCH_1):PAGE40_I12@PURE_QUANTA.SOCKET4677_AZIF0045P001C01CS(CHIPS)':
 'VSS648': CDS_PINID='VSS648';
NODE_NAME     U2 CB73
 '@S9S_MB_2U_LIB.S9S_MB_2U(SCH_1):PAGE40_I12@PURE_QUANTA.SOCKET4677_AZIF0045P001C01CS(CHIPS)':
 'VSS649': CDS_PINID='VSS649';
NODE_NAME     U2 CB79
 '@S9S_MB_2U_LIB.S9S_MB_2U(SCH_1):PAGE40_I12@PURE_QUANTA.SOCKET4677_AZIF0045P001C01CS(CHIPS)':
 'VSS650': CDS_PINID='VSS650';
NODE_NAME     U2 CB8
 '@S9S_MB_2U_LIB.S9S_MB_2U(SCH_1):PAGE40_I12@PURE_QUANTA.SOCKET4677_AZIF0045P001C01CS(CHIPS)':
 'VSS651': CDS_PINID='VSS651';
NODE_NAME     U2 CB81
 '@S9S_MB_2U_LIB.S9S_MB_2U(SCH_1):PAGE40_I12@PURE_QUANTA.SOCKET4677_AZIF0045P001C01CS(CHIPS)':
 'VSS652': CDS_PINID='VSS652';
NODE_NAME     U2 CB83
 '@S9S_MB_2U_LIB.S9S_MB_2U(SCH_1):PAGE40_I12@PURE_QUANTA.SOCKET4677_AZIF0045P001C01CS(CHIPS)':
 'VSS653': CDS_PINID='VSS653';
NODE_NAME     U2 CB85
 '@S9S_MB_2U_LIB.S9S_MB_2U(SCH_1):PAGE40_I12@PURE_QUANTA.SOCKET4677_AZIF0045P001C01CS(CHIPS)':
 'VSS654': CDS_PINID='VSS654';
NODE_NAME     U2 CB87
 '@S9S_MB_2U_LIB.S9S_MB_2U(SCH_1):PAGE40_I12@PURE_QUANTA.SOCKET4677_AZIF0045P001C01CS(CHIPS)':
 'VSS655': CDS_PINID='VSS655';
NODE_NAME     U2 CB89
 '@S9S_MB_2U_LIB.S9S_MB_2U(SCH_1):PAGE40_I12@PURE_QUANTA.SOCKET4677_AZIF0045P001C01CS(CHIPS)':
 'VSS656': CDS_PINID='VSS656';
NODE_NAME     U2 CC13
 '@S9S_MB_2U_LIB.S9S_MB_2U(SCH_1):PAGE40_I12@PURE_QUANTA.SOCKET4677_AZIF0045P001C01CS(CHIPS)':
 'VSS660': CDS_PINID='VSS660';
NODE_NAME     U2 CC17
 '@S9S_MB_2U_LIB.S9S_MB_2U(SCH_1):PAGE40_I12@PURE_QUANTA.SOCKET4677_AZIF0045P001C01CS(CHIPS)':
 'VSS661': CDS_PINID='VSS661';
NODE_NAME     U2 CC31
 '@S9S_MB_2U_LIB.S9S_MB_2U(SCH_1):PAGE40_I12@PURE_QUANTA.SOCKET4677_AZIF0045P001C01CS(CHIPS)':
 'VSS664': CDS_PINID='VSS664';
NODE_NAME     U2 CC5
 '@S9S_MB_2U_LIB.S9S_MB_2U(SCH_1):PAGE40_I12@PURE_QUANTA.SOCKET4677_AZIF0045P001C01CS(CHIPS)':
 'VSS665': CDS_PINID='VSS665';
NODE_NAME     U2 CC62
 '@S9S_MB_2U_LIB.S9S_MB_2U(SCH_1):PAGE40_I12@PURE_QUANTA.SOCKET4677_AZIF0045P001C01CS(CHIPS)':
 'VSS666': CDS_PINID='VSS666';
NODE_NAME     U2 CC70
 '@S9S_MB_2U_LIB.S9S_MB_2U(SCH_1):PAGE40_I12@PURE_QUANTA.SOCKET4677_AZIF0045P001C01CS(CHIPS)':
 'VSS667': CDS_PINID='VSS667';
NODE_NAME     U2 CC72
 '@S9S_MB_2U_LIB.S9S_MB_2U(SCH_1):PAGE40_I12@PURE_QUANTA.SOCKET4677_AZIF0045P001C01CS(CHIPS)':
 'VSS668': CDS_PINID='VSS668';
NODE_NAME     U2 CC74
 '@S9S_MB_2U_LIB.S9S_MB_2U(SCH_1):PAGE40_I12@PURE_QUANTA.SOCKET4677_AZIF0045P001C01CS(CHIPS)':
 'VSS669': CDS_PINID='VSS669';
NODE_NAME     U2 CC9
 '@S9S_MB_2U_LIB.S9S_MB_2U(SCH_1):PAGE40_I12@PURE_QUANTA.SOCKET4677_AZIF0045P001C01CS(CHIPS)':
 'VSS670': CDS_PINID='VSS670';
NODE_NAME     U2 CD12
 '@S9S_MB_2U_LIB.S9S_MB_2U(SCH_1):PAGE40_I12@PURE_QUANTA.SOCKET4677_AZIF0045P001C01CS(CHIPS)':
 'VSS671': CDS_PINID='VSS671';
NODE_NAME     U2 CD16
 '@S9S_MB_2U_LIB.S9S_MB_2U(SCH_1):PAGE40_I12@PURE_QUANTA.SOCKET4677_AZIF0045P001C01CS(CHIPS)':
 'VSS672': CDS_PINID='VSS672';
NODE_NAME     U2 CD20
 '@S9S_MB_2U_LIB.S9S_MB_2U(SCH_1):PAGE40_I12@PURE_QUANTA.SOCKET4677_AZIF0045P001C01CS(CHIPS)':
 'VSS673': CDS_PINID='VSS673';
NODE_NAME     U2 CD4
 '@S9S_MB_2U_LIB.S9S_MB_2U(SCH_1):PAGE40_I12@PURE_QUANTA.SOCKET4677_AZIF0045P001C01CS(CHIPS)':
 'VSS674': CDS_PINID='VSS674';
NODE_NAME     U2 CD61
 '@S9S_MB_2U_LIB.S9S_MB_2U(SCH_1):PAGE40_I12@PURE_QUANTA.SOCKET4677_AZIF0045P001C01CS(CHIPS)':
 'VSS675': CDS_PINID='VSS675';
NODE_NAME     U2 CD75
 '@S9S_MB_2U_LIB.S9S_MB_2U(SCH_1):PAGE40_I12@PURE_QUANTA.SOCKET4677_AZIF0045P001C01CS(CHIPS)':
 'VSS676': CDS_PINID='VSS676';
NODE_NAME     U2 CD77
 '@S9S_MB_2U_LIB.S9S_MB_2U(SCH_1):PAGE40_I12@PURE_QUANTA.SOCKET4677_AZIF0045P001C01CS(CHIPS)':
 'VSS677': CDS_PINID='VSS677';
NODE_NAME     U2 CD8
 '@S9S_MB_2U_LIB.S9S_MB_2U(SCH_1):PAGE40_I12@PURE_QUANTA.SOCKET4677_AZIF0045P001C01CS(CHIPS)':
 'VSS678': CDS_PINID='VSS678';
NODE_NAME     U2 CE3
 '@S9S_MB_2U_LIB.S9S_MB_2U(SCH_1):PAGE40_I12@PURE_QUANTA.SOCKET4677_AZIF0045P001C01CS(CHIPS)':
 'VSS680': CDS_PINID='VSS680';
NODE_NAME     U2 CE60
 '@S9S_MB_2U_LIB.S9S_MB_2U(SCH_1):PAGE40_I12@PURE_QUANTA.SOCKET4677_AZIF0045P001C01CS(CHIPS)':
 'VSS681': CDS_PINID='VSS681';
NODE_NAME     U2 CE66
 '@S9S_MB_2U_LIB.S9S_MB_2U(SCH_1):PAGE40_I12@PURE_QUANTA.SOCKET4677_AZIF0045P001C01CS(CHIPS)':
 'VSS682': CDS_PINID='VSS682';
NODE_NAME     U2 CE72
 '@S9S_MB_2U_LIB.S9S_MB_2U(SCH_1):PAGE40_I12@PURE_QUANTA.SOCKET4677_AZIF0045P001C01CS(CHIPS)':
 'VSS683': CDS_PINID='VSS683';
NODE_NAME     U2 CE76
 '@S9S_MB_2U_LIB.S9S_MB_2U(SCH_1):PAGE40_I12@PURE_QUANTA.SOCKET4677_AZIF0045P001C01CS(CHIPS)':
 'VSS684': CDS_PINID='VSS684';
NODE_NAME     U2 CE78
 '@S9S_MB_2U_LIB.S9S_MB_2U(SCH_1):PAGE40_I12@PURE_QUANTA.SOCKET4677_AZIF0045P001C01CS(CHIPS)':
 'VSS685': CDS_PINID='VSS685';
NODE_NAME     U2 CF12
 '@S9S_MB_2U_LIB.S9S_MB_2U(SCH_1):PAGE40_I12@PURE_QUANTA.SOCKET4677_AZIF0045P001C01CS(CHIPS)':
 'VSS686': CDS_PINID='VSS686';
NODE_NAME     U2 CF16
 '@S9S_MB_2U_LIB.S9S_MB_2U(SCH_1):PAGE40_I12@PURE_QUANTA.SOCKET4677_AZIF0045P001C01CS(CHIPS)':
 'VSS687': CDS_PINID='VSS687';
NODE_NAME     U2 CF20
 '@S9S_MB_2U_LIB.S9S_MB_2U(SCH_1):PAGE40_I12@PURE_QUANTA.SOCKET4677_AZIF0045P001C01CS(CHIPS)':
 'VSS688': CDS_PINID='VSS688';
NODE_NAME     U2 CF4
 '@S9S_MB_2U_LIB.S9S_MB_2U(SCH_1):PAGE40_I12@PURE_QUANTA.SOCKET4677_AZIF0045P001C01CS(CHIPS)':
 'VSS689': CDS_PINID='VSS689';
NODE_NAME     U2 CF69
 '@S9S_MB_2U_LIB.S9S_MB_2U(SCH_1):PAGE40_I12@PURE_QUANTA.SOCKET4677_AZIF0045P001C01CS(CHIPS)':
 'VSS691': CDS_PINID='VSS691';
NODE_NAME     U2 CF71
 '@S9S_MB_2U_LIB.S9S_MB_2U(SCH_1):PAGE40_I12@PURE_QUANTA.SOCKET4677_AZIF0045P001C01CS(CHIPS)':
 'VSS692': CDS_PINID='VSS692';
NODE_NAME     U2 CF8
 '@S9S_MB_2U_LIB.S9S_MB_2U(SCH_1):PAGE40_I12@PURE_QUANTA.SOCKET4677_AZIF0045P001C01CS(CHIPS)':
 'VSS693': CDS_PINID='VSS693';
NODE_NAME     U2 CG1
 '@S9S_MB_2U_LIB.S9S_MB_2U(SCH_1):PAGE40_I12@PURE_QUANTA.SOCKET4677_AZIF0045P001C01CS(CHIPS)':
 'VSS694': CDS_PINID='VSS694';
NODE_NAME     U2 CG13
 '@S9S_MB_2U_LIB.S9S_MB_2U(SCH_1):PAGE40_I12@PURE_QUANTA.SOCKET4677_AZIF0045P001C01CS(CHIPS)':
 'VSS695': CDS_PINID='VSS695';
NODE_NAME     U2 CG17
 '@S9S_MB_2U_LIB.S9S_MB_2U(SCH_1):PAGE40_I12@PURE_QUANTA.SOCKET4677_AZIF0045P001C01CS(CHIPS)':
 'VSS696': CDS_PINID='VSS696';
NODE_NAME     U2 CG21
 '@S9S_MB_2U_LIB.S9S_MB_2U(SCH_1):PAGE40_I12@PURE_QUANTA.SOCKET4677_AZIF0045P001C01CS(CHIPS)':
 'VSS697': CDS_PINID='VSS697';
NODE_NAME     U2 CG23
 '@S9S_MB_2U_LIB.S9S_MB_2U(SCH_1):PAGE40_I12@PURE_QUANTA.SOCKET4677_AZIF0045P001C01CS(CHIPS)':
 'VSS698': CDS_PINID='VSS698';
NODE_NAME     U2 CG25
 '@S9S_MB_2U_LIB.S9S_MB_2U(SCH_1):PAGE40_I12@PURE_QUANTA.SOCKET4677_AZIF0045P001C01CS(CHIPS)':
 'VSS701': CDS_PINID='VSS701';
NODE_NAME     U2 CG5
 '@S9S_MB_2U_LIB.S9S_MB_2U(SCH_1):PAGE40_I12@PURE_QUANTA.SOCKET4677_AZIF0045P001C01CS(CHIPS)':
 'VSS703': CDS_PINID='VSS703';
NODE_NAME     U2 CG62
 '@S9S_MB_2U_LIB.S9S_MB_2U(SCH_1):PAGE40_I12@PURE_QUANTA.SOCKET4677_AZIF0045P001C01CS(CHIPS)':
 'VSS704': CDS_PINID='VSS704';
NODE_NAME     U2 CG64
 '@S9S_MB_2U_LIB.S9S_MB_2U(SCH_1):PAGE40_I12@PURE_QUANTA.SOCKET4677_AZIF0045P001C01CS(CHIPS)':
 'VSS706': CDS_PINID='VSS706';
NODE_NAME     U2 CG70
 '@S9S_MB_2U_LIB.S9S_MB_2U(SCH_1):PAGE40_I12@PURE_QUANTA.SOCKET4677_AZIF0045P001C01CS(CHIPS)':
 'VSS707': CDS_PINID='VSS707';
NODE_NAME     U2 CG72
 '@S9S_MB_2U_LIB.S9S_MB_2U(SCH_1):PAGE40_I12@PURE_QUANTA.SOCKET4677_AZIF0045P001C01CS(CHIPS)':
 'VSS708': CDS_PINID='VSS708';
NODE_NAME     U2 CG74
 '@S9S_MB_2U_LIB.S9S_MB_2U(SCH_1):PAGE40_I12@PURE_QUANTA.SOCKET4677_AZIF0045P001C01CS(CHIPS)':
 'VSS710': CDS_PINID='VSS710';
NODE_NAME     U2 CG78
 '@S9S_MB_2U_LIB.S9S_MB_2U(SCH_1):PAGE40_I12@PURE_QUANTA.SOCKET4677_AZIF0045P001C01CS(CHIPS)':
 'VSS713': CDS_PINID='VSS713';
NODE_NAME     U2 CG9
 '@S9S_MB_2U_LIB.S9S_MB_2U(SCH_1):PAGE40_I12@PURE_QUANTA.SOCKET4677_AZIF0045P001C01CS(CHIPS)':
 'VSS716': CDS_PINID='VSS716';
NODE_NAME     U2 CH12
 '@S9S_MB_2U_LIB.S9S_MB_2U(SCH_1):PAGE40_I12@PURE_QUANTA.SOCKET4677_AZIF0045P001C01CS(CHIPS)':
 'VSS718': CDS_PINID='VSS718';
NODE_NAME     U2 CH16
 '@S9S_MB_2U_LIB.S9S_MB_2U(SCH_1):PAGE40_I12@PURE_QUANTA.SOCKET4677_AZIF0045P001C01CS(CHIPS)':
 'VSS720': CDS_PINID='VSS720';
NODE_NAME     U2 CH20
 '@S9S_MB_2U_LIB.S9S_MB_2U(SCH_1):PAGE40_I12@PURE_QUANTA.SOCKET4677_AZIF0045P001C01CS(CHIPS)':
 'VSS721': CDS_PINID='VSS721';
NODE_NAME     U2 CH4
 '@S9S_MB_2U_LIB.S9S_MB_2U(SCH_1):PAGE40_I12@PURE_QUANTA.SOCKET4677_AZIF0045P001C01CS(CHIPS)':
 'VSS722': CDS_PINID='VSS722';
NODE_NAME     U2 CH67
 '@S9S_MB_2U_LIB.S9S_MB_2U(SCH_1):PAGE40_I12@PURE_QUANTA.SOCKET4677_AZIF0045P001C01CS(CHIPS)':
 'VSS727': CDS_PINID='VSS727';
NODE_NAME     U2 CH73
 '@S9S_MB_2U_LIB.S9S_MB_2U(SCH_1):PAGE40_I12@PURE_QUANTA.SOCKET4677_AZIF0045P001C01CS(CHIPS)':
 'VSS728': CDS_PINID='VSS728';
NODE_NAME     U2 CH79
 '@S9S_MB_2U_LIB.S9S_MB_2U(SCH_1):PAGE40_I12@PURE_QUANTA.SOCKET4677_AZIF0045P001C01CS(CHIPS)':
 'VSS729': CDS_PINID='VSS729';
NODE_NAME     U2 CH8
 '@S9S_MB_2U_LIB.S9S_MB_2U(SCH_1):PAGE40_I12@PURE_QUANTA.SOCKET4677_AZIF0045P001C01CS(CHIPS)':
 'VSS730': CDS_PINID='VSS730';
NODE_NAME     U2 CH83
 '@S9S_MB_2U_LIB.S9S_MB_2U(SCH_1):PAGE40_I12@PURE_QUANTA.SOCKET4677_AZIF0045P001C01CS(CHIPS)':
 'VSS731': CDS_PINID='VSS731';
NODE_NAME     U2 CH85
 '@S9S_MB_2U_LIB.S9S_MB_2U(SCH_1):PAGE40_I12@PURE_QUANTA.SOCKET4677_AZIF0045P001C01CS(CHIPS)':
 'VSS732': CDS_PINID='VSS732';
NODE_NAME     U2 CH87
 '@S9S_MB_2U_LIB.S9S_MB_2U(SCH_1):PAGE40_I12@PURE_QUANTA.SOCKET4677_AZIF0045P001C01CS(CHIPS)':
 'VSS733': CDS_PINID='VSS733';
NODE_NAME     U2 CH89
 '@S9S_MB_2U_LIB.S9S_MB_2U(SCH_1):PAGE40_I12@PURE_QUANTA.SOCKET4677_AZIF0045P001C01CS(CHIPS)':
 'VSS734': CDS_PINID='VSS734';
NODE_NAME     U2 CJ60
 '@S9S_MB_2U_LIB.S9S_MB_2U(SCH_1):PAGE40_I12@PURE_QUANTA.SOCKET4677_AZIF0045P001C01CS(CHIPS)':
 'VSS736': CDS_PINID='VSS736';
NODE_NAME     U2 CJ80
 '@S9S_MB_2U_LIB.S9S_MB_2U(SCH_1):PAGE40_I12@PURE_QUANTA.SOCKET4677_AZIF0045P001C01CS(CHIPS)':
 'VSS737': CDS_PINID='VSS737';
NODE_NAME     U2 CK12
 '@S9S_MB_2U_LIB.S9S_MB_2U(SCH_1):PAGE40_I12@PURE_QUANTA.SOCKET4677_AZIF0045P001C01CS(CHIPS)':
 'VSS740': CDS_PINID='VSS740';
NODE_NAME     U2 CK16
 '@S9S_MB_2U_LIB.S9S_MB_2U(SCH_1):PAGE40_I12@PURE_QUANTA.SOCKET4677_AZIF0045P001C01CS(CHIPS)':
 'VSS741': CDS_PINID='VSS741';
NODE_NAME     U2 CK20
 '@S9S_MB_2U_LIB.S9S_MB_2U(SCH_1):PAGE40_I12@PURE_QUANTA.SOCKET4677_AZIF0045P001C01CS(CHIPS)':
 'VSS742': CDS_PINID='VSS742';
NODE_NAME     U2 CK26
 '@S9S_MB_2U_LIB.S9S_MB_2U(SCH_1):PAGE40_I12@PURE_QUANTA.SOCKET4677_AZIF0045P001C01CS(CHIPS)':
 'VSS743': CDS_PINID='VSS743';
NODE_NAME     U2 CK8
 '@S9S_MB_2U_LIB.S9S_MB_2U(SCH_1):PAGE40_I12@PURE_QUANTA.SOCKET4677_AZIF0045P001C01CS(CHIPS)':
 'VSS746': CDS_PINID='VSS746';
NODE_NAME     U2 BR5
 '@S9S_MB_2U_LIB.S9S_MB_2U(SCH_1):PAGE41_I9@PURE_QUANTA.SOCKET4677_AZIF0045P001C01CS(CHIPS)':
 'VSS0': CDS_PINID='VSS0';
NODE_NAME     U2 AW21
 '@S9S_MB_2U_LIB.S9S_MB_2U(SCH_1):PAGE41_I9@PURE_QUANTA.SOCKET4677_AZIF0045P001C01CS(CHIPS)':
 'VSS356': CDS_PINID='VSS356';
NODE_NAME     U2 AW23
 '@S9S_MB_2U_LIB.S9S_MB_2U(SCH_1):PAGE41_I9@PURE_QUANTA.SOCKET4677_AZIF0045P001C01CS(CHIPS)':
 'VSS357': CDS_PINID='VSS357';
NODE_NAME     U2 AW25
 '@S9S_MB_2U_LIB.S9S_MB_2U(SCH_1):PAGE41_I9@PURE_QUANTA.SOCKET4677_AZIF0045P001C01CS(CHIPS)':
 'VSS358': CDS_PINID='VSS358';
NODE_NAME     U2 AW62
 '@S9S_MB_2U_LIB.S9S_MB_2U(SCH_1):PAGE41_I9@PURE_QUANTA.SOCKET4677_AZIF0045P001C01CS(CHIPS)':
 'VSS360': CDS_PINID='VSS360';
NODE_NAME     U2 AW66
 '@S9S_MB_2U_LIB.S9S_MB_2U(SCH_1):PAGE41_I9@PURE_QUANTA.SOCKET4677_AZIF0045P001C01CS(CHIPS)':
 'VSS361': CDS_PINID='VSS361';
NODE_NAME     U2 AW68
 '@S9S_MB_2U_LIB.S9S_MB_2U(SCH_1):PAGE41_I9@PURE_QUANTA.SOCKET4677_AZIF0045P001C01CS(CHIPS)':
 'VSS362': CDS_PINID='VSS362';
NODE_NAME     U2 AW72
 '@S9S_MB_2U_LIB.S9S_MB_2U(SCH_1):PAGE41_I9@PURE_QUANTA.SOCKET4677_AZIF0045P001C01CS(CHIPS)':
 'VSS363': CDS_PINID='VSS363';
NODE_NAME     U2 AW80
 '@S9S_MB_2U_LIB.S9S_MB_2U(SCH_1):PAGE41_I9@PURE_QUANTA.SOCKET4677_AZIF0045P001C01CS(CHIPS)':
 'VSS364': CDS_PINID='VSS364';
NODE_NAME     U2 AW82
 '@S9S_MB_2U_LIB.S9S_MB_2U(SCH_1):PAGE41_I9@PURE_QUANTA.SOCKET4677_AZIF0045P001C01CS(CHIPS)':
 'VSS365': CDS_PINID='VSS365';
NODE_NAME     U2 AW84
 '@S9S_MB_2U_LIB.S9S_MB_2U(SCH_1):PAGE41_I9@PURE_QUANTA.SOCKET4677_AZIF0045P001C01CS(CHIPS)':
 'VSS366': CDS_PINID='VSS366';
NODE_NAME     U2 AW88
 '@S9S_MB_2U_LIB.S9S_MB_2U(SCH_1):PAGE41_I9@PURE_QUANTA.SOCKET4677_AZIF0045P001C01CS(CHIPS)':
 'VSS367': CDS_PINID='VSS367';
NODE_NAME     U2 AY12
 '@S9S_MB_2U_LIB.S9S_MB_2U(SCH_1):PAGE41_I9@PURE_QUANTA.SOCKET4677_AZIF0045P001C01CS(CHIPS)':
 'VSS369': CDS_PINID='VSS369';
NODE_NAME     U2 AY16
 '@S9S_MB_2U_LIB.S9S_MB_2U(SCH_1):PAGE41_I9@PURE_QUANTA.SOCKET4677_AZIF0045P001C01CS(CHIPS)':
 'VSS370': CDS_PINID='VSS370';
NODE_NAME     U2 AY4
 '@S9S_MB_2U_LIB.S9S_MB_2U(SCH_1):PAGE41_I9@PURE_QUANTA.SOCKET4677_AZIF0045P001C01CS(CHIPS)':
 'VSS371': CDS_PINID='VSS371';
NODE_NAME     U2 AY71
 '@S9S_MB_2U_LIB.S9S_MB_2U(SCH_1):PAGE41_I9@PURE_QUANTA.SOCKET4677_AZIF0045P001C01CS(CHIPS)':
 'VSS372': CDS_PINID='VSS372';
NODE_NAME     U2 AY77
 '@S9S_MB_2U_LIB.S9S_MB_2U(SCH_1):PAGE41_I9@PURE_QUANTA.SOCKET4677_AZIF0045P001C01CS(CHIPS)':
 'VSS373': CDS_PINID='VSS373';
NODE_NAME     U2 AY79
 '@S9S_MB_2U_LIB.S9S_MB_2U(SCH_1):PAGE41_I9@PURE_QUANTA.SOCKET4677_AZIF0045P001C01CS(CHIPS)':
 'VSS374': CDS_PINID='VSS374';
NODE_NAME     U2 AY8
 '@S9S_MB_2U_LIB.S9S_MB_2U(SCH_1):PAGE41_I9@PURE_QUANTA.SOCKET4677_AZIF0045P001C01CS(CHIPS)':
 'VSS375': CDS_PINID='VSS375';
NODE_NAME     U2 AY81
 '@S9S_MB_2U_LIB.S9S_MB_2U(SCH_1):PAGE41_I9@PURE_QUANTA.SOCKET4677_AZIF0045P001C01CS(CHIPS)':
 'VSS376': CDS_PINID='VSS376';
NODE_NAME     U2 AY83
 '@S9S_MB_2U_LIB.S9S_MB_2U(SCH_1):PAGE41_I9@PURE_QUANTA.SOCKET4677_AZIF0045P001C01CS(CHIPS)':
 'VSS377': CDS_PINID='VSS377';
NODE_NAME     U2 BA17
 '@S9S_MB_2U_LIB.S9S_MB_2U(SCH_1):PAGE41_I9@PURE_QUANTA.SOCKET4677_AZIF0045P001C01CS(CHIPS)':
 'VSS393': CDS_PINID='VSS393';
NODE_NAME     U2 BA60
 '@S9S_MB_2U_LIB.S9S_MB_2U(SCH_1):PAGE41_I9@PURE_QUANTA.SOCKET4677_AZIF0045P001C01CS(CHIPS)':
 'VSS394': CDS_PINID='VSS394';
NODE_NAME     U2 BA64
 '@S9S_MB_2U_LIB.S9S_MB_2U(SCH_1):PAGE41_I9@PURE_QUANTA.SOCKET4677_AZIF0045P001C01CS(CHIPS)':
 'VSS395': CDS_PINID='VSS395';
NODE_NAME     U2 BA74
 '@S9S_MB_2U_LIB.S9S_MB_2U(SCH_1):PAGE41_I9@PURE_QUANTA.SOCKET4677_AZIF0045P001C01CS(CHIPS)':
 'VSS397': CDS_PINID='VSS397';
NODE_NAME     U2 BA84
 '@S9S_MB_2U_LIB.S9S_MB_2U(SCH_1):PAGE41_I9@PURE_QUANTA.SOCKET4677_AZIF0045P001C01CS(CHIPS)':
 'VSS398': CDS_PINID='VSS398';
NODE_NAME     U2 BA88
 '@S9S_MB_2U_LIB.S9S_MB_2U(SCH_1):PAGE41_I9@PURE_QUANTA.SOCKET4677_AZIF0045P001C01CS(CHIPS)':
 'VSS399': CDS_PINID='VSS399';
NODE_NAME     U2 BB10
 '@S9S_MB_2U_LIB.S9S_MB_2U(SCH_1):PAGE41_I9@PURE_QUANTA.SOCKET4677_AZIF0045P001C01CS(CHIPS)':
 'VSS400': CDS_PINID='VSS400';
NODE_NAME     U2 BB12
 '@S9S_MB_2U_LIB.S9S_MB_2U(SCH_1):PAGE41_I9@PURE_QUANTA.SOCKET4677_AZIF0045P001C01CS(CHIPS)':
 'VSS401': CDS_PINID='VSS401';
NODE_NAME     U2 BB16
 '@S9S_MB_2U_LIB.S9S_MB_2U(SCH_1):PAGE41_I9@PURE_QUANTA.SOCKET4677_AZIF0045P001C01CS(CHIPS)':
 'VSS402': CDS_PINID='VSS402';
NODE_NAME     U2 BB20
 '@S9S_MB_2U_LIB.S9S_MB_2U(SCH_1):PAGE41_I9@PURE_QUANTA.SOCKET4677_AZIF0045P001C01CS(CHIPS)':
 'VSS403': CDS_PINID='VSS403';
NODE_NAME     U2 BB22
 '@S9S_MB_2U_LIB.S9S_MB_2U(SCH_1):PAGE41_I9@PURE_QUANTA.SOCKET4677_AZIF0045P001C01CS(CHIPS)':
 'VSS404': CDS_PINID='VSS404';
NODE_NAME     U2 BB24
 '@S9S_MB_2U_LIB.S9S_MB_2U(SCH_1):PAGE41_I9@PURE_QUANTA.SOCKET4677_AZIF0045P001C01CS(CHIPS)':
 'VSS405': CDS_PINID='VSS405';
NODE_NAME     U2 BB26
 '@S9S_MB_2U_LIB.S9S_MB_2U(SCH_1):PAGE41_I9@PURE_QUANTA.SOCKET4677_AZIF0045P001C01CS(CHIPS)':
 'VSS406': CDS_PINID='VSS406';
NODE_NAME     U2 BB4
 '@S9S_MB_2U_LIB.S9S_MB_2U(SCH_1):PAGE41_I9@PURE_QUANTA.SOCKET4677_AZIF0045P001C01CS(CHIPS)':
 'VSS407': CDS_PINID='VSS407';
NODE_NAME     U2 BB63
 '@S9S_MB_2U_LIB.S9S_MB_2U(SCH_1):PAGE41_I9@PURE_QUANTA.SOCKET4677_AZIF0045P001C01CS(CHIPS)':
 'VSS408': CDS_PINID='VSS408';
NODE_NAME     U2 BB69
 '@S9S_MB_2U_LIB.S9S_MB_2U(SCH_1):PAGE41_I9@PURE_QUANTA.SOCKET4677_AZIF0045P001C01CS(CHIPS)':
 'VSS409': CDS_PINID='VSS409';
NODE_NAME     U2 BB71
 '@S9S_MB_2U_LIB.S9S_MB_2U(SCH_1):PAGE41_I9@PURE_QUANTA.SOCKET4677_AZIF0045P001C01CS(CHIPS)':
 'VSS410': CDS_PINID='VSS410';
NODE_NAME     U2 BB77
 '@S9S_MB_2U_LIB.S9S_MB_2U(SCH_1):PAGE41_I9@PURE_QUANTA.SOCKET4677_AZIF0045P001C01CS(CHIPS)':
 'VSS411': CDS_PINID='VSS411';
NODE_NAME     U2 BB79
 '@S9S_MB_2U_LIB.S9S_MB_2U(SCH_1):PAGE41_I9@PURE_QUANTA.SOCKET4677_AZIF0045P001C01CS(CHIPS)':
 'VSS412': CDS_PINID='VSS412';
NODE_NAME     U2 BB8
 '@S9S_MB_2U_LIB.S9S_MB_2U(SCH_1):PAGE41_I9@PURE_QUANTA.SOCKET4677_AZIF0045P001C01CS(CHIPS)':
 'VSS413': CDS_PINID='VSS413';
NODE_NAME     U2 BB83
 '@S9S_MB_2U_LIB.S9S_MB_2U(SCH_1):PAGE41_I9@PURE_QUANTA.SOCKET4677_AZIF0045P001C01CS(CHIPS)':
 'VSS414': CDS_PINID='VSS414';
NODE_NAME     U2 BB87
 '@S9S_MB_2U_LIB.S9S_MB_2U(SCH_1):PAGE41_I9@PURE_QUANTA.SOCKET4677_AZIF0045P001C01CS(CHIPS)':
 'VSS415': CDS_PINID='VSS415';
NODE_NAME     U2 BB91
 '@S9S_MB_2U_LIB.S9S_MB_2U(SCH_1):PAGE41_I9@PURE_QUANTA.SOCKET4677_AZIF0045P001C01CS(CHIPS)':
 'VSS416': CDS_PINID='VSS416';
NODE_NAME     U2 BC1
 '@S9S_MB_2U_LIB.S9S_MB_2U(SCH_1):PAGE41_I9@PURE_QUANTA.SOCKET4677_AZIF0045P001C01CS(CHIPS)':
 'VSS417': CDS_PINID='VSS417';
NODE_NAME     U2 BC13
 '@S9S_MB_2U_LIB.S9S_MB_2U(SCH_1):PAGE41_I9@PURE_QUANTA.SOCKET4677_AZIF0045P001C01CS(CHIPS)':
 'VSS418': CDS_PINID='VSS418';
NODE_NAME     U2 BC17
 '@S9S_MB_2U_LIB.S9S_MB_2U(SCH_1):PAGE41_I9@PURE_QUANTA.SOCKET4677_AZIF0045P001C01CS(CHIPS)':
 'VSS419': CDS_PINID='VSS419';
NODE_NAME     U2 BC5
 '@S9S_MB_2U_LIB.S9S_MB_2U(SCH_1):PAGE41_I9@PURE_QUANTA.SOCKET4677_AZIF0045P001C01CS(CHIPS)':
 'VSS420': CDS_PINID='VSS420';
NODE_NAME     U2 BC62
 '@S9S_MB_2U_LIB.S9S_MB_2U(SCH_1):PAGE41_I9@PURE_QUANTA.SOCKET4677_AZIF0045P001C01CS(CHIPS)':
 'VSS421': CDS_PINID='VSS421';
NODE_NAME     U2 BC66
 '@S9S_MB_2U_LIB.S9S_MB_2U(SCH_1):PAGE41_I9@PURE_QUANTA.SOCKET4677_AZIF0045P001C01CS(CHIPS)':
 'VSS422': CDS_PINID='VSS422';
NODE_NAME     U2 BC72
 '@S9S_MB_2U_LIB.S9S_MB_2U(SCH_1):PAGE41_I9@PURE_QUANTA.SOCKET4677_AZIF0045P001C01CS(CHIPS)':
 'VSS423': CDS_PINID='VSS423';
NODE_NAME     U2 BC76
 '@S9S_MB_2U_LIB.S9S_MB_2U(SCH_1):PAGE41_I9@PURE_QUANTA.SOCKET4677_AZIF0045P001C01CS(CHIPS)':
 'VSS424': CDS_PINID='VSS424';
NODE_NAME     U2 BC78
 '@S9S_MB_2U_LIB.S9S_MB_2U(SCH_1):PAGE41_I9@PURE_QUANTA.SOCKET4677_AZIF0045P001C01CS(CHIPS)':
 'VSS425': CDS_PINID='VSS425';
NODE_NAME     U2 BC84
 '@S9S_MB_2U_LIB.S9S_MB_2U(SCH_1):PAGE41_I9@PURE_QUANTA.SOCKET4677_AZIF0045P001C01CS(CHIPS)':
 'VSS426': CDS_PINID='VSS426';
NODE_NAME     U2 BC86
 '@S9S_MB_2U_LIB.S9S_MB_2U(SCH_1):PAGE41_I9@PURE_QUANTA.SOCKET4677_AZIF0045P001C01CS(CHIPS)':
 'VSS427': CDS_PINID='VSS427';
NODE_NAME     U2 BC88
 '@S9S_MB_2U_LIB.S9S_MB_2U(SCH_1):PAGE41_I9@PURE_QUANTA.SOCKET4677_AZIF0045P001C01CS(CHIPS)':
 'VSS428': CDS_PINID='VSS428';
NODE_NAME     U2 BC9
 '@S9S_MB_2U_LIB.S9S_MB_2U(SCH_1):PAGE41_I9@PURE_QUANTA.SOCKET4677_AZIF0045P001C01CS(CHIPS)':
 'VSS429': CDS_PINID='VSS429';
NODE_NAME     U2 BD12
 '@S9S_MB_2U_LIB.S9S_MB_2U(SCH_1):PAGE41_I9@PURE_QUANTA.SOCKET4677_AZIF0045P001C01CS(CHIPS)':
 'VSS430': CDS_PINID='VSS430';
NODE_NAME     U2 BD16
 '@S9S_MB_2U_LIB.S9S_MB_2U(SCH_1):PAGE41_I9@PURE_QUANTA.SOCKET4677_AZIF0045P001C01CS(CHIPS)':
 'VSS431': CDS_PINID='VSS431';
NODE_NAME     U2 BD20
 '@S9S_MB_2U_LIB.S9S_MB_2U(SCH_1):PAGE41_I9@PURE_QUANTA.SOCKET4677_AZIF0045P001C01CS(CHIPS)':
 'VSS432': CDS_PINID='VSS432';
NODE_NAME     U2 BD4
 '@S9S_MB_2U_LIB.S9S_MB_2U(SCH_1):PAGE41_I9@PURE_QUANTA.SOCKET4677_AZIF0045P001C01CS(CHIPS)':
 'VSS433': CDS_PINID='VSS433';
NODE_NAME     U2 BD8
 '@S9S_MB_2U_LIB.S9S_MB_2U(SCH_1):PAGE41_I9@PURE_QUANTA.SOCKET4677_AZIF0045P001C01CS(CHIPS)':
 'VSS434': CDS_PINID='VSS434';
NODE_NAME     U2 BD81
 '@S9S_MB_2U_LIB.S9S_MB_2U(SCH_1):PAGE41_I9@PURE_QUANTA.SOCKET4677_AZIF0045P001C01CS(CHIPS)':
 'VSS435': CDS_PINID='VSS435';
NODE_NAME     U2 BD85
 '@S9S_MB_2U_LIB.S9S_MB_2U(SCH_1):PAGE41_I9@PURE_QUANTA.SOCKET4677_AZIF0045P001C01CS(CHIPS)':
 'VSS437': CDS_PINID='VSS437';
NODE_NAME     U2 BD89
 '@S9S_MB_2U_LIB.S9S_MB_2U(SCH_1):PAGE41_I9@PURE_QUANTA.SOCKET4677_AZIF0045P001C01CS(CHIPS)':
 'VSS439': CDS_PINID='VSS439';
NODE_NAME     U2 BE64
 '@S9S_MB_2U_LIB.S9S_MB_2U(SCH_1):PAGE41_I9@PURE_QUANTA.SOCKET4677_AZIF0045P001C01CS(CHIPS)':
 'VSS440': CDS_PINID='VSS440';
NODE_NAME     U2 BE66
 '@S9S_MB_2U_LIB.S9S_MB_2U(SCH_1):PAGE41_I9@PURE_QUANTA.SOCKET4677_AZIF0045P001C01CS(CHIPS)':
 'VSS441': CDS_PINID='VSS441';
NODE_NAME     U2 BE68
 '@S9S_MB_2U_LIB.S9S_MB_2U(SCH_1):PAGE41_I9@PURE_QUANTA.SOCKET4677_AZIF0045P001C01CS(CHIPS)':
 'VSS442': CDS_PINID='VSS442';
NODE_NAME     U2 BE74
 '@S9S_MB_2U_LIB.S9S_MB_2U(SCH_1):PAGE41_I9@PURE_QUANTA.SOCKET4677_AZIF0045P001C01CS(CHIPS)':
 'VSS443': CDS_PINID='VSS443';
NODE_NAME     U2 BE76
 '@S9S_MB_2U_LIB.S9S_MB_2U(SCH_1):PAGE41_I9@PURE_QUANTA.SOCKET4677_AZIF0045P001C01CS(CHIPS)':
 'VSS444': CDS_PINID='VSS444';
NODE_NAME     U2 BE78
 '@S9S_MB_2U_LIB.S9S_MB_2U(SCH_1):PAGE41_I9@PURE_QUANTA.SOCKET4677_AZIF0045P001C01CS(CHIPS)':
 'VSS445': CDS_PINID='VSS445';
NODE_NAME     U2 BE84
 '@S9S_MB_2U_LIB.S9S_MB_2U(SCH_1):PAGE41_I9@PURE_QUANTA.SOCKET4677_AZIF0045P001C01CS(CHIPS)':
 'VSS446': CDS_PINID='VSS446';
NODE_NAME     U2 BF12
 '@S9S_MB_2U_LIB.S9S_MB_2U(SCH_1):PAGE41_I9@PURE_QUANTA.SOCKET4677_AZIF0045P001C01CS(CHIPS)':
 'VSS447': CDS_PINID='VSS447';
NODE_NAME     U2 BF16
 '@S9S_MB_2U_LIB.S9S_MB_2U(SCH_1):PAGE41_I9@PURE_QUANTA.SOCKET4677_AZIF0045P001C01CS(CHIPS)':
 'VSS448': CDS_PINID='VSS448';
NODE_NAME     U2 BF20
 '@S9S_MB_2U_LIB.S9S_MB_2U(SCH_1):PAGE41_I9@PURE_QUANTA.SOCKET4677_AZIF0045P001C01CS(CHIPS)':
 'VSS449': CDS_PINID='VSS449';
NODE_NAME     U2 BF4
 '@S9S_MB_2U_LIB.S9S_MB_2U(SCH_1):PAGE41_I9@PURE_QUANTA.SOCKET4677_AZIF0045P001C01CS(CHIPS)':
 'VSS450': CDS_PINID='VSS450';
NODE_NAME     U2 BF61
 '@S9S_MB_2U_LIB.S9S_MB_2U(SCH_1):PAGE41_I9@PURE_QUANTA.SOCKET4677_AZIF0045P001C01CS(CHIPS)':
 'VSS451': CDS_PINID='VSS451';
NODE_NAME     U2 BF63
 '@S9S_MB_2U_LIB.S9S_MB_2U(SCH_1):PAGE41_I9@PURE_QUANTA.SOCKET4677_AZIF0045P001C01CS(CHIPS)':
 'VSS452': CDS_PINID='VSS452';
NODE_NAME     U2 BF73
 '@S9S_MB_2U_LIB.S9S_MB_2U(SCH_1):PAGE41_I9@PURE_QUANTA.SOCKET4677_AZIF0045P001C01CS(CHIPS)':
 'VSS453': CDS_PINID='VSS453';
NODE_NAME     U2 BF75
 '@S9S_MB_2U_LIB.S9S_MB_2U(SCH_1):PAGE41_I9@PURE_QUANTA.SOCKET4677_AZIF0045P001C01CS(CHIPS)':
 'VSS454': CDS_PINID='VSS454';
NODE_NAME     U2 BF79
 '@S9S_MB_2U_LIB.S9S_MB_2U(SCH_1):PAGE41_I9@PURE_QUANTA.SOCKET4677_AZIF0045P001C01CS(CHIPS)':
 'VSS455': CDS_PINID='VSS455';
NODE_NAME     U2 BF8
 '@S9S_MB_2U_LIB.S9S_MB_2U(SCH_1):PAGE41_I9@PURE_QUANTA.SOCKET4677_AZIF0045P001C01CS(CHIPS)':
 'VSS456': CDS_PINID='VSS456';
NODE_NAME     U2 BF83
 '@S9S_MB_2U_LIB.S9S_MB_2U(SCH_1):PAGE41_I9@PURE_QUANTA.SOCKET4677_AZIF0045P001C01CS(CHIPS)':
 'VSS457': CDS_PINID='VSS457';
NODE_NAME     U2 BG1
 '@S9S_MB_2U_LIB.S9S_MB_2U(SCH_1):PAGE41_I9@PURE_QUANTA.SOCKET4677_AZIF0045P001C01CS(CHIPS)':
 'VSS458': CDS_PINID='VSS458';
NODE_NAME     U2 BG13
 '@S9S_MB_2U_LIB.S9S_MB_2U(SCH_1):PAGE41_I9@PURE_QUANTA.SOCKET4677_AZIF0045P001C01CS(CHIPS)':
 'VSS459': CDS_PINID='VSS459';
NODE_NAME     U2 BG17
 '@S9S_MB_2U_LIB.S9S_MB_2U(SCH_1):PAGE41_I9@PURE_QUANTA.SOCKET4677_AZIF0045P001C01CS(CHIPS)':
 'VSS460': CDS_PINID='VSS460';
NODE_NAME     U2 BG21
 '@S9S_MB_2U_LIB.S9S_MB_2U(SCH_1):PAGE41_I9@PURE_QUANTA.SOCKET4677_AZIF0045P001C01CS(CHIPS)':
 'VSS461': CDS_PINID='VSS461';
NODE_NAME     U2 BG23
 '@S9S_MB_2U_LIB.S9S_MB_2U(SCH_1):PAGE41_I9@PURE_QUANTA.SOCKET4677_AZIF0045P001C01CS(CHIPS)':
 'VSS462': CDS_PINID='VSS462';
NODE_NAME     U2 BG25
 '@S9S_MB_2U_LIB.S9S_MB_2U(SCH_1):PAGE41_I9@PURE_QUANTA.SOCKET4677_AZIF0045P001C01CS(CHIPS)':
 'VSS463': CDS_PINID='VSS463';
NODE_NAME     U2 BG5
 '@S9S_MB_2U_LIB.S9S_MB_2U(SCH_1):PAGE41_I9@PURE_QUANTA.SOCKET4677_AZIF0045P001C01CS(CHIPS)':
 'VSS464': CDS_PINID='VSS464';
NODE_NAME     U2 BG70
 '@S9S_MB_2U_LIB.S9S_MB_2U(SCH_1):PAGE41_I9@PURE_QUANTA.SOCKET4677_AZIF0045P001C01CS(CHIPS)':
 'VSS465': CDS_PINID='VSS465';
NODE_NAME     U2 BG9
 '@S9S_MB_2U_LIB.S9S_MB_2U(SCH_1):PAGE41_I9@PURE_QUANTA.SOCKET4677_AZIF0045P001C01CS(CHIPS)':
 'VSS466': CDS_PINID='VSS466';
NODE_NAME     U2 BH12
 '@S9S_MB_2U_LIB.S9S_MB_2U(SCH_1):PAGE41_I9@PURE_QUANTA.SOCKET4677_AZIF0045P001C01CS(CHIPS)':
 'VSS467': CDS_PINID='VSS467';
NODE_NAME     U2 BH16
 '@S9S_MB_2U_LIB.S9S_MB_2U(SCH_1):PAGE41_I9@PURE_QUANTA.SOCKET4677_AZIF0045P001C01CS(CHIPS)':
 'VSS468': CDS_PINID='VSS468';
NODE_NAME     U2 BH20
 '@S9S_MB_2U_LIB.S9S_MB_2U(SCH_1):PAGE41_I9@PURE_QUANTA.SOCKET4677_AZIF0045P001C01CS(CHIPS)':
 'VSS469': CDS_PINID='VSS469';
NODE_NAME     U2 BH4
 '@S9S_MB_2U_LIB.S9S_MB_2U(SCH_1):PAGE41_I9@PURE_QUANTA.SOCKET4677_AZIF0045P001C01CS(CHIPS)':
 'VSS470': CDS_PINID='VSS470';
NODE_NAME     U2 BH67
 '@S9S_MB_2U_LIB.S9S_MB_2U(SCH_1):PAGE41_I9@PURE_QUANTA.SOCKET4677_AZIF0045P001C01CS(CHIPS)':
 'VSS472': CDS_PINID='VSS472';
NODE_NAME     U2 BH73
 '@S9S_MB_2U_LIB.S9S_MB_2U(SCH_1):PAGE41_I9@PURE_QUANTA.SOCKET4677_AZIF0045P001C01CS(CHIPS)':
 'VSS473': CDS_PINID='VSS473';
NODE_NAME     U2 BH77
 '@S9S_MB_2U_LIB.S9S_MB_2U(SCH_1):PAGE41_I9@PURE_QUANTA.SOCKET4677_AZIF0045P001C01CS(CHIPS)':
 'VSS474': CDS_PINID='VSS474';
NODE_NAME     U2 BH8
 '@S9S_MB_2U_LIB.S9S_MB_2U(SCH_1):PAGE41_I9@PURE_QUANTA.SOCKET4677_AZIF0045P001C01CS(CHIPS)':
 'VSS475': CDS_PINID='VSS475';
NODE_NAME     U2 BH81
 '@S9S_MB_2U_LIB.S9S_MB_2U(SCH_1):PAGE41_I9@PURE_QUANTA.SOCKET4677_AZIF0045P001C01CS(CHIPS)':
 'VSS476': CDS_PINID='VSS476';
NODE_NAME     U2 BH83
 '@S9S_MB_2U_LIB.S9S_MB_2U(SCH_1):PAGE41_I9@PURE_QUANTA.SOCKET4677_AZIF0045P001C01CS(CHIPS)':
 'VSS477': CDS_PINID='VSS477';
NODE_NAME     U2 BJ62
 '@S9S_MB_2U_LIB.S9S_MB_2U(SCH_1):PAGE41_I9@PURE_QUANTA.SOCKET4677_AZIF0045P001C01CS(CHIPS)':
 'VSS479': CDS_PINID='VSS479';
NODE_NAME     U2 BJ68
 '@S9S_MB_2U_LIB.S9S_MB_2U(SCH_1):PAGE41_I9@PURE_QUANTA.SOCKET4677_AZIF0045P001C01CS(CHIPS)':
 'VSS480': CDS_PINID='VSS480';
NODE_NAME     U2 BJ80
 '@S9S_MB_2U_LIB.S9S_MB_2U(SCH_1):PAGE41_I9@PURE_QUANTA.SOCKET4677_AZIF0045P001C01CS(CHIPS)':
 'VSS481': CDS_PINID='VSS481';
NODE_NAME     U2 BJ82
 '@S9S_MB_2U_LIB.S9S_MB_2U(SCH_1):PAGE41_I9@PURE_QUANTA.SOCKET4677_AZIF0045P001C01CS(CHIPS)':
 'VSS482': CDS_PINID='VSS482';
NODE_NAME     U2 BJ84
 '@S9S_MB_2U_LIB.S9S_MB_2U(SCH_1):PAGE41_I9@PURE_QUANTA.SOCKET4677_AZIF0045P001C01CS(CHIPS)':
 'VSS483': CDS_PINID='VSS483';
NODE_NAME     U2 BJ86
 '@S9S_MB_2U_LIB.S9S_MB_2U(SCH_1):PAGE41_I9@PURE_QUANTA.SOCKET4677_AZIF0045P001C01CS(CHIPS)':
 'VSS484': CDS_PINID='VSS484';
NODE_NAME     U2 BJ88
 '@S9S_MB_2U_LIB.S9S_MB_2U(SCH_1):PAGE41_I9@PURE_QUANTA.SOCKET4677_AZIF0045P001C01CS(CHIPS)':
 'VSS485': CDS_PINID='VSS485';
NODE_NAME     U2 BJ90
 '@S9S_MB_2U_LIB.S9S_MB_2U(SCH_1):PAGE41_I9@PURE_QUANTA.SOCKET4677_AZIF0045P001C01CS(CHIPS)':
 'VSS486': CDS_PINID='VSS486';
NODE_NAME     U2 BK12
 '@S9S_MB_2U_LIB.S9S_MB_2U(SCH_1):PAGE41_I9@PURE_QUANTA.SOCKET4677_AZIF0045P001C01CS(CHIPS)':
 'VSS487': CDS_PINID='VSS487';
NODE_NAME     U2 BK16
 '@S9S_MB_2U_LIB.S9S_MB_2U(SCH_1):PAGE41_I9@PURE_QUANTA.SOCKET4677_AZIF0045P001C01CS(CHIPS)':
 'VSS488': CDS_PINID='VSS488';
NODE_NAME     U2 BK20
 '@S9S_MB_2U_LIB.S9S_MB_2U(SCH_1):PAGE41_I9@PURE_QUANTA.SOCKET4677_AZIF0045P001C01CS(CHIPS)':
 'VSS489': CDS_PINID='VSS489';
NODE_NAME     U2 BK4
 '@S9S_MB_2U_LIB.S9S_MB_2U(SCH_1):PAGE41_I9@PURE_QUANTA.SOCKET4677_AZIF0045P001C01CS(CHIPS)':
 'VSS490': CDS_PINID='VSS490';
NODE_NAME     U2 BK65
 '@S9S_MB_2U_LIB.S9S_MB_2U(SCH_1):PAGE41_I9@PURE_QUANTA.SOCKET4677_AZIF0045P001C01CS(CHIPS)':
 'VSS491': CDS_PINID='VSS491';
NODE_NAME     U2 BK71
 '@S9S_MB_2U_LIB.S9S_MB_2U(SCH_1):PAGE41_I9@PURE_QUANTA.SOCKET4677_AZIF0045P001C01CS(CHIPS)':
 'VSS492': CDS_PINID='VSS492';
NODE_NAME     U2 BK75
 '@S9S_MB_2U_LIB.S9S_MB_2U(SCH_1):PAGE41_I9@PURE_QUANTA.SOCKET4677_AZIF0045P001C01CS(CHIPS)':
 'VSS494': CDS_PINID='VSS494';
NODE_NAME     U2 BK79
 '@S9S_MB_2U_LIB.S9S_MB_2U(SCH_1):PAGE41_I9@PURE_QUANTA.SOCKET4677_AZIF0045P001C01CS(CHIPS)':
 'VSS495': CDS_PINID='VSS495';
NODE_NAME     U2 BK8
 '@S9S_MB_2U_LIB.S9S_MB_2U(SCH_1):PAGE41_I9@PURE_QUANTA.SOCKET4677_AZIF0045P001C01CS(CHIPS)':
 'VSS496': CDS_PINID='VSS496';
NODE_NAME     U2 BL1
 '@S9S_MB_2U_LIB.S9S_MB_2U(SCH_1):PAGE41_I9@PURE_QUANTA.SOCKET4677_AZIF0045P001C01CS(CHIPS)':
 'VSS497': CDS_PINID='VSS497';
NODE_NAME     U2 BL13
 '@S9S_MB_2U_LIB.S9S_MB_2U(SCH_1):PAGE41_I9@PURE_QUANTA.SOCKET4677_AZIF0045P001C01CS(CHIPS)':
 'VSS498': CDS_PINID='VSS498';
NODE_NAME     U2 BL17
 '@S9S_MB_2U_LIB.S9S_MB_2U(SCH_1):PAGE41_I9@PURE_QUANTA.SOCKET4677_AZIF0045P001C01CS(CHIPS)':
 'VSS499': CDS_PINID='VSS499';
NODE_NAME     U2 BL5
 '@S9S_MB_2U_LIB.S9S_MB_2U(SCH_1):PAGE41_I9@PURE_QUANTA.SOCKET4677_AZIF0045P001C01CS(CHIPS)':
 'VSS500': CDS_PINID='VSS500';
NODE_NAME     U2 BL68
 '@S9S_MB_2U_LIB.S9S_MB_2U(SCH_1):PAGE41_I9@PURE_QUANTA.SOCKET4677_AZIF0045P001C01CS(CHIPS)':
 'VSS501': CDS_PINID='VSS501';
NODE_NAME     U2 BL70
 '@S9S_MB_2U_LIB.S9S_MB_2U(SCH_1):PAGE41_I9@PURE_QUANTA.SOCKET4677_AZIF0045P001C01CS(CHIPS)':
 'VSS502': CDS_PINID='VSS502';
NODE_NAME     U2 BL72
 '@S9S_MB_2U_LIB.S9S_MB_2U(SCH_1):PAGE41_I9@PURE_QUANTA.SOCKET4677_AZIF0045P001C01CS(CHIPS)':
 'VSS503': CDS_PINID='VSS503';
NODE_NAME     U2 BL78
 '@S9S_MB_2U_LIB.S9S_MB_2U(SCH_1):PAGE41_I9@PURE_QUANTA.SOCKET4677_AZIF0045P001C01CS(CHIPS)':
 'VSS504': CDS_PINID='VSS504';
NODE_NAME     U2 BL9
 '@S9S_MB_2U_LIB.S9S_MB_2U(SCH_1):PAGE41_I9@PURE_QUANTA.SOCKET4677_AZIF0045P001C01CS(CHIPS)':
 'VSS505': CDS_PINID='VSS505';
NODE_NAME     U2 BM12
 '@S9S_MB_2U_LIB.S9S_MB_2U(SCH_1):PAGE41_I9@PURE_QUANTA.SOCKET4677_AZIF0045P001C01CS(CHIPS)':
 'VSS506': CDS_PINID='VSS506';
NODE_NAME     U2 BM16
 '@S9S_MB_2U_LIB.S9S_MB_2U(SCH_1):PAGE41_I9@PURE_QUANTA.SOCKET4677_AZIF0045P001C01CS(CHIPS)':
 'VSS507': CDS_PINID='VSS507';
NODE_NAME     U2 BM20
 '@S9S_MB_2U_LIB.S9S_MB_2U(SCH_1):PAGE41_I9@PURE_QUANTA.SOCKET4677_AZIF0045P001C01CS(CHIPS)':
 'VSS508': CDS_PINID='VSS508';
NODE_NAME     U2 BM22
 '@S9S_MB_2U_LIB.S9S_MB_2U(SCH_1):PAGE41_I9@PURE_QUANTA.SOCKET4677_AZIF0045P001C01CS(CHIPS)':
 'VSS509': CDS_PINID='VSS509';
NODE_NAME     U2 BM24
 '@S9S_MB_2U_LIB.S9S_MB_2U(SCH_1):PAGE41_I9@PURE_QUANTA.SOCKET4677_AZIF0045P001C01CS(CHIPS)':
 'VSS510': CDS_PINID='VSS510';
NODE_NAME     U2 BM26
 '@S9S_MB_2U_LIB.S9S_MB_2U(SCH_1):PAGE41_I9@PURE_QUANTA.SOCKET4677_AZIF0045P001C01CS(CHIPS)':
 'VSS511': CDS_PINID='VSS511';
NODE_NAME     U2 BM4
 '@S9S_MB_2U_LIB.S9S_MB_2U(SCH_1):PAGE41_I9@PURE_QUANTA.SOCKET4677_AZIF0045P001C01CS(CHIPS)':
 'VSS512': CDS_PINID='VSS512';
NODE_NAME     U2 BM61
 '@S9S_MB_2U_LIB.S9S_MB_2U(SCH_1):PAGE41_I9@PURE_QUANTA.SOCKET4677_AZIF0045P001C01CS(CHIPS)':
 'VSS513': CDS_PINID='VSS513';
NODE_NAME     U2 BM73
 '@S9S_MB_2U_LIB.S9S_MB_2U(SCH_1):PAGE41_I9@PURE_QUANTA.SOCKET4677_AZIF0045P001C01CS(CHIPS)':
 'VSS515': CDS_PINID='VSS515';
NODE_NAME     U2 BM77
 '@S9S_MB_2U_LIB.S9S_MB_2U(SCH_1):PAGE41_I9@PURE_QUANTA.SOCKET4677_AZIF0045P001C01CS(CHIPS)':
 'VSS516': CDS_PINID='VSS516';
NODE_NAME     U2 BM8
 '@S9S_MB_2U_LIB.S9S_MB_2U(SCH_1):PAGE41_I9@PURE_QUANTA.SOCKET4677_AZIF0045P001C01CS(CHIPS)':
 'VSS517': CDS_PINID='VSS517';
NODE_NAME     U2 BN31
 '@S9S_MB_2U_LIB.S9S_MB_2U(SCH_1):PAGE41_I9@PURE_QUANTA.SOCKET4677_AZIF0045P001C01CS(CHIPS)':
 'VSS518': CDS_PINID='VSS518';
NODE_NAME     U2 BN62
 '@S9S_MB_2U_LIB.S9S_MB_2U(SCH_1):PAGE41_I9@PURE_QUANTA.SOCKET4677_AZIF0045P001C01CS(CHIPS)':
 'VSS519': CDS_PINID='VSS519';
NODE_NAME     U2 BN70
 '@S9S_MB_2U_LIB.S9S_MB_2U(SCH_1):PAGE41_I9@PURE_QUANTA.SOCKET4677_AZIF0045P001C01CS(CHIPS)':
 'VSS520': CDS_PINID='VSS520';
NODE_NAME     U2 BP12
 '@S9S_MB_2U_LIB.S9S_MB_2U(SCH_1):PAGE41_I9@PURE_QUANTA.SOCKET4677_AZIF0045P001C01CS(CHIPS)':
 'VSS522': CDS_PINID='VSS522';
NODE_NAME     U2 BP16
 '@S9S_MB_2U_LIB.S9S_MB_2U(SCH_1):PAGE41_I9@PURE_QUANTA.SOCKET4677_AZIF0045P001C01CS(CHIPS)':
 'VSS523': CDS_PINID='VSS523';
NODE_NAME     U2 BP2
 '@S9S_MB_2U_LIB.S9S_MB_2U(SCH_1):PAGE41_I9@PURE_QUANTA.SOCKET4677_AZIF0045P001C01CS(CHIPS)':
 'VSS524': CDS_PINID='VSS524';
NODE_NAME     U2 BP20
 '@S9S_MB_2U_LIB.S9S_MB_2U(SCH_1):PAGE41_I9@PURE_QUANTA.SOCKET4677_AZIF0045P001C01CS(CHIPS)':
 'VSS525': CDS_PINID='VSS525';
NODE_NAME     U2 BP4
 '@S9S_MB_2U_LIB.S9S_MB_2U(SCH_1):PAGE41_I9@PURE_QUANTA.SOCKET4677_AZIF0045P001C01CS(CHIPS)':
 'VSS527': CDS_PINID='VSS527';
NODE_NAME     U2 BP63
 '@S9S_MB_2U_LIB.S9S_MB_2U(SCH_1):PAGE41_I9@PURE_QUANTA.SOCKET4677_AZIF0045P001C01CS(CHIPS)':
 'VSS528': CDS_PINID='VSS528';
NODE_NAME     U2 BP71
 '@S9S_MB_2U_LIB.S9S_MB_2U(SCH_1):PAGE41_I9@PURE_QUANTA.SOCKET4677_AZIF0045P001C01CS(CHIPS)':
 'VSS529': CDS_PINID='VSS529';
NODE_NAME     U2 BP73
 '@S9S_MB_2U_LIB.S9S_MB_2U(SCH_1):PAGE41_I9@PURE_QUANTA.SOCKET4677_AZIF0045P001C01CS(CHIPS)':
 'VSS530': CDS_PINID='VSS530';
NODE_NAME     U2 BP75
 '@S9S_MB_2U_LIB.S9S_MB_2U(SCH_1):PAGE41_I9@PURE_QUANTA.SOCKET4677_AZIF0045P001C01CS(CHIPS)':
 'VSS531': CDS_PINID='VSS531';
NODE_NAME     U2 BP77
 '@S9S_MB_2U_LIB.S9S_MB_2U(SCH_1):PAGE41_I9@PURE_QUANTA.SOCKET4677_AZIF0045P001C01CS(CHIPS)':
 'VSS532': CDS_PINID='VSS532';
NODE_NAME     U2 BP8
 '@S9S_MB_2U_LIB.S9S_MB_2U(SCH_1):PAGE41_I9@PURE_QUANTA.SOCKET4677_AZIF0045P001C01CS(CHIPS)':
 'VSS533': CDS_PINID='VSS533';
NODE_NAME     U2 BR13
 '@S9S_MB_2U_LIB.S9S_MB_2U(SCH_1):PAGE41_I9@PURE_QUANTA.SOCKET4677_AZIF0045P001C01CS(CHIPS)':
 'VSS535': CDS_PINID='VSS535';
NODE_NAME     U2 BR17
 '@S9S_MB_2U_LIB.S9S_MB_2U(SCH_1):PAGE41_I9@PURE_QUANTA.SOCKET4677_AZIF0045P001C01CS(CHIPS)':
 'VSS536': CDS_PINID='VSS536';
NODE_NAME     U2 BR27
 '@S9S_MB_2U_LIB.S9S_MB_2U(SCH_1):PAGE41_I9@PURE_QUANTA.SOCKET4677_AZIF0045P001C01CS(CHIPS)':
 'VSS538': CDS_PINID='VSS538';
NODE_NAME     U2 BR29
 '@S9S_MB_2U_LIB.S9S_MB_2U(SCH_1):PAGE41_I9@PURE_QUANTA.SOCKET4677_AZIF0045P001C01CS(CHIPS)':
 'VSS539': CDS_PINID='VSS539';
NODE_NAME     U2 BR31
 '@S9S_MB_2U_LIB.S9S_MB_2U(SCH_1):PAGE41_I9@PURE_QUANTA.SOCKET4677_AZIF0045P001C01CS(CHIPS)':
 'VSS540': CDS_PINID='VSS540';
NODE_NAME     U2 BR33
 '@S9S_MB_2U_LIB.S9S_MB_2U(SCH_1):PAGE41_I9@PURE_QUANTA.SOCKET4677_AZIF0045P001C01CS(CHIPS)':
 'VSS541': CDS_PINID='VSS541';
NODE_NAME     U2 BR9
 '@S9S_MB_2U_LIB.S9S_MB_2U(SCH_1):PAGE41_I9@PURE_QUANTA.SOCKET4677_AZIF0045P001C01CS(CHIPS)':
 'VSS572': CDS_PINID='VSS572';
NODE_NAME     U2 AK12
 '@S9S_MB_2U_LIB.S9S_MB_2U(SCH_1):PAGE41_I10@PURE_QUANTA.SOCKET4677_AZIF0045P001C01CS(CHIPS)':
 'VSS198': CDS_PINID='VSS198';
NODE_NAME     U2 AK16
 '@S9S_MB_2U_LIB.S9S_MB_2U(SCH_1):PAGE41_I10@PURE_QUANTA.SOCKET4677_AZIF0045P001C01CS(CHIPS)':
 'VSS199': CDS_PINID='VSS199';
NODE_NAME     U2 AK18
 '@S9S_MB_2U_LIB.S9S_MB_2U(SCH_1):PAGE41_I10@PURE_QUANTA.SOCKET4677_AZIF0045P001C01CS(CHIPS)':
 'VSS200': CDS_PINID='VSS200';
NODE_NAME     U2 AK24
 '@S9S_MB_2U_LIB.S9S_MB_2U(SCH_1):PAGE41_I10@PURE_QUANTA.SOCKET4677_AZIF0045P001C01CS(CHIPS)':
 'VSS201': CDS_PINID='VSS201';
NODE_NAME     U2 AK30
 '@S9S_MB_2U_LIB.S9S_MB_2U(SCH_1):PAGE41_I10@PURE_QUANTA.SOCKET4677_AZIF0045P001C01CS(CHIPS)':
 'VSS202': CDS_PINID='VSS202';
NODE_NAME     U2 AK36
 '@S9S_MB_2U_LIB.S9S_MB_2U(SCH_1):PAGE41_I10@PURE_QUANTA.SOCKET4677_AZIF0045P001C01CS(CHIPS)':
 'VSS203': CDS_PINID='VSS203';
NODE_NAME     U2 AK4
 '@S9S_MB_2U_LIB.S9S_MB_2U(SCH_1):PAGE41_I10@PURE_QUANTA.SOCKET4677_AZIF0045P001C01CS(CHIPS)':
 'VSS204': CDS_PINID='VSS204';
NODE_NAME     U2 AK42
 '@S9S_MB_2U_LIB.S9S_MB_2U(SCH_1):PAGE41_I10@PURE_QUANTA.SOCKET4677_AZIF0045P001C01CS(CHIPS)':
 'VSS205': CDS_PINID='VSS205';
NODE_NAME     U2 AK49
 '@S9S_MB_2U_LIB.S9S_MB_2U(SCH_1):PAGE41_I10@PURE_QUANTA.SOCKET4677_AZIF0045P001C01CS(CHIPS)':
 'VSS206': CDS_PINID='VSS206';
NODE_NAME     U2 AK55
 '@S9S_MB_2U_LIB.S9S_MB_2U(SCH_1):PAGE41_I10@PURE_QUANTA.SOCKET4677_AZIF0045P001C01CS(CHIPS)':
 'VSS207': CDS_PINID='VSS207';
NODE_NAME     U2 AK61
 '@S9S_MB_2U_LIB.S9S_MB_2U(SCH_1):PAGE41_I10@PURE_QUANTA.SOCKET4677_AZIF0045P001C01CS(CHIPS)':
 'VSS208': CDS_PINID='VSS208';
NODE_NAME     U2 AK67
 '@S9S_MB_2U_LIB.S9S_MB_2U(SCH_1):PAGE41_I10@PURE_QUANTA.SOCKET4677_AZIF0045P001C01CS(CHIPS)':
 'VSS209': CDS_PINID='VSS209';
NODE_NAME     U2 AK73
 '@S9S_MB_2U_LIB.S9S_MB_2U(SCH_1):PAGE41_I10@PURE_QUANTA.SOCKET4677_AZIF0045P001C01CS(CHIPS)':
 'VSS210': CDS_PINID='VSS210';
NODE_NAME     U2 AK79
 '@S9S_MB_2U_LIB.S9S_MB_2U(SCH_1):PAGE41_I10@PURE_QUANTA.SOCKET4677_AZIF0045P001C01CS(CHIPS)':
 'VSS211': CDS_PINID='VSS211';
NODE_NAME     U2 AK8
 '@S9S_MB_2U_LIB.S9S_MB_2U(SCH_1):PAGE41_I10@PURE_QUANTA.SOCKET4677_AZIF0045P001C01CS(CHIPS)':
 'VSS212': CDS_PINID='VSS212';
NODE_NAME     U2 AK81
 '@S9S_MB_2U_LIB.S9S_MB_2U(SCH_1):PAGE41_I10@PURE_QUANTA.SOCKET4677_AZIF0045P001C01CS(CHIPS)':
 'VSS213': CDS_PINID='VSS213';
NODE_NAME     U2 AK83
 '@S9S_MB_2U_LIB.S9S_MB_2U(SCH_1):PAGE41_I10@PURE_QUANTA.SOCKET4677_AZIF0045P001C01CS(CHIPS)':
 'VSS214': CDS_PINID='VSS214';
NODE_NAME     U2 AK87
 '@S9S_MB_2U_LIB.S9S_MB_2U(SCH_1):PAGE41_I10@PURE_QUANTA.SOCKET4677_AZIF0045P001C01CS(CHIPS)':
 'VSS215': CDS_PINID='VSS215';
NODE_NAME     U2 AK91
 '@S9S_MB_2U_LIB.S9S_MB_2U(SCH_1):PAGE41_I10@PURE_QUANTA.SOCKET4677_AZIF0045P001C01CS(CHIPS)':
 'VSS216': CDS_PINID='VSS216';
NODE_NAME     U2 AL1
 '@S9S_MB_2U_LIB.S9S_MB_2U(SCH_1):PAGE41_I10@PURE_QUANTA.SOCKET4677_AZIF0045P001C01CS(CHIPS)':
 'VSS217': CDS_PINID='VSS217';
NODE_NAME     U2 AL13
 '@S9S_MB_2U_LIB.S9S_MB_2U(SCH_1):PAGE41_I10@PURE_QUANTA.SOCKET4677_AZIF0045P001C01CS(CHIPS)':
 'VSS218': CDS_PINID='VSS218';
NODE_NAME     U2 AL17
 '@S9S_MB_2U_LIB.S9S_MB_2U(SCH_1):PAGE41_I10@PURE_QUANTA.SOCKET4677_AZIF0045P001C01CS(CHIPS)':
 'VSS219': CDS_PINID='VSS219';
NODE_NAME     U2 AL5
 '@S9S_MB_2U_LIB.S9S_MB_2U(SCH_1):PAGE41_I10@PURE_QUANTA.SOCKET4677_AZIF0045P001C01CS(CHIPS)':
 'VSS220': CDS_PINID='VSS220';
NODE_NAME     U2 AL52
 '@S9S_MB_2U_LIB.S9S_MB_2U(SCH_1):PAGE41_I10@PURE_QUANTA.SOCKET4677_AZIF0045P001C01CS(CHIPS)':
 'VSS221': CDS_PINID='VSS221';
NODE_NAME     U2 AL80
 '@S9S_MB_2U_LIB.S9S_MB_2U(SCH_1):PAGE41_I10@PURE_QUANTA.SOCKET4677_AZIF0045P001C01CS(CHIPS)':
 'VSS222': CDS_PINID='VSS222';
NODE_NAME     U2 AL82
 '@S9S_MB_2U_LIB.S9S_MB_2U(SCH_1):PAGE41_I10@PURE_QUANTA.SOCKET4677_AZIF0045P001C01CS(CHIPS)':
 'VSS223': CDS_PINID='VSS223';
NODE_NAME     U2 AL84
 '@S9S_MB_2U_LIB.S9S_MB_2U(SCH_1):PAGE41_I10@PURE_QUANTA.SOCKET4677_AZIF0045P001C01CS(CHIPS)':
 'VSS224': CDS_PINID='VSS224';
NODE_NAME     U2 AL88
 '@S9S_MB_2U_LIB.S9S_MB_2U(SCH_1):PAGE41_I10@PURE_QUANTA.SOCKET4677_AZIF0045P001C01CS(CHIPS)':
 'VSS225': CDS_PINID='VSS225';
NODE_NAME     U2 AL9
 '@S9S_MB_2U_LIB.S9S_MB_2U(SCH_1):PAGE41_I10@PURE_QUANTA.SOCKET4677_AZIF0045P001C01CS(CHIPS)':
 'VSS226': CDS_PINID='VSS226';
NODE_NAME     U2 AM12
 '@S9S_MB_2U_LIB.S9S_MB_2U(SCH_1):PAGE41_I10@PURE_QUANTA.SOCKET4677_AZIF0045P001C01CS(CHIPS)':
 'VSS227': CDS_PINID='VSS227';
NODE_NAME     U2 AM16
 '@S9S_MB_2U_LIB.S9S_MB_2U(SCH_1):PAGE41_I10@PURE_QUANTA.SOCKET4677_AZIF0045P001C01CS(CHIPS)':
 'VSS228': CDS_PINID='VSS228';
NODE_NAME     U2 AM18
 '@S9S_MB_2U_LIB.S9S_MB_2U(SCH_1):PAGE41_I10@PURE_QUANTA.SOCKET4677_AZIF0045P001C01CS(CHIPS)':
 'VSS229': CDS_PINID='VSS229';
NODE_NAME     U2 AM20
 '@S9S_MB_2U_LIB.S9S_MB_2U(SCH_1):PAGE41_I10@PURE_QUANTA.SOCKET4677_AZIF0045P001C01CS(CHIPS)':
 'VSS230': CDS_PINID='VSS230';
NODE_NAME     U2 AM22
 '@S9S_MB_2U_LIB.S9S_MB_2U(SCH_1):PAGE41_I10@PURE_QUANTA.SOCKET4677_AZIF0045P001C01CS(CHIPS)':
 'VSS231': CDS_PINID='VSS231';
NODE_NAME     U2 AM24
 '@S9S_MB_2U_LIB.S9S_MB_2U(SCH_1):PAGE41_I10@PURE_QUANTA.SOCKET4677_AZIF0045P001C01CS(CHIPS)':
 'VSS232': CDS_PINID='VSS232';
NODE_NAME     U2 AM26
 '@S9S_MB_2U_LIB.S9S_MB_2U(SCH_1):PAGE41_I10@PURE_QUANTA.SOCKET4677_AZIF0045P001C01CS(CHIPS)':
 'VSS233': CDS_PINID='VSS233';
NODE_NAME     U2 AM28
 '@S9S_MB_2U_LIB.S9S_MB_2U(SCH_1):PAGE41_I10@PURE_QUANTA.SOCKET4677_AZIF0045P001C01CS(CHIPS)':
 'VSS234': CDS_PINID='VSS234';
NODE_NAME     U2 AM30
 '@S9S_MB_2U_LIB.S9S_MB_2U(SCH_1):PAGE41_I10@PURE_QUANTA.SOCKET4677_AZIF0045P001C01CS(CHIPS)':
 'VSS235': CDS_PINID='VSS235';
NODE_NAME     U2 AM32
 '@S9S_MB_2U_LIB.S9S_MB_2U(SCH_1):PAGE41_I10@PURE_QUANTA.SOCKET4677_AZIF0045P001C01CS(CHIPS)':
 'VSS236': CDS_PINID='VSS236';
NODE_NAME     U2 AM34
 '@S9S_MB_2U_LIB.S9S_MB_2U(SCH_1):PAGE41_I10@PURE_QUANTA.SOCKET4677_AZIF0045P001C01CS(CHIPS)':
 'VSS237': CDS_PINID='VSS237';
NODE_NAME     U2 AM36
 '@S9S_MB_2U_LIB.S9S_MB_2U(SCH_1):PAGE41_I10@PURE_QUANTA.SOCKET4677_AZIF0045P001C01CS(CHIPS)':
 'VSS238': CDS_PINID='VSS238';
NODE_NAME     U2 AM38
 '@S9S_MB_2U_LIB.S9S_MB_2U(SCH_1):PAGE41_I10@PURE_QUANTA.SOCKET4677_AZIF0045P001C01CS(CHIPS)':
 'VSS239': CDS_PINID='VSS239';
NODE_NAME     U2 AM4
 '@S9S_MB_2U_LIB.S9S_MB_2U(SCH_1):PAGE41_I10@PURE_QUANTA.SOCKET4677_AZIF0045P001C01CS(CHIPS)':
 'VSS240': CDS_PINID='VSS240';
NODE_NAME     U2 AM40
 '@S9S_MB_2U_LIB.S9S_MB_2U(SCH_1):PAGE41_I10@PURE_QUANTA.SOCKET4677_AZIF0045P001C01CS(CHIPS)':
 'VSS241': CDS_PINID='VSS241';
NODE_NAME     U2 AM42
 '@S9S_MB_2U_LIB.S9S_MB_2U(SCH_1):PAGE41_I10@PURE_QUANTA.SOCKET4677_AZIF0045P001C01CS(CHIPS)':
 'VSS242': CDS_PINID='VSS242';
NODE_NAME     U2 AM44
 '@S9S_MB_2U_LIB.S9S_MB_2U(SCH_1):PAGE41_I10@PURE_QUANTA.SOCKET4677_AZIF0045P001C01CS(CHIPS)':
 'VSS243': CDS_PINID='VSS243';
NODE_NAME     U2 AM47
 '@S9S_MB_2U_LIB.S9S_MB_2U(SCH_1):PAGE41_I10@PURE_QUANTA.SOCKET4677_AZIF0045P001C01CS(CHIPS)':
 'VSS244': CDS_PINID='VSS244';
NODE_NAME     U2 AM49
 '@S9S_MB_2U_LIB.S9S_MB_2U(SCH_1):PAGE41_I10@PURE_QUANTA.SOCKET4677_AZIF0045P001C01CS(CHIPS)':
 'VSS245': CDS_PINID='VSS245';
NODE_NAME     U2 AM51
 '@S9S_MB_2U_LIB.S9S_MB_2U(SCH_1):PAGE41_I10@PURE_QUANTA.SOCKET4677_AZIF0045P001C01CS(CHIPS)':
 'VSS246': CDS_PINID='VSS246';
NODE_NAME     U2 AM53
 '@S9S_MB_2U_LIB.S9S_MB_2U(SCH_1):PAGE41_I10@PURE_QUANTA.SOCKET4677_AZIF0045P001C01CS(CHIPS)':
 'VSS247': CDS_PINID='VSS247';
NODE_NAME     U2 AM55
 '@S9S_MB_2U_LIB.S9S_MB_2U(SCH_1):PAGE41_I10@PURE_QUANTA.SOCKET4677_AZIF0045P001C01CS(CHIPS)':
 'VSS248': CDS_PINID='VSS248';
NODE_NAME     U2 AM57
 '@S9S_MB_2U_LIB.S9S_MB_2U(SCH_1):PAGE41_I10@PURE_QUANTA.SOCKET4677_AZIF0045P001C01CS(CHIPS)':
 'VSS249': CDS_PINID='VSS249';
NODE_NAME     U2 AM59
 '@S9S_MB_2U_LIB.S9S_MB_2U(SCH_1):PAGE41_I10@PURE_QUANTA.SOCKET4677_AZIF0045P001C01CS(CHIPS)':
 'VSS250': CDS_PINID='VSS250';
NODE_NAME     U2 AM61
 '@S9S_MB_2U_LIB.S9S_MB_2U(SCH_1):PAGE41_I10@PURE_QUANTA.SOCKET4677_AZIF0045P001C01CS(CHIPS)':
 'VSS251': CDS_PINID='VSS251';
NODE_NAME     U2 AM63
 '@S9S_MB_2U_LIB.S9S_MB_2U(SCH_1):PAGE41_I10@PURE_QUANTA.SOCKET4677_AZIF0045P001C01CS(CHIPS)':
 'VSS252': CDS_PINID='VSS252';
NODE_NAME     U2 AM65
 '@S9S_MB_2U_LIB.S9S_MB_2U(SCH_1):PAGE41_I10@PURE_QUANTA.SOCKET4677_AZIF0045P001C01CS(CHIPS)':
 'VSS253': CDS_PINID='VSS253';
NODE_NAME     U2 AM67
 '@S9S_MB_2U_LIB.S9S_MB_2U(SCH_1):PAGE41_I10@PURE_QUANTA.SOCKET4677_AZIF0045P001C01CS(CHIPS)':
 'VSS254': CDS_PINID='VSS254';
NODE_NAME     U2 AM69
 '@S9S_MB_2U_LIB.S9S_MB_2U(SCH_1):PAGE41_I10@PURE_QUANTA.SOCKET4677_AZIF0045P001C01CS(CHIPS)':
 'VSS255': CDS_PINID='VSS255';
NODE_NAME     U2 AM71
 '@S9S_MB_2U_LIB.S9S_MB_2U(SCH_1):PAGE41_I10@PURE_QUANTA.SOCKET4677_AZIF0045P001C01CS(CHIPS)':
 'VSS256': CDS_PINID='VSS256';
NODE_NAME     U2 AM73
 '@S9S_MB_2U_LIB.S9S_MB_2U(SCH_1):PAGE41_I10@PURE_QUANTA.SOCKET4677_AZIF0045P001C01CS(CHIPS)':
 'VSS257': CDS_PINID='VSS257';
NODE_NAME     U2 AM75
 '@S9S_MB_2U_LIB.S9S_MB_2U(SCH_1):PAGE41_I10@PURE_QUANTA.SOCKET4677_AZIF0045P001C01CS(CHIPS)':
 'VSS258': CDS_PINID='VSS258';
NODE_NAME     U2 AM77
 '@S9S_MB_2U_LIB.S9S_MB_2U(SCH_1):PAGE41_I10@PURE_QUANTA.SOCKET4677_AZIF0045P001C01CS(CHIPS)':
 'VSS259': CDS_PINID='VSS259';
NODE_NAME     U2 AM8
 '@S9S_MB_2U_LIB.S9S_MB_2U(SCH_1):PAGE41_I10@PURE_QUANTA.SOCKET4677_AZIF0045P001C01CS(CHIPS)':
 'VSS260': CDS_PINID='VSS260';
NODE_NAME     U2 AN52
 '@S9S_MB_2U_LIB.S9S_MB_2U(SCH_1):PAGE41_I10@PURE_QUANTA.SOCKET4677_AZIF0045P001C01CS(CHIPS)':
 'VSS261': CDS_PINID='VSS261';
NODE_NAME     U2 AN84
 '@S9S_MB_2U_LIB.S9S_MB_2U(SCH_1):PAGE41_I10@PURE_QUANTA.SOCKET4677_AZIF0045P001C01CS(CHIPS)':
 'VSS262': CDS_PINID='VSS262';
NODE_NAME     U2 AN88
 '@S9S_MB_2U_LIB.S9S_MB_2U(SCH_1):PAGE41_I10@PURE_QUANTA.SOCKET4677_AZIF0045P001C01CS(CHIPS)':
 'VSS263': CDS_PINID='VSS263';
NODE_NAME     U2 AP12
 '@S9S_MB_2U_LIB.S9S_MB_2U(SCH_1):PAGE41_I10@PURE_QUANTA.SOCKET4677_AZIF0045P001C01CS(CHIPS)':
 'VSS264': CDS_PINID='VSS264';
NODE_NAME     U2 AP16
 '@S9S_MB_2U_LIB.S9S_MB_2U(SCH_1):PAGE41_I10@PURE_QUANTA.SOCKET4677_AZIF0045P001C01CS(CHIPS)':
 'VSS265': CDS_PINID='VSS265';
NODE_NAME     U2 AP18
 '@S9S_MB_2U_LIB.S9S_MB_2U(SCH_1):PAGE41_I10@PURE_QUANTA.SOCKET4677_AZIF0045P001C01CS(CHIPS)':
 'VSS266': CDS_PINID='VSS266';
NODE_NAME     U2 AP24
 '@S9S_MB_2U_LIB.S9S_MB_2U(SCH_1):PAGE41_I10@PURE_QUANTA.SOCKET4677_AZIF0045P001C01CS(CHIPS)':
 'VSS267': CDS_PINID='VSS267';
NODE_NAME     U2 AP30
 '@S9S_MB_2U_LIB.S9S_MB_2U(SCH_1):PAGE41_I10@PURE_QUANTA.SOCKET4677_AZIF0045P001C01CS(CHIPS)':
 'VSS268': CDS_PINID='VSS268';
NODE_NAME     U2 AP36
 '@S9S_MB_2U_LIB.S9S_MB_2U(SCH_1):PAGE41_I10@PURE_QUANTA.SOCKET4677_AZIF0045P001C01CS(CHIPS)':
 'VSS269': CDS_PINID='VSS269';
NODE_NAME     U2 AP4
 '@S9S_MB_2U_LIB.S9S_MB_2U(SCH_1):PAGE41_I10@PURE_QUANTA.SOCKET4677_AZIF0045P001C01CS(CHIPS)':
 'VSS270': CDS_PINID='VSS270';
NODE_NAME     U2 AP42
 '@S9S_MB_2U_LIB.S9S_MB_2U(SCH_1):PAGE41_I10@PURE_QUANTA.SOCKET4677_AZIF0045P001C01CS(CHIPS)':
 'VSS271': CDS_PINID='VSS271';
NODE_NAME     U2 AP49
 '@S9S_MB_2U_LIB.S9S_MB_2U(SCH_1):PAGE41_I10@PURE_QUANTA.SOCKET4677_AZIF0045P001C01CS(CHIPS)':
 'VSS272': CDS_PINID='VSS272';
NODE_NAME     U2 AP55
 '@S9S_MB_2U_LIB.S9S_MB_2U(SCH_1):PAGE41_I10@PURE_QUANTA.SOCKET4677_AZIF0045P001C01CS(CHIPS)':
 'VSS273': CDS_PINID='VSS273';
NODE_NAME     U2 AP61
 '@S9S_MB_2U_LIB.S9S_MB_2U(SCH_1):PAGE41_I10@PURE_QUANTA.SOCKET4677_AZIF0045P001C01CS(CHIPS)':
 'VSS274': CDS_PINID='VSS274';
NODE_NAME     U2 AP67
 '@S9S_MB_2U_LIB.S9S_MB_2U(SCH_1):PAGE41_I10@PURE_QUANTA.SOCKET4677_AZIF0045P001C01CS(CHIPS)':
 'VSS275': CDS_PINID='VSS275';
NODE_NAME     U2 AP73
 '@S9S_MB_2U_LIB.S9S_MB_2U(SCH_1):PAGE41_I10@PURE_QUANTA.SOCKET4677_AZIF0045P001C01CS(CHIPS)':
 'VSS276': CDS_PINID='VSS276';
NODE_NAME     U2 AP79
 '@S9S_MB_2U_LIB.S9S_MB_2U(SCH_1):PAGE41_I10@PURE_QUANTA.SOCKET4677_AZIF0045P001C01CS(CHIPS)':
 'VSS277': CDS_PINID='VSS277';
NODE_NAME     U2 AP8
 '@S9S_MB_2U_LIB.S9S_MB_2U(SCH_1):PAGE41_I10@PURE_QUANTA.SOCKET4677_AZIF0045P001C01CS(CHIPS)':
 'VSS278': CDS_PINID='VSS278';
NODE_NAME     U2 AP83
 '@S9S_MB_2U_LIB.S9S_MB_2U(SCH_1):PAGE41_I10@PURE_QUANTA.SOCKET4677_AZIF0045P001C01CS(CHIPS)':
 'VSS279': CDS_PINID='VSS279';
NODE_NAME     U2 AP87
 '@S9S_MB_2U_LIB.S9S_MB_2U(SCH_1):PAGE41_I10@PURE_QUANTA.SOCKET4677_AZIF0045P001C01CS(CHIPS)':
 'VSS280': CDS_PINID='VSS280';
NODE_NAME     U2 AP91
 '@S9S_MB_2U_LIB.S9S_MB_2U(SCH_1):PAGE41_I10@PURE_QUANTA.SOCKET4677_AZIF0045P001C01CS(CHIPS)':
 'VSS281': CDS_PINID='VSS281';
NODE_NAME     U2 AR1
 '@S9S_MB_2U_LIB.S9S_MB_2U(SCH_1):PAGE41_I10@PURE_QUANTA.SOCKET4677_AZIF0045P001C01CS(CHIPS)':
 'VSS282': CDS_PINID='VSS282';
NODE_NAME     U2 AR13
 '@S9S_MB_2U_LIB.S9S_MB_2U(SCH_1):PAGE41_I10@PURE_QUANTA.SOCKET4677_AZIF0045P001C01CS(CHIPS)':
 'VSS283': CDS_PINID='VSS283';
NODE_NAME     U2 AR19
 '@S9S_MB_2U_LIB.S9S_MB_2U(SCH_1):PAGE41_I10@PURE_QUANTA.SOCKET4677_AZIF0045P001C01CS(CHIPS)':
 'VSS284': CDS_PINID='VSS284';
NODE_NAME     U2 AR23
 '@S9S_MB_2U_LIB.S9S_MB_2U(SCH_1):PAGE41_I10@PURE_QUANTA.SOCKET4677_AZIF0045P001C01CS(CHIPS)':
 'VSS285': CDS_PINID='VSS285';
NODE_NAME     U2 AR25
 '@S9S_MB_2U_LIB.S9S_MB_2U(SCH_1):PAGE41_I10@PURE_QUANTA.SOCKET4677_AZIF0045P001C01CS(CHIPS)':
 'VSS286': CDS_PINID='VSS286';
NODE_NAME     U2 AR29
 '@S9S_MB_2U_LIB.S9S_MB_2U(SCH_1):PAGE41_I10@PURE_QUANTA.SOCKET4677_AZIF0045P001C01CS(CHIPS)':
 'VSS287': CDS_PINID='VSS287';
NODE_NAME     U2 AR31
 '@S9S_MB_2U_LIB.S9S_MB_2U(SCH_1):PAGE41_I10@PURE_QUANTA.SOCKET4677_AZIF0045P001C01CS(CHIPS)':
 'VSS288': CDS_PINID='VSS288';
NODE_NAME     U2 AR35
 '@S9S_MB_2U_LIB.S9S_MB_2U(SCH_1):PAGE41_I10@PURE_QUANTA.SOCKET4677_AZIF0045P001C01CS(CHIPS)':
 'VSS289': CDS_PINID='VSS289';
NODE_NAME     U2 AR37
 '@S9S_MB_2U_LIB.S9S_MB_2U(SCH_1):PAGE41_I10@PURE_QUANTA.SOCKET4677_AZIF0045P001C01CS(CHIPS)':
 'VSS290': CDS_PINID='VSS290';
NODE_NAME     U2 AR41
 '@S9S_MB_2U_LIB.S9S_MB_2U(SCH_1):PAGE41_I10@PURE_QUANTA.SOCKET4677_AZIF0045P001C01CS(CHIPS)':
 'VSS291': CDS_PINID='VSS291';
NODE_NAME     U2 AR43
 '@S9S_MB_2U_LIB.S9S_MB_2U(SCH_1):PAGE41_I10@PURE_QUANTA.SOCKET4677_AZIF0045P001C01CS(CHIPS)':
 'VSS292': CDS_PINID='VSS292';
NODE_NAME     U2 AR48
 '@S9S_MB_2U_LIB.S9S_MB_2U(SCH_1):PAGE41_I10@PURE_QUANTA.SOCKET4677_AZIF0045P001C01CS(CHIPS)':
 'VSS293': CDS_PINID='VSS293';
NODE_NAME     U2 AR5
 '@S9S_MB_2U_LIB.S9S_MB_2U(SCH_1):PAGE41_I10@PURE_QUANTA.SOCKET4677_AZIF0045P001C01CS(CHIPS)':
 'VSS294': CDS_PINID='VSS294';
NODE_NAME     U2 AR50
 '@S9S_MB_2U_LIB.S9S_MB_2U(SCH_1):PAGE41_I10@PURE_QUANTA.SOCKET4677_AZIF0045P001C01CS(CHIPS)':
 'VSS295': CDS_PINID='VSS295';
NODE_NAME     U2 AR54
 '@S9S_MB_2U_LIB.S9S_MB_2U(SCH_1):PAGE41_I10@PURE_QUANTA.SOCKET4677_AZIF0045P001C01CS(CHIPS)':
 'VSS296': CDS_PINID='VSS296';
NODE_NAME     U2 AR56
 '@S9S_MB_2U_LIB.S9S_MB_2U(SCH_1):PAGE41_I10@PURE_QUANTA.SOCKET4677_AZIF0045P001C01CS(CHIPS)':
 'VSS297': CDS_PINID='VSS297';
NODE_NAME     U2 AR60
 '@S9S_MB_2U_LIB.S9S_MB_2U(SCH_1):PAGE41_I10@PURE_QUANTA.SOCKET4677_AZIF0045P001C01CS(CHIPS)':
 'VSS298': CDS_PINID='VSS298';
NODE_NAME     U2 AR62
 '@S9S_MB_2U_LIB.S9S_MB_2U(SCH_1):PAGE41_I10@PURE_QUANTA.SOCKET4677_AZIF0045P001C01CS(CHIPS)':
 'VSS299': CDS_PINID='VSS299';
NODE_NAME     U2 AR66
 '@S9S_MB_2U_LIB.S9S_MB_2U(SCH_1):PAGE41_I10@PURE_QUANTA.SOCKET4677_AZIF0045P001C01CS(CHIPS)':
 'VSS300': CDS_PINID='VSS300';
NODE_NAME     U2 AR68
 '@S9S_MB_2U_LIB.S9S_MB_2U(SCH_1):PAGE41_I10@PURE_QUANTA.SOCKET4677_AZIF0045P001C01CS(CHIPS)':
 'VSS301': CDS_PINID='VSS301';
NODE_NAME     U2 AR72
 '@S9S_MB_2U_LIB.S9S_MB_2U(SCH_1):PAGE41_I10@PURE_QUANTA.SOCKET4677_AZIF0045P001C01CS(CHIPS)':
 'VSS302': CDS_PINID='VSS302';
NODE_NAME     U2 AR74
 '@S9S_MB_2U_LIB.S9S_MB_2U(SCH_1):PAGE41_I10@PURE_QUANTA.SOCKET4677_AZIF0045P001C01CS(CHIPS)':
 'VSS303': CDS_PINID='VSS303';
NODE_NAME     U2 AR78
 '@S9S_MB_2U_LIB.S9S_MB_2U(SCH_1):PAGE41_I10@PURE_QUANTA.SOCKET4677_AZIF0045P001C01CS(CHIPS)':
 'VSS304': CDS_PINID='VSS304';
NODE_NAME     U2 AR82
 '@S9S_MB_2U_LIB.S9S_MB_2U(SCH_1):PAGE41_I10@PURE_QUANTA.SOCKET4677_AZIF0045P001C01CS(CHIPS)':
 'VSS305': CDS_PINID='VSS305';
NODE_NAME     U2 AR84
 '@S9S_MB_2U_LIB.S9S_MB_2U(SCH_1):PAGE41_I10@PURE_QUANTA.SOCKET4677_AZIF0045P001C01CS(CHIPS)':
 'VSS306': CDS_PINID='VSS306';
NODE_NAME     U2 AR88
 '@S9S_MB_2U_LIB.S9S_MB_2U(SCH_1):PAGE41_I10@PURE_QUANTA.SOCKET4677_AZIF0045P001C01CS(CHIPS)':
 'VSS307': CDS_PINID='VSS307';
NODE_NAME     U2 AR9
 '@S9S_MB_2U_LIB.S9S_MB_2U(SCH_1):PAGE41_I10@PURE_QUANTA.SOCKET4677_AZIF0045P001C01CS(CHIPS)':
 'VSS308': CDS_PINID='VSS308';
NODE_NAME     U2 AT12
 '@S9S_MB_2U_LIB.S9S_MB_2U(SCH_1):PAGE41_I10@PURE_QUANTA.SOCKET4677_AZIF0045P001C01CS(CHIPS)':
 'VSS309': CDS_PINID='VSS309';
NODE_NAME     U2 AT16
 '@S9S_MB_2U_LIB.S9S_MB_2U(SCH_1):PAGE41_I10@PURE_QUANTA.SOCKET4677_AZIF0045P001C01CS(CHIPS)':
 'VSS310': CDS_PINID='VSS310';
NODE_NAME     U2 AT20
 '@S9S_MB_2U_LIB.S9S_MB_2U(SCH_1):PAGE41_I10@PURE_QUANTA.SOCKET4677_AZIF0045P001C01CS(CHIPS)':
 'VSS311': CDS_PINID='VSS311';
NODE_NAME     U2 AT22
 '@S9S_MB_2U_LIB.S9S_MB_2U(SCH_1):PAGE41_I10@PURE_QUANTA.SOCKET4677_AZIF0045P001C01CS(CHIPS)':
 'VSS312': CDS_PINID='VSS312';
NODE_NAME     U2 AT26
 '@S9S_MB_2U_LIB.S9S_MB_2U(SCH_1):PAGE41_I10@PURE_QUANTA.SOCKET4677_AZIF0045P001C01CS(CHIPS)':
 'VSS313': CDS_PINID='VSS313';
NODE_NAME     U2 AT28
 '@S9S_MB_2U_LIB.S9S_MB_2U(SCH_1):PAGE41_I10@PURE_QUANTA.SOCKET4677_AZIF0045P001C01CS(CHIPS)':
 'VSS314': CDS_PINID='VSS314';
NODE_NAME     U2 AT32
 '@S9S_MB_2U_LIB.S9S_MB_2U(SCH_1):PAGE41_I10@PURE_QUANTA.SOCKET4677_AZIF0045P001C01CS(CHIPS)':
 'VSS315': CDS_PINID='VSS315';
NODE_NAME     U2 AT34
 '@S9S_MB_2U_LIB.S9S_MB_2U(SCH_1):PAGE41_I10@PURE_QUANTA.SOCKET4677_AZIF0045P001C01CS(CHIPS)':
 'VSS316': CDS_PINID='VSS316';
NODE_NAME     U2 AT38
 '@S9S_MB_2U_LIB.S9S_MB_2U(SCH_1):PAGE41_I10@PURE_QUANTA.SOCKET4677_AZIF0045P001C01CS(CHIPS)':
 'VSS317': CDS_PINID='VSS317';
NODE_NAME     U2 AT4
 '@S9S_MB_2U_LIB.S9S_MB_2U(SCH_1):PAGE41_I10@PURE_QUANTA.SOCKET4677_AZIF0045P001C01CS(CHIPS)':
 'VSS318': CDS_PINID='VSS318';
NODE_NAME     U2 AT40
 '@S9S_MB_2U_LIB.S9S_MB_2U(SCH_1):PAGE41_I10@PURE_QUANTA.SOCKET4677_AZIF0045P001C01CS(CHIPS)':
 'VSS319': CDS_PINID='VSS319';
NODE_NAME     U2 AT44
 '@S9S_MB_2U_LIB.S9S_MB_2U(SCH_1):PAGE41_I10@PURE_QUANTA.SOCKET4677_AZIF0045P001C01CS(CHIPS)':
 'VSS320': CDS_PINID='VSS320';
NODE_NAME     U2 AT51
 '@S9S_MB_2U_LIB.S9S_MB_2U(SCH_1):PAGE41_I10@PURE_QUANTA.SOCKET4677_AZIF0045P001C01CS(CHIPS)':
 'VSS321': CDS_PINID='VSS321';
NODE_NAME     U2 AT53
 '@S9S_MB_2U_LIB.S9S_MB_2U(SCH_1):PAGE41_I10@PURE_QUANTA.SOCKET4677_AZIF0045P001C01CS(CHIPS)':
 'VSS322': CDS_PINID='VSS322';
NODE_NAME     U2 AT57
 '@S9S_MB_2U_LIB.S9S_MB_2U(SCH_1):PAGE41_I10@PURE_QUANTA.SOCKET4677_AZIF0045P001C01CS(CHIPS)':
 'VSS323': CDS_PINID='VSS323';
NODE_NAME     U2 AT59
 '@S9S_MB_2U_LIB.S9S_MB_2U(SCH_1):PAGE41_I10@PURE_QUANTA.SOCKET4677_AZIF0045P001C01CS(CHIPS)':
 'VSS324': CDS_PINID='VSS324';
NODE_NAME     U2 AT63
 '@S9S_MB_2U_LIB.S9S_MB_2U(SCH_1):PAGE41_I10@PURE_QUANTA.SOCKET4677_AZIF0045P001C01CS(CHIPS)':
 'VSS325': CDS_PINID='VSS325';
NODE_NAME     U2 AT65
 '@S9S_MB_2U_LIB.S9S_MB_2U(SCH_1):PAGE41_I10@PURE_QUANTA.SOCKET4677_AZIF0045P001C01CS(CHIPS)':
 'VSS326': CDS_PINID='VSS326';
NODE_NAME     U2 AT69
 '@S9S_MB_2U_LIB.S9S_MB_2U(SCH_1):PAGE41_I10@PURE_QUANTA.SOCKET4677_AZIF0045P001C01CS(CHIPS)':
 'VSS327': CDS_PINID='VSS327';
NODE_NAME     U2 AT71
 '@S9S_MB_2U_LIB.S9S_MB_2U(SCH_1):PAGE41_I10@PURE_QUANTA.SOCKET4677_AZIF0045P001C01CS(CHIPS)':
 'VSS328': CDS_PINID='VSS328';
NODE_NAME     U2 AT75
 '@S9S_MB_2U_LIB.S9S_MB_2U(SCH_1):PAGE41_I10@PURE_QUANTA.SOCKET4677_AZIF0045P001C01CS(CHIPS)':
 'VSS329': CDS_PINID='VSS329';
NODE_NAME     U2 AT77
 '@S9S_MB_2U_LIB.S9S_MB_2U(SCH_1):PAGE41_I10@PURE_QUANTA.SOCKET4677_AZIF0045P001C01CS(CHIPS)':
 'VSS330': CDS_PINID='VSS330';
NODE_NAME     U2 AT79
 '@S9S_MB_2U_LIB.S9S_MB_2U(SCH_1):PAGE41_I10@PURE_QUANTA.SOCKET4677_AZIF0045P001C01CS(CHIPS)':
 'VSS331': CDS_PINID='VSS331';
NODE_NAME     U2 AT8
 '@S9S_MB_2U_LIB.S9S_MB_2U(SCH_1):PAGE41_I10@PURE_QUANTA.SOCKET4677_AZIF0045P001C01CS(CHIPS)':
 'VSS332': CDS_PINID='VSS332';
NODE_NAME     U2 AU27
 '@S9S_MB_2U_LIB.S9S_MB_2U(SCH_1):PAGE41_I10@PURE_QUANTA.SOCKET4677_AZIF0045P001C01CS(CHIPS)':
 'VSS333': CDS_PINID='VSS333';
NODE_NAME     U2 AU31
 '@S9S_MB_2U_LIB.S9S_MB_2U(SCH_1):PAGE41_I10@PURE_QUANTA.SOCKET4677_AZIF0045P001C01CS(CHIPS)':
 'VSS334': CDS_PINID='VSS334';
NODE_NAME     U2 AU37
 '@S9S_MB_2U_LIB.S9S_MB_2U(SCH_1):PAGE41_I10@PURE_QUANTA.SOCKET4677_AZIF0045P001C01CS(CHIPS)':
 'VSS335': CDS_PINID='VSS335';
NODE_NAME     U2 AU39
 '@S9S_MB_2U_LIB.S9S_MB_2U(SCH_1):PAGE41_I10@PURE_QUANTA.SOCKET4677_AZIF0045P001C01CS(CHIPS)':
 'VSS336': CDS_PINID='VSS336';
NODE_NAME     U2 AU41
 '@S9S_MB_2U_LIB.S9S_MB_2U(SCH_1):PAGE41_I10@PURE_QUANTA.SOCKET4677_AZIF0045P001C01CS(CHIPS)':
 'VSS337': CDS_PINID='VSS337';
NODE_NAME     U2 AU45
 '@S9S_MB_2U_LIB.S9S_MB_2U(SCH_1):PAGE41_I10@PURE_QUANTA.SOCKET4677_AZIF0045P001C01CS(CHIPS)':
 'VSS338': CDS_PINID='VSS338';
NODE_NAME     U2 AU48
 '@S9S_MB_2U_LIB.S9S_MB_2U(SCH_1):PAGE41_I10@PURE_QUANTA.SOCKET4677_AZIF0045P001C01CS(CHIPS)':
 'VSS339': CDS_PINID='VSS339';
NODE_NAME     U2 AU70
 '@S9S_MB_2U_LIB.S9S_MB_2U(SCH_1):PAGE41_I10@PURE_QUANTA.SOCKET4677_AZIF0045P001C01CS(CHIPS)':
 'VSS340': CDS_PINID='VSS340';
NODE_NAME     U2 AU72
 '@S9S_MB_2U_LIB.S9S_MB_2U(SCH_1):PAGE41_I10@PURE_QUANTA.SOCKET4677_AZIF0045P001C01CS(CHIPS)':
 'VSS341': CDS_PINID='VSS341';
NODE_NAME     U2 AU74
 '@S9S_MB_2U_LIB.S9S_MB_2U(SCH_1):PAGE41_I10@PURE_QUANTA.SOCKET4677_AZIF0045P001C01CS(CHIPS)':
 'VSS342': CDS_PINID='VSS342';
NODE_NAME     U2 AU76
 '@S9S_MB_2U_LIB.S9S_MB_2U(SCH_1):PAGE41_I10@PURE_QUANTA.SOCKET4677_AZIF0045P001C01CS(CHIPS)':
 'VSS343': CDS_PINID='VSS343';
NODE_NAME     U2 AU80
 '@S9S_MB_2U_LIB.S9S_MB_2U(SCH_1):PAGE41_I10@PURE_QUANTA.SOCKET4677_AZIF0045P001C01CS(CHIPS)':
 'VSS344': CDS_PINID='VSS344';
NODE_NAME     U2 AU84
 '@S9S_MB_2U_LIB.S9S_MB_2U(SCH_1):PAGE41_I10@PURE_QUANTA.SOCKET4677_AZIF0045P001C01CS(CHIPS)':
 'VSS345': CDS_PINID='VSS345';
NODE_NAME     U2 AU88
 '@S9S_MB_2U_LIB.S9S_MB_2U(SCH_1):PAGE41_I10@PURE_QUANTA.SOCKET4677_AZIF0045P001C01CS(CHIPS)':
 'VSS346': CDS_PINID='VSS346';
NODE_NAME     U2 AV12
 '@S9S_MB_2U_LIB.S9S_MB_2U(SCH_1):PAGE41_I10@PURE_QUANTA.SOCKET4677_AZIF0045P001C01CS(CHIPS)':
 'VSS347': CDS_PINID='VSS347';
NODE_NAME     U2 AV16
 '@S9S_MB_2U_LIB.S9S_MB_2U(SCH_1):PAGE41_I10@PURE_QUANTA.SOCKET4677_AZIF0045P001C01CS(CHIPS)':
 'VSS348': CDS_PINID='VSS348';
NODE_NAME     U2 AV4
 '@S9S_MB_2U_LIB.S9S_MB_2U(SCH_1):PAGE41_I10@PURE_QUANTA.SOCKET4677_AZIF0045P001C01CS(CHIPS)':
 'VSS349': CDS_PINID='VSS349';
NODE_NAME     U2 AV77
 '@S9S_MB_2U_LIB.S9S_MB_2U(SCH_1):PAGE41_I10@PURE_QUANTA.SOCKET4677_AZIF0045P001C01CS(CHIPS)':
 'VSS350': CDS_PINID='VSS350';
NODE_NAME     U2 AV8
 '@S9S_MB_2U_LIB.S9S_MB_2U(SCH_1):PAGE41_I10@PURE_QUANTA.SOCKET4677_AZIF0045P001C01CS(CHIPS)':
 'VSS351': CDS_PINID='VSS351';
NODE_NAME     U2 AV87
 '@S9S_MB_2U_LIB.S9S_MB_2U(SCH_1):PAGE41_I10@PURE_QUANTA.SOCKET4677_AZIF0045P001C01CS(CHIPS)':
 'VSS352': CDS_PINID='VSS352';
NODE_NAME     U2 AV91
 '@S9S_MB_2U_LIB.S9S_MB_2U(SCH_1):PAGE41_I10@PURE_QUANTA.SOCKET4677_AZIF0045P001C01CS(CHIPS)':
 'VSS353': CDS_PINID='VSS353';
NODE_NAME     U2 AW1
 '@S9S_MB_2U_LIB.S9S_MB_2U(SCH_1):PAGE41_I10@PURE_QUANTA.SOCKET4677_AZIF0045P001C01CS(CHIPS)':
 'VSS354': CDS_PINID='VSS354';
NODE_NAME     U2 AW13
 '@S9S_MB_2U_LIB.S9S_MB_2U(SCH_1):PAGE41_I10@PURE_QUANTA.SOCKET4677_AZIF0045P001C01CS(CHIPS)':
 'VSS355': CDS_PINID='VSS355';
NODE_NAME     U2 AW5
 '@S9S_MB_2U_LIB.S9S_MB_2U(SCH_1):PAGE41_I10@PURE_QUANTA.SOCKET4677_AZIF0045P001C01CS(CHIPS)':
 'VSS359': CDS_PINID='VSS359';
NODE_NAME     U2 AW9
 '@S9S_MB_2U_LIB.S9S_MB_2U(SCH_1):PAGE41_I10@PURE_QUANTA.SOCKET4677_AZIF0045P001C01CS(CHIPS)':
 'VSS368': CDS_PINID='VSS368';
NODE_NAME     U2 AA82
 '@S9S_MB_2U_LIB.S9S_MB_2U(SCH_1):PAGE41_I11@PURE_QUANTA.SOCKET4677_AZIF0045P001C01CS(CHIPS)':
 'VSS38': CDS_PINID='VSS38';
NODE_NAME     U2 AA84
 '@S9S_MB_2U_LIB.S9S_MB_2U(SCH_1):PAGE41_I11@PURE_QUANTA.SOCKET4677_AZIF0045P001C01CS(CHIPS)':
 'VSS39': CDS_PINID='VSS39';
NODE_NAME     U2 AA88
 '@S9S_MB_2U_LIB.S9S_MB_2U(SCH_1):PAGE41_I11@PURE_QUANTA.SOCKET4677_AZIF0045P001C01CS(CHIPS)':
 'VSS40': CDS_PINID='VSS40';
NODE_NAME     U2 AB12
 '@S9S_MB_2U_LIB.S9S_MB_2U(SCH_1):PAGE41_I11@PURE_QUANTA.SOCKET4677_AZIF0045P001C01CS(CHIPS)':
 'VSS41': CDS_PINID='VSS41';
NODE_NAME     U2 AB16
 '@S9S_MB_2U_LIB.S9S_MB_2U(SCH_1):PAGE41_I11@PURE_QUANTA.SOCKET4677_AZIF0045P001C01CS(CHIPS)':
 'VSS42': CDS_PINID='VSS42';
NODE_NAME     U2 AB20
 '@S9S_MB_2U_LIB.S9S_MB_2U(SCH_1):PAGE41_I11@PURE_QUANTA.SOCKET4677_AZIF0045P001C01CS(CHIPS)':
 'VSS43': CDS_PINID='VSS43';
NODE_NAME     U2 AB22
 '@S9S_MB_2U_LIB.S9S_MB_2U(SCH_1):PAGE41_I11@PURE_QUANTA.SOCKET4677_AZIF0045P001C01CS(CHIPS)':
 'VSS44': CDS_PINID='VSS44';
NODE_NAME     U2 AB26
 '@S9S_MB_2U_LIB.S9S_MB_2U(SCH_1):PAGE41_I11@PURE_QUANTA.SOCKET4677_AZIF0045P001C01CS(CHIPS)':
 'VSS45': CDS_PINID='VSS45';
NODE_NAME     U2 AB28
 '@S9S_MB_2U_LIB.S9S_MB_2U(SCH_1):PAGE41_I11@PURE_QUANTA.SOCKET4677_AZIF0045P001C01CS(CHIPS)':
 'VSS46': CDS_PINID='VSS46';
NODE_NAME     U2 AB32
 '@S9S_MB_2U_LIB.S9S_MB_2U(SCH_1):PAGE41_I11@PURE_QUANTA.SOCKET4677_AZIF0045P001C01CS(CHIPS)':
 'VSS47': CDS_PINID='VSS47';
NODE_NAME     U2 AB34
 '@S9S_MB_2U_LIB.S9S_MB_2U(SCH_1):PAGE41_I11@PURE_QUANTA.SOCKET4677_AZIF0045P001C01CS(CHIPS)':
 'VSS48': CDS_PINID='VSS48';
NODE_NAME     U2 AB38
 '@S9S_MB_2U_LIB.S9S_MB_2U(SCH_1):PAGE41_I11@PURE_QUANTA.SOCKET4677_AZIF0045P001C01CS(CHIPS)':
 'VSS49': CDS_PINID='VSS49';
NODE_NAME     U2 AB4
 '@S9S_MB_2U_LIB.S9S_MB_2U(SCH_1):PAGE41_I11@PURE_QUANTA.SOCKET4677_AZIF0045P001C01CS(CHIPS)':
 'VSS50': CDS_PINID='VSS50';
NODE_NAME     U2 AB40
 '@S9S_MB_2U_LIB.S9S_MB_2U(SCH_1):PAGE41_I11@PURE_QUANTA.SOCKET4677_AZIF0045P001C01CS(CHIPS)':
 'VSS51': CDS_PINID='VSS51';
NODE_NAME     U2 AB44
 '@S9S_MB_2U_LIB.S9S_MB_2U(SCH_1):PAGE41_I11@PURE_QUANTA.SOCKET4677_AZIF0045P001C01CS(CHIPS)':
 'VSS52': CDS_PINID='VSS52';
NODE_NAME     U2 AB47
 '@S9S_MB_2U_LIB.S9S_MB_2U(SCH_1):PAGE41_I11@PURE_QUANTA.SOCKET4677_AZIF0045P001C01CS(CHIPS)':
 'VSS53': CDS_PINID='VSS53';
NODE_NAME     U2 AB51
 '@S9S_MB_2U_LIB.S9S_MB_2U(SCH_1):PAGE41_I11@PURE_QUANTA.SOCKET4677_AZIF0045P001C01CS(CHIPS)':
 'VSS54': CDS_PINID='VSS54';
NODE_NAME     U2 AB53
 '@S9S_MB_2U_LIB.S9S_MB_2U(SCH_1):PAGE41_I11@PURE_QUANTA.SOCKET4677_AZIF0045P001C01CS(CHIPS)':
 'VSS55': CDS_PINID='VSS55';
NODE_NAME     U2 AB57
 '@S9S_MB_2U_LIB.S9S_MB_2U(SCH_1):PAGE41_I11@PURE_QUANTA.SOCKET4677_AZIF0045P001C01CS(CHIPS)':
 'VSS56': CDS_PINID='VSS56';
NODE_NAME     U2 AB59
 '@S9S_MB_2U_LIB.S9S_MB_2U(SCH_1):PAGE41_I11@PURE_QUANTA.SOCKET4677_AZIF0045P001C01CS(CHIPS)':
 'VSS57': CDS_PINID='VSS57';
NODE_NAME     U2 AB63
 '@S9S_MB_2U_LIB.S9S_MB_2U(SCH_1):PAGE41_I11@PURE_QUANTA.SOCKET4677_AZIF0045P001C01CS(CHIPS)':
 'VSS58': CDS_PINID='VSS58';
NODE_NAME     U2 AB65
 '@S9S_MB_2U_LIB.S9S_MB_2U(SCH_1):PAGE41_I11@PURE_QUANTA.SOCKET4677_AZIF0045P001C01CS(CHIPS)':
 'VSS59': CDS_PINID='VSS59';
NODE_NAME     U2 AB69
 '@S9S_MB_2U_LIB.S9S_MB_2U(SCH_1):PAGE41_I11@PURE_QUANTA.SOCKET4677_AZIF0045P001C01CS(CHIPS)':
 'VSS60': CDS_PINID='VSS60';
NODE_NAME     U2 AB71
 '@S9S_MB_2U_LIB.S9S_MB_2U(SCH_1):PAGE41_I11@PURE_QUANTA.SOCKET4677_AZIF0045P001C01CS(CHIPS)':
 'VSS61': CDS_PINID='VSS61';
NODE_NAME     U2 AB75
 '@S9S_MB_2U_LIB.S9S_MB_2U(SCH_1):PAGE41_I11@PURE_QUANTA.SOCKET4677_AZIF0045P001C01CS(CHIPS)':
 'VSS62': CDS_PINID='VSS62';
NODE_NAME     U2 AB77
 '@S9S_MB_2U_LIB.S9S_MB_2U(SCH_1):PAGE41_I11@PURE_QUANTA.SOCKET4677_AZIF0045P001C01CS(CHIPS)':
 'VSS63': CDS_PINID='VSS63';
NODE_NAME     U2 AB79
 '@S9S_MB_2U_LIB.S9S_MB_2U(SCH_1):PAGE41_I11@PURE_QUANTA.SOCKET4677_AZIF0045P001C01CS(CHIPS)':
 'VSS64': CDS_PINID='VSS64';
NODE_NAME     U2 AB8
 '@S9S_MB_2U_LIB.S9S_MB_2U(SCH_1):PAGE41_I11@PURE_QUANTA.SOCKET4677_AZIF0045P001C01CS(CHIPS)':
 'VSS65': CDS_PINID='VSS65';
NODE_NAME     U2 AB81
 '@S9S_MB_2U_LIB.S9S_MB_2U(SCH_1):PAGE41_I11@PURE_QUANTA.SOCKET4677_AZIF0045P001C01CS(CHIPS)':
 'VSS66': CDS_PINID='VSS66';
NODE_NAME     U2 AB83
 '@S9S_MB_2U_LIB.S9S_MB_2U(SCH_1):PAGE41_I11@PURE_QUANTA.SOCKET4677_AZIF0045P001C01CS(CHIPS)':
 'VSS67': CDS_PINID='VSS67';
NODE_NAME     U2 AB87
 '@S9S_MB_2U_LIB.S9S_MB_2U(SCH_1):PAGE41_I11@PURE_QUANTA.SOCKET4677_AZIF0045P001C01CS(CHIPS)':
 'VSS68': CDS_PINID='VSS68';
NODE_NAME     U2 AB91
 '@S9S_MB_2U_LIB.S9S_MB_2U(SCH_1):PAGE41_I11@PURE_QUANTA.SOCKET4677_AZIF0045P001C01CS(CHIPS)':
 'VSS69': CDS_PINID='VSS69';
NODE_NAME     U2 AC1
 '@S9S_MB_2U_LIB.S9S_MB_2U(SCH_1):PAGE41_I11@PURE_QUANTA.SOCKET4677_AZIF0045P001C01CS(CHIPS)':
 'VSS70': CDS_PINID='VSS70';
NODE_NAME     U2 AC13
 '@S9S_MB_2U_LIB.S9S_MB_2U(SCH_1):PAGE41_I11@PURE_QUANTA.SOCKET4677_AZIF0045P001C01CS(CHIPS)':
 'VSS71': CDS_PINID='VSS71';
NODE_NAME     U2 AC21
 '@S9S_MB_2U_LIB.S9S_MB_2U(SCH_1):PAGE41_I11@PURE_QUANTA.SOCKET4677_AZIF0045P001C01CS(CHIPS)':
 'VSS72': CDS_PINID='VSS72';
NODE_NAME     U2 AC27
 '@S9S_MB_2U_LIB.S9S_MB_2U(SCH_1):PAGE41_I11@PURE_QUANTA.SOCKET4677_AZIF0045P001C01CS(CHIPS)':
 'VSS73': CDS_PINID='VSS73';
NODE_NAME     U2 AC33
 '@S9S_MB_2U_LIB.S9S_MB_2U(SCH_1):PAGE41_I11@PURE_QUANTA.SOCKET4677_AZIF0045P001C01CS(CHIPS)':
 'VSS74': CDS_PINID='VSS74';
NODE_NAME     U2 AC39
 '@S9S_MB_2U_LIB.S9S_MB_2U(SCH_1):PAGE41_I11@PURE_QUANTA.SOCKET4677_AZIF0045P001C01CS(CHIPS)':
 'VSS75': CDS_PINID='VSS75';
NODE_NAME     U2 AC45
 '@S9S_MB_2U_LIB.S9S_MB_2U(SCH_1):PAGE41_I11@PURE_QUANTA.SOCKET4677_AZIF0045P001C01CS(CHIPS)':
 'VSS76': CDS_PINID='VSS76';
NODE_NAME     U2 AC5
 '@S9S_MB_2U_LIB.S9S_MB_2U(SCH_1):PAGE41_I11@PURE_QUANTA.SOCKET4677_AZIF0045P001C01CS(CHIPS)':
 'VSS77': CDS_PINID='VSS77';
NODE_NAME     U2 AC52
 '@S9S_MB_2U_LIB.S9S_MB_2U(SCH_1):PAGE41_I11@PURE_QUANTA.SOCKET4677_AZIF0045P001C01CS(CHIPS)':
 'VSS78': CDS_PINID='VSS78';
NODE_NAME     U2 AC58
 '@S9S_MB_2U_LIB.S9S_MB_2U(SCH_1):PAGE41_I11@PURE_QUANTA.SOCKET4677_AZIF0045P001C01CS(CHIPS)':
 'VSS79': CDS_PINID='VSS79';
NODE_NAME     U2 AC64
 '@S9S_MB_2U_LIB.S9S_MB_2U(SCH_1):PAGE41_I11@PURE_QUANTA.SOCKET4677_AZIF0045P001C01CS(CHIPS)':
 'VSS80': CDS_PINID='VSS80';
NODE_NAME     U2 AC70
 '@S9S_MB_2U_LIB.S9S_MB_2U(SCH_1):PAGE41_I11@PURE_QUANTA.SOCKET4677_AZIF0045P001C01CS(CHIPS)':
 'VSS81': CDS_PINID='VSS81';
NODE_NAME     U2 AC76
 '@S9S_MB_2U_LIB.S9S_MB_2U(SCH_1):PAGE41_I11@PURE_QUANTA.SOCKET4677_AZIF0045P001C01CS(CHIPS)':
 'VSS82': CDS_PINID='VSS82';
NODE_NAME     U2 AC84
 '@S9S_MB_2U_LIB.S9S_MB_2U(SCH_1):PAGE41_I11@PURE_QUANTA.SOCKET4677_AZIF0045P001C01CS(CHIPS)':
 'VSS83': CDS_PINID='VSS83';
NODE_NAME     U2 AC88
 '@S9S_MB_2U_LIB.S9S_MB_2U(SCH_1):PAGE41_I11@PURE_QUANTA.SOCKET4677_AZIF0045P001C01CS(CHIPS)':
 'VSS84': CDS_PINID='VSS84';
NODE_NAME     U2 AC9
 '@S9S_MB_2U_LIB.S9S_MB_2U(SCH_1):PAGE41_I11@PURE_QUANTA.SOCKET4677_AZIF0045P001C01CS(CHIPS)':
 'VSS85': CDS_PINID='VSS85';
NODE_NAME     U2 AD12
 '@S9S_MB_2U_LIB.S9S_MB_2U(SCH_1):PAGE41_I11@PURE_QUANTA.SOCKET4677_AZIF0045P001C01CS(CHIPS)':
 'VSS86': CDS_PINID='VSS86';
NODE_NAME     U2 AD16
 '@S9S_MB_2U_LIB.S9S_MB_2U(SCH_1):PAGE41_I11@PURE_QUANTA.SOCKET4677_AZIF0045P001C01CS(CHIPS)':
 'VSS87': CDS_PINID='VSS87';
NODE_NAME     U2 AD4
 '@S9S_MB_2U_LIB.S9S_MB_2U(SCH_1):PAGE41_I11@PURE_QUANTA.SOCKET4677_AZIF0045P001C01CS(CHIPS)':
 'VSS88': CDS_PINID='VSS88';
NODE_NAME     U2 AD42
 '@S9S_MB_2U_LIB.S9S_MB_2U(SCH_1):PAGE41_I11@PURE_QUANTA.SOCKET4677_AZIF0045P001C01CS(CHIPS)':
 'VSS89': CDS_PINID='VSS89';
NODE_NAME     U2 AD79
 '@S9S_MB_2U_LIB.S9S_MB_2U(SCH_1):PAGE41_I11@PURE_QUANTA.SOCKET4677_AZIF0045P001C01CS(CHIPS)':
 'VSS90': CDS_PINID='VSS90';
NODE_NAME     U2 AD8
 '@S9S_MB_2U_LIB.S9S_MB_2U(SCH_1):PAGE41_I11@PURE_QUANTA.SOCKET4677_AZIF0045P001C01CS(CHIPS)':
 'VSS91': CDS_PINID='VSS91';
NODE_NAME     U2 AD83
 '@S9S_MB_2U_LIB.S9S_MB_2U(SCH_1):PAGE41_I11@PURE_QUANTA.SOCKET4677_AZIF0045P001C01CS(CHIPS)':
 'VSS92': CDS_PINID='VSS92';
NODE_NAME     U2 AE17
 '@S9S_MB_2U_LIB.S9S_MB_2U(SCH_1):PAGE41_I11@PURE_QUANTA.SOCKET4677_AZIF0045P001C01CS(CHIPS)':
 'VSS93': CDS_PINID='VSS93';
NODE_NAME     U2 AE19
 '@S9S_MB_2U_LIB.S9S_MB_2U(SCH_1):PAGE41_I11@PURE_QUANTA.SOCKET4677_AZIF0045P001C01CS(CHIPS)':
 'VSS94': CDS_PINID='VSS94';
NODE_NAME     U2 AE21
 '@S9S_MB_2U_LIB.S9S_MB_2U(SCH_1):PAGE41_I11@PURE_QUANTA.SOCKET4677_AZIF0045P001C01CS(CHIPS)':
 'VSS95': CDS_PINID='VSS95';
NODE_NAME     U2 AE23
 '@S9S_MB_2U_LIB.S9S_MB_2U(SCH_1):PAGE41_I11@PURE_QUANTA.SOCKET4677_AZIF0045P001C01CS(CHIPS)':
 'VSS96': CDS_PINID='VSS96';
NODE_NAME     U2 AE25
 '@S9S_MB_2U_LIB.S9S_MB_2U(SCH_1):PAGE41_I11@PURE_QUANTA.SOCKET4677_AZIF0045P001C01CS(CHIPS)':
 'VSS97': CDS_PINID='VSS97';
NODE_NAME     U2 AE27
 '@S9S_MB_2U_LIB.S9S_MB_2U(SCH_1):PAGE41_I11@PURE_QUANTA.SOCKET4677_AZIF0045P001C01CS(CHIPS)':
 'VSS98': CDS_PINID='VSS98';
NODE_NAME     U2 AE29
 '@S9S_MB_2U_LIB.S9S_MB_2U(SCH_1):PAGE41_I11@PURE_QUANTA.SOCKET4677_AZIF0045P001C01CS(CHIPS)':
 'VSS99': CDS_PINID='VSS99';
NODE_NAME     U2 AE31
 '@S9S_MB_2U_LIB.S9S_MB_2U(SCH_1):PAGE41_I11@PURE_QUANTA.SOCKET4677_AZIF0045P001C01CS(CHIPS)':
 'VSS100': CDS_PINID='VSS100';
NODE_NAME     U2 AE33
 '@S9S_MB_2U_LIB.S9S_MB_2U(SCH_1):PAGE41_I11@PURE_QUANTA.SOCKET4677_AZIF0045P001C01CS(CHIPS)':
 'VSS101': CDS_PINID='VSS101';
NODE_NAME     U2 AE35
 '@S9S_MB_2U_LIB.S9S_MB_2U(SCH_1):PAGE41_I11@PURE_QUANTA.SOCKET4677_AZIF0045P001C01CS(CHIPS)':
 'VSS102': CDS_PINID='VSS102';
NODE_NAME     U2 AE37
 '@S9S_MB_2U_LIB.S9S_MB_2U(SCH_1):PAGE41_I11@PURE_QUANTA.SOCKET4677_AZIF0045P001C01CS(CHIPS)':
 'VSS103': CDS_PINID='VSS103';
NODE_NAME     U2 AE39
 '@S9S_MB_2U_LIB.S9S_MB_2U(SCH_1):PAGE41_I11@PURE_QUANTA.SOCKET4677_AZIF0045P001C01CS(CHIPS)':
 'VSS104': CDS_PINID='VSS104';
NODE_NAME     U2 AE41
 '@S9S_MB_2U_LIB.S9S_MB_2U(SCH_1):PAGE41_I11@PURE_QUANTA.SOCKET4677_AZIF0045P001C01CS(CHIPS)':
 'VSS105': CDS_PINID='VSS105';
NODE_NAME     U2 AE43
 '@S9S_MB_2U_LIB.S9S_MB_2U(SCH_1):PAGE41_I11@PURE_QUANTA.SOCKET4677_AZIF0045P001C01CS(CHIPS)':
 'VSS106': CDS_PINID='VSS106';
NODE_NAME     U2 AE45
 '@S9S_MB_2U_LIB.S9S_MB_2U(SCH_1):PAGE41_I11@PURE_QUANTA.SOCKET4677_AZIF0045P001C01CS(CHIPS)':
 'VSS107': CDS_PINID='VSS107';
NODE_NAME     U2 AE48
 '@S9S_MB_2U_LIB.S9S_MB_2U(SCH_1):PAGE41_I11@PURE_QUANTA.SOCKET4677_AZIF0045P001C01CS(CHIPS)':
 'VSS108': CDS_PINID='VSS108';
NODE_NAME     U2 AE50
 '@S9S_MB_2U_LIB.S9S_MB_2U(SCH_1):PAGE41_I11@PURE_QUANTA.SOCKET4677_AZIF0045P001C01CS(CHIPS)':
 'VSS109': CDS_PINID='VSS109';
NODE_NAME     U2 AE52
 '@S9S_MB_2U_LIB.S9S_MB_2U(SCH_1):PAGE41_I11@PURE_QUANTA.SOCKET4677_AZIF0045P001C01CS(CHIPS)':
 'VSS110': CDS_PINID='VSS110';
NODE_NAME     U2 AE54
 '@S9S_MB_2U_LIB.S9S_MB_2U(SCH_1):PAGE41_I11@PURE_QUANTA.SOCKET4677_AZIF0045P001C01CS(CHIPS)':
 'VSS111': CDS_PINID='VSS111';
NODE_NAME     U2 AE56
 '@S9S_MB_2U_LIB.S9S_MB_2U(SCH_1):PAGE41_I11@PURE_QUANTA.SOCKET4677_AZIF0045P001C01CS(CHIPS)':
 'VSS112': CDS_PINID='VSS112';
NODE_NAME     U2 AE58
 '@S9S_MB_2U_LIB.S9S_MB_2U(SCH_1):PAGE41_I11@PURE_QUANTA.SOCKET4677_AZIF0045P001C01CS(CHIPS)':
 'VSS113': CDS_PINID='VSS113';
NODE_NAME     U2 AE60
 '@S9S_MB_2U_LIB.S9S_MB_2U(SCH_1):PAGE41_I11@PURE_QUANTA.SOCKET4677_AZIF0045P001C01CS(CHIPS)':
 'VSS114': CDS_PINID='VSS114';
NODE_NAME     U2 AE62
 '@S9S_MB_2U_LIB.S9S_MB_2U(SCH_1):PAGE41_I11@PURE_QUANTA.SOCKET4677_AZIF0045P001C01CS(CHIPS)':
 'VSS115': CDS_PINID='VSS115';
NODE_NAME     U2 AE64
 '@S9S_MB_2U_LIB.S9S_MB_2U(SCH_1):PAGE41_I11@PURE_QUANTA.SOCKET4677_AZIF0045P001C01CS(CHIPS)':
 'VSS116': CDS_PINID='VSS116';
NODE_NAME     U2 AE66
 '@S9S_MB_2U_LIB.S9S_MB_2U(SCH_1):PAGE41_I11@PURE_QUANTA.SOCKET4677_AZIF0045P001C01CS(CHIPS)':
 'VSS117': CDS_PINID='VSS117';
NODE_NAME     U2 AE68
 '@S9S_MB_2U_LIB.S9S_MB_2U(SCH_1):PAGE41_I11@PURE_QUANTA.SOCKET4677_AZIF0045P001C01CS(CHIPS)':
 'VSS118': CDS_PINID='VSS118';
NODE_NAME     U2 AE70
 '@S9S_MB_2U_LIB.S9S_MB_2U(SCH_1):PAGE41_I11@PURE_QUANTA.SOCKET4677_AZIF0045P001C01CS(CHIPS)':
 'VSS119': CDS_PINID='VSS119';
NODE_NAME     U2 AE72
 '@S9S_MB_2U_LIB.S9S_MB_2U(SCH_1):PAGE41_I11@PURE_QUANTA.SOCKET4677_AZIF0045P001C01CS(CHIPS)':
 'VSS120': CDS_PINID='VSS120';
NODE_NAME     U2 AE74
 '@S9S_MB_2U_LIB.S9S_MB_2U(SCH_1):PAGE41_I11@PURE_QUANTA.SOCKET4677_AZIF0045P001C01CS(CHIPS)':
 'VSS121': CDS_PINID='VSS121';
NODE_NAME     U2 AE76
 '@S9S_MB_2U_LIB.S9S_MB_2U(SCH_1):PAGE41_I11@PURE_QUANTA.SOCKET4677_AZIF0045P001C01CS(CHIPS)':
 'VSS122': CDS_PINID='VSS122';
NODE_NAME     U2 AE78
 '@S9S_MB_2U_LIB.S9S_MB_2U(SCH_1):PAGE41_I11@PURE_QUANTA.SOCKET4677_AZIF0045P001C01CS(CHIPS)':
 'VSS123': CDS_PINID='VSS123';
NODE_NAME     U2 AE84
 '@S9S_MB_2U_LIB.S9S_MB_2U(SCH_1):PAGE41_I11@PURE_QUANTA.SOCKET4677_AZIF0045P001C01CS(CHIPS)':
 'VSS124': CDS_PINID='VSS124';
NODE_NAME     U2 AE88
 '@S9S_MB_2U_LIB.S9S_MB_2U(SCH_1):PAGE41_I11@PURE_QUANTA.SOCKET4677_AZIF0045P001C01CS(CHIPS)':
 'VSS125': CDS_PINID='VSS125';
NODE_NAME     U2 AF12
 '@S9S_MB_2U_LIB.S9S_MB_2U(SCH_1):PAGE41_I11@PURE_QUANTA.SOCKET4677_AZIF0045P001C01CS(CHIPS)':
 'VSS126': CDS_PINID='VSS126';
NODE_NAME     U2 AF16
 '@S9S_MB_2U_LIB.S9S_MB_2U(SCH_1):PAGE41_I11@PURE_QUANTA.SOCKET4677_AZIF0045P001C01CS(CHIPS)':
 'VSS127': CDS_PINID='VSS127';
NODE_NAME     U2 AF4
 '@S9S_MB_2U_LIB.S9S_MB_2U(SCH_1):PAGE41_I11@PURE_QUANTA.SOCKET4677_AZIF0045P001C01CS(CHIPS)':
 'VSS128': CDS_PINID='VSS128';
NODE_NAME     U2 AF42
 '@S9S_MB_2U_LIB.S9S_MB_2U(SCH_1):PAGE41_I11@PURE_QUANTA.SOCKET4677_AZIF0045P001C01CS(CHIPS)':
 'VSS129': CDS_PINID='VSS129';
NODE_NAME     U2 AF8
 '@S9S_MB_2U_LIB.S9S_MB_2U(SCH_1):PAGE41_I11@PURE_QUANTA.SOCKET4677_AZIF0045P001C01CS(CHIPS)':
 'VSS130': CDS_PINID='VSS130';
NODE_NAME     U2 AF81
 '@S9S_MB_2U_LIB.S9S_MB_2U(SCH_1):PAGE41_I11@PURE_QUANTA.SOCKET4677_AZIF0045P001C01CS(CHIPS)':
 'VSS131': CDS_PINID='VSS131';
NODE_NAME     U2 AF87
 '@S9S_MB_2U_LIB.S9S_MB_2U(SCH_1):PAGE41_I11@PURE_QUANTA.SOCKET4677_AZIF0045P001C01CS(CHIPS)':
 'VSS132': CDS_PINID='VSS132';
NODE_NAME     U2 AF91
 '@S9S_MB_2U_LIB.S9S_MB_2U(SCH_1):PAGE41_I11@PURE_QUANTA.SOCKET4677_AZIF0045P001C01CS(CHIPS)':
 'VSS133': CDS_PINID='VSS133';
NODE_NAME     U2 AG1
 '@S9S_MB_2U_LIB.S9S_MB_2U(SCH_1):PAGE41_I11@PURE_QUANTA.SOCKET4677_AZIF0045P001C01CS(CHIPS)':
 'VSS134': CDS_PINID='VSS134';
NODE_NAME     U2 AG13
 '@S9S_MB_2U_LIB.S9S_MB_2U(SCH_1):PAGE41_I11@PURE_QUANTA.SOCKET4677_AZIF0045P001C01CS(CHIPS)':
 'VSS135': CDS_PINID='VSS135';
NODE_NAME     U2 AG21
 '@S9S_MB_2U_LIB.S9S_MB_2U(SCH_1):PAGE41_I11@PURE_QUANTA.SOCKET4677_AZIF0045P001C01CS(CHIPS)':
 'VSS136': CDS_PINID='VSS136';
NODE_NAME     U2 AG27
 '@S9S_MB_2U_LIB.S9S_MB_2U(SCH_1):PAGE41_I11@PURE_QUANTA.SOCKET4677_AZIF0045P001C01CS(CHIPS)':
 'VSS137': CDS_PINID='VSS137';
NODE_NAME     U2 AG33
 '@S9S_MB_2U_LIB.S9S_MB_2U(SCH_1):PAGE41_I11@PURE_QUANTA.SOCKET4677_AZIF0045P001C01CS(CHIPS)':
 'VSS138': CDS_PINID='VSS138';
NODE_NAME     U2 AG39
 '@S9S_MB_2U_LIB.S9S_MB_2U(SCH_1):PAGE41_I11@PURE_QUANTA.SOCKET4677_AZIF0045P001C01CS(CHIPS)':
 'VSS139': CDS_PINID='VSS139';
NODE_NAME     U2 AG45
 '@S9S_MB_2U_LIB.S9S_MB_2U(SCH_1):PAGE41_I11@PURE_QUANTA.SOCKET4677_AZIF0045P001C01CS(CHIPS)':
 'VSS140': CDS_PINID='VSS140';
NODE_NAME     U2 AG5
 '@S9S_MB_2U_LIB.S9S_MB_2U(SCH_1):PAGE41_I11@PURE_QUANTA.SOCKET4677_AZIF0045P001C01CS(CHIPS)':
 'VSS141': CDS_PINID='VSS141';
NODE_NAME     U2 AG52
 '@S9S_MB_2U_LIB.S9S_MB_2U(SCH_1):PAGE41_I11@PURE_QUANTA.SOCKET4677_AZIF0045P001C01CS(CHIPS)':
 'VSS142': CDS_PINID='VSS142';
NODE_NAME     U2 AG58
 '@S9S_MB_2U_LIB.S9S_MB_2U(SCH_1):PAGE41_I11@PURE_QUANTA.SOCKET4677_AZIF0045P001C01CS(CHIPS)':
 'VSS143': CDS_PINID='VSS143';
NODE_NAME     U2 AG64
 '@S9S_MB_2U_LIB.S9S_MB_2U(SCH_1):PAGE41_I11@PURE_QUANTA.SOCKET4677_AZIF0045P001C01CS(CHIPS)':
 'VSS144': CDS_PINID='VSS144';
NODE_NAME     U2 AG70
 '@S9S_MB_2U_LIB.S9S_MB_2U(SCH_1):PAGE41_I11@PURE_QUANTA.SOCKET4677_AZIF0045P001C01CS(CHIPS)':
 'VSS145': CDS_PINID='VSS145';
NODE_NAME     U2 AG76
 '@S9S_MB_2U_LIB.S9S_MB_2U(SCH_1):PAGE41_I11@PURE_QUANTA.SOCKET4677_AZIF0045P001C01CS(CHIPS)':
 'VSS146': CDS_PINID='VSS146';
NODE_NAME     U2 AG84
 '@S9S_MB_2U_LIB.S9S_MB_2U(SCH_1):PAGE41_I11@PURE_QUANTA.SOCKET4677_AZIF0045P001C01CS(CHIPS)':
 'VSS147': CDS_PINID='VSS147';
NODE_NAME     U2 AG88
 '@S9S_MB_2U_LIB.S9S_MB_2U(SCH_1):PAGE41_I11@PURE_QUANTA.SOCKET4677_AZIF0045P001C01CS(CHIPS)':
 'VSS148': CDS_PINID='VSS148';
NODE_NAME     U2 AG9
 '@S9S_MB_2U_LIB.S9S_MB_2U(SCH_1):PAGE41_I11@PURE_QUANTA.SOCKET4677_AZIF0045P001C01CS(CHIPS)':
 'VSS149': CDS_PINID='VSS149';
NODE_NAME     U2 AH12
 '@S9S_MB_2U_LIB.S9S_MB_2U(SCH_1):PAGE41_I11@PURE_QUANTA.SOCKET4677_AZIF0045P001C01CS(CHIPS)':
 'VSS150': CDS_PINID='VSS150';
NODE_NAME     U2 AH16
 '@S9S_MB_2U_LIB.S9S_MB_2U(SCH_1):PAGE41_I11@PURE_QUANTA.SOCKET4677_AZIF0045P001C01CS(CHIPS)':
 'VSS151': CDS_PINID='VSS151';
NODE_NAME     U2 AH20
 '@S9S_MB_2U_LIB.S9S_MB_2U(SCH_1):PAGE41_I11@PURE_QUANTA.SOCKET4677_AZIF0045P001C01CS(CHIPS)':
 'VSS152': CDS_PINID='VSS152';
NODE_NAME     U2 AH22
 '@S9S_MB_2U_LIB.S9S_MB_2U(SCH_1):PAGE41_I11@PURE_QUANTA.SOCKET4677_AZIF0045P001C01CS(CHIPS)':
 'VSS153': CDS_PINID='VSS153';
NODE_NAME     U2 AH26
 '@S9S_MB_2U_LIB.S9S_MB_2U(SCH_1):PAGE41_I11@PURE_QUANTA.SOCKET4677_AZIF0045P001C01CS(CHIPS)':
 'VSS154': CDS_PINID='VSS154';
NODE_NAME     U2 AH28
 '@S9S_MB_2U_LIB.S9S_MB_2U(SCH_1):PAGE41_I11@PURE_QUANTA.SOCKET4677_AZIF0045P001C01CS(CHIPS)':
 'VSS155': CDS_PINID='VSS155';
NODE_NAME     U2 AH32
 '@S9S_MB_2U_LIB.S9S_MB_2U(SCH_1):PAGE41_I11@PURE_QUANTA.SOCKET4677_AZIF0045P001C01CS(CHIPS)':
 'VSS156': CDS_PINID='VSS156';
NODE_NAME     U2 AH34
 '@S9S_MB_2U_LIB.S9S_MB_2U(SCH_1):PAGE41_I11@PURE_QUANTA.SOCKET4677_AZIF0045P001C01CS(CHIPS)':
 'VSS157': CDS_PINID='VSS157';
NODE_NAME     U2 AH38
 '@S9S_MB_2U_LIB.S9S_MB_2U(SCH_1):PAGE41_I11@PURE_QUANTA.SOCKET4677_AZIF0045P001C01CS(CHIPS)':
 'VSS158': CDS_PINID='VSS158';
NODE_NAME     U2 AH4
 '@S9S_MB_2U_LIB.S9S_MB_2U(SCH_1):PAGE41_I11@PURE_QUANTA.SOCKET4677_AZIF0045P001C01CS(CHIPS)':
 'VSS159': CDS_PINID='VSS159';
NODE_NAME     U2 AH40
 '@S9S_MB_2U_LIB.S9S_MB_2U(SCH_1):PAGE41_I11@PURE_QUANTA.SOCKET4677_AZIF0045P001C01CS(CHIPS)':
 'VSS160': CDS_PINID='VSS160';
NODE_NAME     U2 AH44
 '@S9S_MB_2U_LIB.S9S_MB_2U(SCH_1):PAGE41_I11@PURE_QUANTA.SOCKET4677_AZIF0045P001C01CS(CHIPS)':
 'VSS161': CDS_PINID='VSS161';
NODE_NAME     U2 AH47
 '@S9S_MB_2U_LIB.S9S_MB_2U(SCH_1):PAGE41_I11@PURE_QUANTA.SOCKET4677_AZIF0045P001C01CS(CHIPS)':
 'VSS162': CDS_PINID='VSS162';
NODE_NAME     U2 AH51
 '@S9S_MB_2U_LIB.S9S_MB_2U(SCH_1):PAGE41_I11@PURE_QUANTA.SOCKET4677_AZIF0045P001C01CS(CHIPS)':
 'VSS163': CDS_PINID='VSS163';
NODE_NAME     U2 AH53
 '@S9S_MB_2U_LIB.S9S_MB_2U(SCH_1):PAGE41_I11@PURE_QUANTA.SOCKET4677_AZIF0045P001C01CS(CHIPS)':
 'VSS164': CDS_PINID='VSS164';
NODE_NAME     U2 AH57
 '@S9S_MB_2U_LIB.S9S_MB_2U(SCH_1):PAGE41_I11@PURE_QUANTA.SOCKET4677_AZIF0045P001C01CS(CHIPS)':
 'VSS165': CDS_PINID='VSS165';
NODE_NAME     U2 AH59
 '@S9S_MB_2U_LIB.S9S_MB_2U(SCH_1):PAGE41_I11@PURE_QUANTA.SOCKET4677_AZIF0045P001C01CS(CHIPS)':
 'VSS166': CDS_PINID='VSS166';
NODE_NAME     U2 AH63
 '@S9S_MB_2U_LIB.S9S_MB_2U(SCH_1):PAGE41_I11@PURE_QUANTA.SOCKET4677_AZIF0045P001C01CS(CHIPS)':
 'VSS167': CDS_PINID='VSS167';
NODE_NAME     U2 AH65
 '@S9S_MB_2U_LIB.S9S_MB_2U(SCH_1):PAGE41_I11@PURE_QUANTA.SOCKET4677_AZIF0045P001C01CS(CHIPS)':
 'VSS168': CDS_PINID='VSS168';
NODE_NAME     U2 AH69
 '@S9S_MB_2U_LIB.S9S_MB_2U(SCH_1):PAGE41_I11@PURE_QUANTA.SOCKET4677_AZIF0045P001C01CS(CHIPS)':
 'VSS169': CDS_PINID='VSS169';
NODE_NAME     U2 AH71
 '@S9S_MB_2U_LIB.S9S_MB_2U(SCH_1):PAGE41_I11@PURE_QUANTA.SOCKET4677_AZIF0045P001C01CS(CHIPS)':
 'VSS170': CDS_PINID='VSS170';
NODE_NAME     U2 AH75
 '@S9S_MB_2U_LIB.S9S_MB_2U(SCH_1):PAGE41_I11@PURE_QUANTA.SOCKET4677_AZIF0045P001C01CS(CHIPS)':
 'VSS171': CDS_PINID='VSS171';
NODE_NAME     U2 AH77
 '@S9S_MB_2U_LIB.S9S_MB_2U(SCH_1):PAGE41_I11@PURE_QUANTA.SOCKET4677_AZIF0045P001C01CS(CHIPS)':
 'VSS172': CDS_PINID='VSS172';
NODE_NAME     U2 AH79
 '@S9S_MB_2U_LIB.S9S_MB_2U(SCH_1):PAGE41_I11@PURE_QUANTA.SOCKET4677_AZIF0045P001C01CS(CHIPS)':
 'VSS173': CDS_PINID='VSS173';
NODE_NAME     U2 AH8
 '@S9S_MB_2U_LIB.S9S_MB_2U(SCH_1):PAGE41_I11@PURE_QUANTA.SOCKET4677_AZIF0045P001C01CS(CHIPS)':
 'VSS174': CDS_PINID='VSS174';
NODE_NAME     U2 AH83
 '@S9S_MB_2U_LIB.S9S_MB_2U(SCH_1):PAGE41_I11@PURE_QUANTA.SOCKET4677_AZIF0045P001C01CS(CHIPS)':
 'VSS175': CDS_PINID='VSS175';
NODE_NAME     U2 AJ19
 '@S9S_MB_2U_LIB.S9S_MB_2U(SCH_1):PAGE41_I11@PURE_QUANTA.SOCKET4677_AZIF0045P001C01CS(CHIPS)':
 'VSS176': CDS_PINID='VSS176';
NODE_NAME     U2 AJ23
 '@S9S_MB_2U_LIB.S9S_MB_2U(SCH_1):PAGE41_I11@PURE_QUANTA.SOCKET4677_AZIF0045P001C01CS(CHIPS)':
 'VSS177': CDS_PINID='VSS177';
NODE_NAME     U2 AJ25
 '@S9S_MB_2U_LIB.S9S_MB_2U(SCH_1):PAGE41_I11@PURE_QUANTA.SOCKET4677_AZIF0045P001C01CS(CHIPS)':
 'VSS178': CDS_PINID='VSS178';
NODE_NAME     U2 AJ29
 '@S9S_MB_2U_LIB.S9S_MB_2U(SCH_1):PAGE41_I11@PURE_QUANTA.SOCKET4677_AZIF0045P001C01CS(CHIPS)':
 'VSS179': CDS_PINID='VSS179';
NODE_NAME     U2 AJ31
 '@S9S_MB_2U_LIB.S9S_MB_2U(SCH_1):PAGE41_I11@PURE_QUANTA.SOCKET4677_AZIF0045P001C01CS(CHIPS)':
 'VSS180': CDS_PINID='VSS180';
NODE_NAME     U2 AJ35
 '@S9S_MB_2U_LIB.S9S_MB_2U(SCH_1):PAGE41_I11@PURE_QUANTA.SOCKET4677_AZIF0045P001C01CS(CHIPS)':
 'VSS181': CDS_PINID='VSS181';
NODE_NAME     U2 AJ37
 '@S9S_MB_2U_LIB.S9S_MB_2U(SCH_1):PAGE41_I11@PURE_QUANTA.SOCKET4677_AZIF0045P001C01CS(CHIPS)':
 'VSS182': CDS_PINID='VSS182';
NODE_NAME     U2 AJ41
 '@S9S_MB_2U_LIB.S9S_MB_2U(SCH_1):PAGE41_I11@PURE_QUANTA.SOCKET4677_AZIF0045P001C01CS(CHIPS)':
 'VSS183': CDS_PINID='VSS183';
NODE_NAME     U2 AJ43
 '@S9S_MB_2U_LIB.S9S_MB_2U(SCH_1):PAGE41_I11@PURE_QUANTA.SOCKET4677_AZIF0045P001C01CS(CHIPS)':
 'VSS184': CDS_PINID='VSS184';
NODE_NAME     U2 AJ48
 '@S9S_MB_2U_LIB.S9S_MB_2U(SCH_1):PAGE41_I11@PURE_QUANTA.SOCKET4677_AZIF0045P001C01CS(CHIPS)':
 'VSS185': CDS_PINID='VSS185';
NODE_NAME     U2 AJ50
 '@S9S_MB_2U_LIB.S9S_MB_2U(SCH_1):PAGE41_I11@PURE_QUANTA.SOCKET4677_AZIF0045P001C01CS(CHIPS)':
 'VSS186': CDS_PINID='VSS186';
NODE_NAME     U2 AJ54
 '@S9S_MB_2U_LIB.S9S_MB_2U(SCH_1):PAGE41_I11@PURE_QUANTA.SOCKET4677_AZIF0045P001C01CS(CHIPS)':
 'VSS187': CDS_PINID='VSS187';
NODE_NAME     U2 AJ56
 '@S9S_MB_2U_LIB.S9S_MB_2U(SCH_1):PAGE41_I11@PURE_QUANTA.SOCKET4677_AZIF0045P001C01CS(CHIPS)':
 'VSS188': CDS_PINID='VSS188';
NODE_NAME     U2 AJ60
 '@S9S_MB_2U_LIB.S9S_MB_2U(SCH_1):PAGE41_I11@PURE_QUANTA.SOCKET4677_AZIF0045P001C01CS(CHIPS)':
 'VSS189': CDS_PINID='VSS189';
NODE_NAME     U2 AJ62
 '@S9S_MB_2U_LIB.S9S_MB_2U(SCH_1):PAGE41_I11@PURE_QUANTA.SOCKET4677_AZIF0045P001C01CS(CHIPS)':
 'VSS190': CDS_PINID='VSS190';
NODE_NAME     U2 AJ66
 '@S9S_MB_2U_LIB.S9S_MB_2U(SCH_1):PAGE41_I11@PURE_QUANTA.SOCKET4677_AZIF0045P001C01CS(CHIPS)':
 'VSS191': CDS_PINID='VSS191';
NODE_NAME     U2 AJ68
 '@S9S_MB_2U_LIB.S9S_MB_2U(SCH_1):PAGE41_I11@PURE_QUANTA.SOCKET4677_AZIF0045P001C01CS(CHIPS)':
 'VSS192': CDS_PINID='VSS192';
NODE_NAME     U2 AJ72
 '@S9S_MB_2U_LIB.S9S_MB_2U(SCH_1):PAGE41_I11@PURE_QUANTA.SOCKET4677_AZIF0045P001C01CS(CHIPS)':
 'VSS193': CDS_PINID='VSS193';
NODE_NAME     U2 AJ74
 '@S9S_MB_2U_LIB.S9S_MB_2U(SCH_1):PAGE41_I11@PURE_QUANTA.SOCKET4677_AZIF0045P001C01CS(CHIPS)':
 'VSS194': CDS_PINID='VSS194';
NODE_NAME     U2 AJ78
 '@S9S_MB_2U_LIB.S9S_MB_2U(SCH_1):PAGE41_I11@PURE_QUANTA.SOCKET4677_AZIF0045P001C01CS(CHIPS)':
 'VSS195': CDS_PINID='VSS195';
NODE_NAME     U2 AJ84
 '@S9S_MB_2U_LIB.S9S_MB_2U(SCH_1):PAGE41_I11@PURE_QUANTA.SOCKET4677_AZIF0045P001C01CS(CHIPS)':
 'VSS196': CDS_PINID='VSS196';
NODE_NAME     U2 AJ88
 '@S9S_MB_2U_LIB.S9S_MB_2U(SCH_1):PAGE41_I11@PURE_QUANTA.SOCKET4677_AZIF0045P001C01CS(CHIPS)':
 'VSS197': CDS_PINID='VSS197';
NODE_NAME     U2 AA19
 '@S9S_MB_2U_LIB.S9S_MB_2U(SCH_1):PAGE42_I10@PURE_QUANTA.SOCKET4677_AZIF0045P001C01CS(CHIPS)':
 'VSS17': CDS_PINID='VSS17';
NODE_NAME     U2 AA23
 '@S9S_MB_2U_LIB.S9S_MB_2U(SCH_1):PAGE42_I10@PURE_QUANTA.SOCKET4677_AZIF0045P001C01CS(CHIPS)':
 'VSS18': CDS_PINID='VSS18';
NODE_NAME     U2 AA25
 '@S9S_MB_2U_LIB.S9S_MB_2U(SCH_1):PAGE42_I10@PURE_QUANTA.SOCKET4677_AZIF0045P001C01CS(CHIPS)':
 'VSS19': CDS_PINID='VSS19';
NODE_NAME     U2 AA29
 '@S9S_MB_2U_LIB.S9S_MB_2U(SCH_1):PAGE42_I10@PURE_QUANTA.SOCKET4677_AZIF0045P001C01CS(CHIPS)':
 'VSS20': CDS_PINID='VSS20';
NODE_NAME     U2 AA31
 '@S9S_MB_2U_LIB.S9S_MB_2U(SCH_1):PAGE42_I10@PURE_QUANTA.SOCKET4677_AZIF0045P001C01CS(CHIPS)':
 'VSS21': CDS_PINID='VSS21';
NODE_NAME     U2 AA35
 '@S9S_MB_2U_LIB.S9S_MB_2U(SCH_1):PAGE42_I10@PURE_QUANTA.SOCKET4677_AZIF0045P001C01CS(CHIPS)':
 'VSS22': CDS_PINID='VSS22';
NODE_NAME     U2 AA37
 '@S9S_MB_2U_LIB.S9S_MB_2U(SCH_1):PAGE42_I10@PURE_QUANTA.SOCKET4677_AZIF0045P001C01CS(CHIPS)':
 'VSS23': CDS_PINID='VSS23';
NODE_NAME     U2 AA41
 '@S9S_MB_2U_LIB.S9S_MB_2U(SCH_1):PAGE42_I10@PURE_QUANTA.SOCKET4677_AZIF0045P001C01CS(CHIPS)':
 'VSS24': CDS_PINID='VSS24';
NODE_NAME     U2 AA43
 '@S9S_MB_2U_LIB.S9S_MB_2U(SCH_1):PAGE42_I10@PURE_QUANTA.SOCKET4677_AZIF0045P001C01CS(CHIPS)':
 'VSS25': CDS_PINID='VSS25';
NODE_NAME     U2 AA48
 '@S9S_MB_2U_LIB.S9S_MB_2U(SCH_1):PAGE42_I10@PURE_QUANTA.SOCKET4677_AZIF0045P001C01CS(CHIPS)':
 'VSS26': CDS_PINID='VSS26';
NODE_NAME     U2 AA50
 '@S9S_MB_2U_LIB.S9S_MB_2U(SCH_1):PAGE42_I10@PURE_QUANTA.SOCKET4677_AZIF0045P001C01CS(CHIPS)':
 'VSS27': CDS_PINID='VSS27';
NODE_NAME     U2 AA54
 '@S9S_MB_2U_LIB.S9S_MB_2U(SCH_1):PAGE42_I10@PURE_QUANTA.SOCKET4677_AZIF0045P001C01CS(CHIPS)':
 'VSS28': CDS_PINID='VSS28';
NODE_NAME     U2 AA56
 '@S9S_MB_2U_LIB.S9S_MB_2U(SCH_1):PAGE42_I10@PURE_QUANTA.SOCKET4677_AZIF0045P001C01CS(CHIPS)':
 'VSS29': CDS_PINID='VSS29';
NODE_NAME     U2 AA60
 '@S9S_MB_2U_LIB.S9S_MB_2U(SCH_1):PAGE42_I10@PURE_QUANTA.SOCKET4677_AZIF0045P001C01CS(CHIPS)':
 'VSS30': CDS_PINID='VSS30';
NODE_NAME     U2 AA62
 '@S9S_MB_2U_LIB.S9S_MB_2U(SCH_1):PAGE42_I10@PURE_QUANTA.SOCKET4677_AZIF0045P001C01CS(CHIPS)':
 'VSS31': CDS_PINID='VSS31';
NODE_NAME     U2 AA66
 '@S9S_MB_2U_LIB.S9S_MB_2U(SCH_1):PAGE42_I10@PURE_QUANTA.SOCKET4677_AZIF0045P001C01CS(CHIPS)':
 'VSS32': CDS_PINID='VSS32';
NODE_NAME     U2 AA68
 '@S9S_MB_2U_LIB.S9S_MB_2U(SCH_1):PAGE42_I10@PURE_QUANTA.SOCKET4677_AZIF0045P001C01CS(CHIPS)':
 'VSS33': CDS_PINID='VSS33';
NODE_NAME     U2 AA72
 '@S9S_MB_2U_LIB.S9S_MB_2U(SCH_1):PAGE42_I10@PURE_QUANTA.SOCKET4677_AZIF0045P001C01CS(CHIPS)':
 'VSS34': CDS_PINID='VSS34';
NODE_NAME     U2 AA74
 '@S9S_MB_2U_LIB.S9S_MB_2U(SCH_1):PAGE42_I10@PURE_QUANTA.SOCKET4677_AZIF0045P001C01CS(CHIPS)':
 'VSS35': CDS_PINID='VSS35';
NODE_NAME     U2 AA78
 '@S9S_MB_2U_LIB.S9S_MB_2U(SCH_1):PAGE42_I10@PURE_QUANTA.SOCKET4677_AZIF0045P001C01CS(CHIPS)':
 'VSS36': CDS_PINID='VSS36';
NODE_NAME     U2 AA80
 '@S9S_MB_2U_LIB.S9S_MB_2U(SCH_1):PAGE42_I10@PURE_QUANTA.SOCKET4677_AZIF0045P001C01CS(CHIPS)':
 'VSS37': CDS_PINID='VSS37';
NODE_NAME     U2 P32
 '@S9S_MB_2U_LIB.S9S_MB_2U(SCH_1):PAGE42_I10@PURE_QUANTA.SOCKET4677_AZIF0045P001C01CS(CHIPS)':
 'VSS1690': CDS_PINID='VSS1690';
NODE_NAME     U2 N76
 '@S9S_MB_2U_LIB.S9S_MB_2U(SCH_1):PAGE42_I10@PURE_QUANTA.SOCKET4677_AZIF0045P001C01CS(CHIPS)':
 'VSS1696': CDS_PINID='VSS1696';
NODE_NAME     U2 P51
 '@S9S_MB_2U_LIB.S9S_MB_2U(SCH_1):PAGE42_I10@PURE_QUANTA.SOCKET4677_AZIF0045P001C01CS(CHIPS)':
 'VSS1697': CDS_PINID='VSS1697';
NODE_NAME     U2 N78
 '@S9S_MB_2U_LIB.S9S_MB_2U(SCH_1):PAGE42_I10@PURE_QUANTA.SOCKET4677_AZIF0045P001C01CS(CHIPS)':
 'VSS1698': CDS_PINID='VSS1698';
NODE_NAME     U2 P57
 '@S9S_MB_2U_LIB.S9S_MB_2U(SCH_1):PAGE42_I10@PURE_QUANTA.SOCKET4677_AZIF0045P001C01CS(CHIPS)':
 'VSS1699': CDS_PINID='VSS1699';
NODE_NAME     U2 N80
 '@S9S_MB_2U_LIB.S9S_MB_2U(SCH_1):PAGE42_I10@PURE_QUANTA.SOCKET4677_AZIF0045P001C01CS(CHIPS)':
 'VSS1700': CDS_PINID='VSS1700';
NODE_NAME     U2 N82
 '@S9S_MB_2U_LIB.S9S_MB_2U(SCH_1):PAGE42_I10@PURE_QUANTA.SOCKET4677_AZIF0045P001C01CS(CHIPS)':
 'VSS1701': CDS_PINID='VSS1701';
NODE_NAME     U2 N84
 '@S9S_MB_2U_LIB.S9S_MB_2U(SCH_1):PAGE42_I10@PURE_QUANTA.SOCKET4677_AZIF0045P001C01CS(CHIPS)':
 'VSS1702': CDS_PINID='VSS1702';
NODE_NAME     U2 N88
 '@S9S_MB_2U_LIB.S9S_MB_2U(SCH_1):PAGE42_I10@PURE_QUANTA.SOCKET4677_AZIF0045P001C01CS(CHIPS)':
 'VSS1703': CDS_PINID='VSS1703';
NODE_NAME     U2 P71
 '@S9S_MB_2U_LIB.S9S_MB_2U(SCH_1):PAGE42_I10@PURE_QUANTA.SOCKET4677_AZIF0045P001C01CS(CHIPS)':
 'VSS1704': CDS_PINID='VSS1704';
NODE_NAME     U2 P12
 '@S9S_MB_2U_LIB.S9S_MB_2U(SCH_1):PAGE42_I10@PURE_QUANTA.SOCKET4677_AZIF0045P001C01CS(CHIPS)':
 'VSS1705': CDS_PINID='VSS1705';
NODE_NAME     U2 P16
 '@S9S_MB_2U_LIB.S9S_MB_2U(SCH_1):PAGE42_I10@PURE_QUANTA.SOCKET4677_AZIF0045P001C01CS(CHIPS)':
 'VSS1706': CDS_PINID='VSS1706';
NODE_NAME     U2 P20
 '@S9S_MB_2U_LIB.S9S_MB_2U(SCH_1):PAGE42_I10@PURE_QUANTA.SOCKET4677_AZIF0045P001C01CS(CHIPS)':
 'VSS1707': CDS_PINID='VSS1707';
NODE_NAME     U2 P22
 '@S9S_MB_2U_LIB.S9S_MB_2U(SCH_1):PAGE42_I10@PURE_QUANTA.SOCKET4677_AZIF0045P001C01CS(CHIPS)':
 'VSS1708': CDS_PINID='VSS1708';
NODE_NAME     U2 P26
 '@S9S_MB_2U_LIB.S9S_MB_2U(SCH_1):PAGE42_I10@PURE_QUANTA.SOCKET4677_AZIF0045P001C01CS(CHIPS)':
 'VSS1709': CDS_PINID='VSS1709';
NODE_NAME     U2 P28
 '@S9S_MB_2U_LIB.S9S_MB_2U(SCH_1):PAGE42_I10@PURE_QUANTA.SOCKET4677_AZIF0045P001C01CS(CHIPS)':
 'VSS1710': CDS_PINID='VSS1710';
NODE_NAME     U2 R1
 '@S9S_MB_2U_LIB.S9S_MB_2U(SCH_1):PAGE42_I10@PURE_QUANTA.SOCKET4677_AZIF0045P001C01CS(CHIPS)':
 'VSS1711': CDS_PINID='VSS1711';
NODE_NAME     U2 P34
 '@S9S_MB_2U_LIB.S9S_MB_2U(SCH_1):PAGE42_I10@PURE_QUANTA.SOCKET4677_AZIF0045P001C01CS(CHIPS)':
 'VSS1712': CDS_PINID='VSS1712';
NODE_NAME     U2 P38
 '@S9S_MB_2U_LIB.S9S_MB_2U(SCH_1):PAGE42_I10@PURE_QUANTA.SOCKET4677_AZIF0045P001C01CS(CHIPS)':
 'VSS1713': CDS_PINID='VSS1713';
NODE_NAME     U2 R19
 '@S9S_MB_2U_LIB.S9S_MB_2U(SCH_1):PAGE42_I10@PURE_QUANTA.SOCKET4677_AZIF0045P001C01CS(CHIPS)':
 'VSS1714': CDS_PINID='VSS1714';
NODE_NAME     U2 R23
 '@S9S_MB_2U_LIB.S9S_MB_2U(SCH_1):PAGE42_I10@PURE_QUANTA.SOCKET4677_AZIF0045P001C01CS(CHIPS)':
 'VSS1715': CDS_PINID='VSS1715';
NODE_NAME     U2 P4
 '@S9S_MB_2U_LIB.S9S_MB_2U(SCH_1):PAGE42_I10@PURE_QUANTA.SOCKET4677_AZIF0045P001C01CS(CHIPS)':
 'VSS1716': CDS_PINID='VSS1716';
NODE_NAME     U2 P40
 '@S9S_MB_2U_LIB.S9S_MB_2U(SCH_1):PAGE42_I10@PURE_QUANTA.SOCKET4677_AZIF0045P001C01CS(CHIPS)':
 'VSS1717': CDS_PINID='VSS1717';
NODE_NAME     U2 P44
 '@S9S_MB_2U_LIB.S9S_MB_2U(SCH_1):PAGE42_I10@PURE_QUANTA.SOCKET4677_AZIF0045P001C01CS(CHIPS)':
 'VSS1718': CDS_PINID='VSS1718';
NODE_NAME     U2 P47
 '@S9S_MB_2U_LIB.S9S_MB_2U(SCH_1):PAGE42_I10@PURE_QUANTA.SOCKET4677_AZIF0045P001C01CS(CHIPS)':
 'VSS1719': CDS_PINID='VSS1719';
NODE_NAME     U2 P53
 '@S9S_MB_2U_LIB.S9S_MB_2U(SCH_1):PAGE42_I10@PURE_QUANTA.SOCKET4677_AZIF0045P001C01CS(CHIPS)':
 'VSS1720': CDS_PINID='VSS1720';
NODE_NAME     U2 P59
 '@S9S_MB_2U_LIB.S9S_MB_2U(SCH_1):PAGE42_I10@PURE_QUANTA.SOCKET4677_AZIF0045P001C01CS(CHIPS)':
 'VSS1721': CDS_PINID='VSS1721';
NODE_NAME     U2 P63
 '@S9S_MB_2U_LIB.S9S_MB_2U(SCH_1):PAGE42_I10@PURE_QUANTA.SOCKET4677_AZIF0045P001C01CS(CHIPS)':
 'VSS1722': CDS_PINID='VSS1722';
NODE_NAME     U2 R48
 '@S9S_MB_2U_LIB.S9S_MB_2U(SCH_1):PAGE42_I10@PURE_QUANTA.SOCKET4677_AZIF0045P001C01CS(CHIPS)':
 'VSS1723': CDS_PINID='VSS1723';
NODE_NAME     U2 P65
 '@S9S_MB_2U_LIB.S9S_MB_2U(SCH_1):PAGE42_I10@PURE_QUANTA.SOCKET4677_AZIF0045P001C01CS(CHIPS)':
 'VSS1724': CDS_PINID='VSS1724';
NODE_NAME     U2 P69
 '@S9S_MB_2U_LIB.S9S_MB_2U(SCH_1):PAGE42_I10@PURE_QUANTA.SOCKET4677_AZIF0045P001C01CS(CHIPS)':
 'VSS1725': CDS_PINID='VSS1725';
NODE_NAME     U2 P75
 '@S9S_MB_2U_LIB.S9S_MB_2U(SCH_1):PAGE42_I10@PURE_QUANTA.SOCKET4677_AZIF0045P001C01CS(CHIPS)':
 'VSS1726': CDS_PINID='VSS1726';
NODE_NAME     U2 P77
 '@S9S_MB_2U_LIB.S9S_MB_2U(SCH_1):PAGE42_I10@PURE_QUANTA.SOCKET4677_AZIF0045P001C01CS(CHIPS)':
 'VSS1727': CDS_PINID='VSS1727';
NODE_NAME     U2 R60
 '@S9S_MB_2U_LIB.S9S_MB_2U(SCH_1):PAGE42_I10@PURE_QUANTA.SOCKET4677_AZIF0045P001C01CS(CHIPS)':
 'VSS1728': CDS_PINID='VSS1728';
NODE_NAME     U2 P8
 '@S9S_MB_2U_LIB.S9S_MB_2U(SCH_1):PAGE42_I10@PURE_QUANTA.SOCKET4677_AZIF0045P001C01CS(CHIPS)':
 'VSS1729': CDS_PINID='VSS1729';
NODE_NAME     U2 R66
 '@S9S_MB_2U_LIB.S9S_MB_2U(SCH_1):PAGE42_I10@PURE_QUANTA.SOCKET4677_AZIF0045P001C01CS(CHIPS)':
 'VSS1730': CDS_PINID='VSS1730';
NODE_NAME     U2 P87
 '@S9S_MB_2U_LIB.S9S_MB_2U(SCH_1):PAGE42_I10@PURE_QUANTA.SOCKET4677_AZIF0045P001C01CS(CHIPS)':
 'VSS1731': CDS_PINID='VSS1731';
NODE_NAME     U2 P91
 '@S9S_MB_2U_LIB.S9S_MB_2U(SCH_1):PAGE42_I10@PURE_QUANTA.SOCKET4677_AZIF0045P001C01CS(CHIPS)':
 'VSS1732': CDS_PINID='VSS1732';
NODE_NAME     U2 R13
 '@S9S_MB_2U_LIB.S9S_MB_2U(SCH_1):PAGE42_I10@PURE_QUANTA.SOCKET4677_AZIF0045P001C01CS(CHIPS)':
 'VSS1733': CDS_PINID='VSS1733';
NODE_NAME     U2 R17
 '@S9S_MB_2U_LIB.S9S_MB_2U(SCH_1):PAGE42_I10@PURE_QUANTA.SOCKET4677_AZIF0045P001C01CS(CHIPS)':
 'VSS1734': CDS_PINID='VSS1734';
NODE_NAME     U2 R25
 '@S9S_MB_2U_LIB.S9S_MB_2U(SCH_1):PAGE42_I10@PURE_QUANTA.SOCKET4677_AZIF0045P001C01CS(CHIPS)':
 'VSS1735': CDS_PINID='VSS1735';
NODE_NAME     U2 R29
 '@S9S_MB_2U_LIB.S9S_MB_2U(SCH_1):PAGE42_I10@PURE_QUANTA.SOCKET4677_AZIF0045P001C01CS(CHIPS)':
 'VSS1736': CDS_PINID='VSS1736';
NODE_NAME     U2 R31
 '@S9S_MB_2U_LIB.S9S_MB_2U(SCH_1):PAGE42_I10@PURE_QUANTA.SOCKET4677_AZIF0045P001C01CS(CHIPS)':
 'VSS1737': CDS_PINID='VSS1737';
NODE_NAME     U2 R35
 '@S9S_MB_2U_LIB.S9S_MB_2U(SCH_1):PAGE42_I10@PURE_QUANTA.SOCKET4677_AZIF0045P001C01CS(CHIPS)':
 'VSS1738': CDS_PINID='VSS1738';
NODE_NAME     U2 T12
 '@S9S_MB_2U_LIB.S9S_MB_2U(SCH_1):PAGE42_I10@PURE_QUANTA.SOCKET4677_AZIF0045P001C01CS(CHIPS)':
 'VSS1739': CDS_PINID='VSS1739';
NODE_NAME     U2 T16
 '@S9S_MB_2U_LIB.S9S_MB_2U(SCH_1):PAGE42_I10@PURE_QUANTA.SOCKET4677_AZIF0045P001C01CS(CHIPS)':
 'VSS1740': CDS_PINID='VSS1740';
NODE_NAME     U2 T18
 '@S9S_MB_2U_LIB.S9S_MB_2U(SCH_1):PAGE42_I10@PURE_QUANTA.SOCKET4677_AZIF0045P001C01CS(CHIPS)':
 'VSS1741': CDS_PINID='VSS1741';
NODE_NAME     U2 R37
 '@S9S_MB_2U_LIB.S9S_MB_2U(SCH_1):PAGE42_I10@PURE_QUANTA.SOCKET4677_AZIF0045P001C01CS(CHIPS)':
 'VSS1742': CDS_PINID='VSS1742';
NODE_NAME     U2 R41
 '@S9S_MB_2U_LIB.S9S_MB_2U(SCH_1):PAGE42_I10@PURE_QUANTA.SOCKET4677_AZIF0045P001C01CS(CHIPS)':
 'VSS1743': CDS_PINID='VSS1743';
NODE_NAME     U2 R43
 '@S9S_MB_2U_LIB.S9S_MB_2U(SCH_1):PAGE42_I10@PURE_QUANTA.SOCKET4677_AZIF0045P001C01CS(CHIPS)':
 'VSS1744': CDS_PINID='VSS1744';
NODE_NAME     U2 R5
 '@S9S_MB_2U_LIB.S9S_MB_2U(SCH_1):PAGE42_I10@PURE_QUANTA.SOCKET4677_AZIF0045P001C01CS(CHIPS)':
 'VSS1745': CDS_PINID='VSS1745';
NODE_NAME     U2 T36
 '@S9S_MB_2U_LIB.S9S_MB_2U(SCH_1):PAGE42_I10@PURE_QUANTA.SOCKET4677_AZIF0045P001C01CS(CHIPS)':
 'VSS1746': CDS_PINID='VSS1746';
NODE_NAME     U2 R50
 '@S9S_MB_2U_LIB.S9S_MB_2U(SCH_1):PAGE42_I10@PURE_QUANTA.SOCKET4677_AZIF0045P001C01CS(CHIPS)':
 'VSS1747': CDS_PINID='VSS1747';
NODE_NAME     U2 R54
 '@S9S_MB_2U_LIB.S9S_MB_2U(SCH_1):PAGE42_I10@PURE_QUANTA.SOCKET4677_AZIF0045P001C01CS(CHIPS)':
 'VSS1748': CDS_PINID='VSS1748';
NODE_NAME     U2 T49
 '@S9S_MB_2U_LIB.S9S_MB_2U(SCH_1):PAGE42_I10@PURE_QUANTA.SOCKET4677_AZIF0045P001C01CS(CHIPS)':
 'VSS1749': CDS_PINID='VSS1749';
NODE_NAME     U2 T55
 '@S9S_MB_2U_LIB.S9S_MB_2U(SCH_1):PAGE42_I10@PURE_QUANTA.SOCKET4677_AZIF0045P001C01CS(CHIPS)':
 'VSS1750': CDS_PINID='VSS1750';
NODE_NAME     U2 R56
 '@S9S_MB_2U_LIB.S9S_MB_2U(SCH_1):PAGE42_I10@PURE_QUANTA.SOCKET4677_AZIF0045P001C01CS(CHIPS)':
 'VSS1751': CDS_PINID='VSS1751';
NODE_NAME     U2 R62
 '@S9S_MB_2U_LIB.S9S_MB_2U(SCH_1):PAGE42_I10@PURE_QUANTA.SOCKET4677_AZIF0045P001C01CS(CHIPS)':
 'VSS1752': CDS_PINID='VSS1752';
NODE_NAME     U2 R68
 '@S9S_MB_2U_LIB.S9S_MB_2U(SCH_1):PAGE42_I10@PURE_QUANTA.SOCKET4677_AZIF0045P001C01CS(CHIPS)':
 'VSS1753': CDS_PINID='VSS1753';
NODE_NAME     U2 R72
 '@S9S_MB_2U_LIB.S9S_MB_2U(SCH_1):PAGE42_I10@PURE_QUANTA.SOCKET4677_AZIF0045P001C01CS(CHIPS)':
 'VSS1754': CDS_PINID='VSS1754';
NODE_NAME     U2 R74
 '@S9S_MB_2U_LIB.S9S_MB_2U(SCH_1):PAGE42_I10@PURE_QUANTA.SOCKET4677_AZIF0045P001C01CS(CHIPS)':
 'VSS1755': CDS_PINID='VSS1755';
NODE_NAME     U2 R78
 '@S9S_MB_2U_LIB.S9S_MB_2U(SCH_1):PAGE42_I10@PURE_QUANTA.SOCKET4677_AZIF0045P001C01CS(CHIPS)':
 'VSS1756': CDS_PINID='VSS1756';
NODE_NAME     U2 R84
 '@S9S_MB_2U_LIB.S9S_MB_2U(SCH_1):PAGE42_I10@PURE_QUANTA.SOCKET4677_AZIF0045P001C01CS(CHIPS)':
 'VSS1757': CDS_PINID='VSS1757';
NODE_NAME     U2 R88
 '@S9S_MB_2U_LIB.S9S_MB_2U(SCH_1):PAGE42_I10@PURE_QUANTA.SOCKET4677_AZIF0045P001C01CS(CHIPS)':
 'VSS1758': CDS_PINID='VSS1758';
NODE_NAME     U2 R9
 '@S9S_MB_2U_LIB.S9S_MB_2U(SCH_1):PAGE42_I10@PURE_QUANTA.SOCKET4677_AZIF0045P001C01CS(CHIPS)':
 'VSS1759': CDS_PINID='VSS1759';
NODE_NAME     U2 T24
 '@S9S_MB_2U_LIB.S9S_MB_2U(SCH_1):PAGE42_I10@PURE_QUANTA.SOCKET4677_AZIF0045P001C01CS(CHIPS)':
 'VSS1760': CDS_PINID='VSS1760';
NODE_NAME     U2 T30
 '@S9S_MB_2U_LIB.S9S_MB_2U(SCH_1):PAGE42_I10@PURE_QUANTA.SOCKET4677_AZIF0045P001C01CS(CHIPS)':
 'VSS1761': CDS_PINID='VSS1761';
NODE_NAME     U2 T4
 '@S9S_MB_2U_LIB.S9S_MB_2U(SCH_1):PAGE42_I10@PURE_QUANTA.SOCKET4677_AZIF0045P001C01CS(CHIPS)':
 'VSS1762': CDS_PINID='VSS1762';
NODE_NAME     U2 T42
 '@S9S_MB_2U_LIB.S9S_MB_2U(SCH_1):PAGE42_I10@PURE_QUANTA.SOCKET4677_AZIF0045P001C01CS(CHIPS)':
 'VSS1763': CDS_PINID='VSS1763';
NODE_NAME     U2 T61
 '@S9S_MB_2U_LIB.S9S_MB_2U(SCH_1):PAGE42_I10@PURE_QUANTA.SOCKET4677_AZIF0045P001C01CS(CHIPS)':
 'VSS1764': CDS_PINID='VSS1764';
NODE_NAME     U2 T67
 '@S9S_MB_2U_LIB.S9S_MB_2U(SCH_1):PAGE42_I10@PURE_QUANTA.SOCKET4677_AZIF0045P001C01CS(CHIPS)':
 'VSS1765': CDS_PINID='VSS1765';
NODE_NAME     U2 U52
 '@S9S_MB_2U_LIB.S9S_MB_2U(SCH_1):PAGE42_I10@PURE_QUANTA.SOCKET4677_AZIF0045P001C01CS(CHIPS)':
 'VSS1766': CDS_PINID='VSS1766';
NODE_NAME     U2 T73
 '@S9S_MB_2U_LIB.S9S_MB_2U(SCH_1):PAGE42_I10@PURE_QUANTA.SOCKET4677_AZIF0045P001C01CS(CHIPS)':
 'VSS1767': CDS_PINID='VSS1767';
NODE_NAME     U2 T79
 '@S9S_MB_2U_LIB.S9S_MB_2U(SCH_1):PAGE42_I10@PURE_QUANTA.SOCKET4677_AZIF0045P001C01CS(CHIPS)':
 'VSS1768': CDS_PINID='VSS1768';
NODE_NAME     U2 T8
 '@S9S_MB_2U_LIB.S9S_MB_2U(SCH_1):PAGE42_I10@PURE_QUANTA.SOCKET4677_AZIF0045P001C01CS(CHIPS)':
 'VSS1769': CDS_PINID='VSS1769';
NODE_NAME     U2 T83
 '@S9S_MB_2U_LIB.S9S_MB_2U(SCH_1):PAGE42_I10@PURE_QUANTA.SOCKET4677_AZIF0045P001C01CS(CHIPS)':
 'VSS1770': CDS_PINID='VSS1770';
NODE_NAME     U2 U39
 '@S9S_MB_2U_LIB.S9S_MB_2U(SCH_1):PAGE42_I10@PURE_QUANTA.SOCKET4677_AZIF0045P001C01CS(CHIPS)':
 'VSS1771': CDS_PINID='VSS1771';
NODE_NAME     U2 U82
 '@S9S_MB_2U_LIB.S9S_MB_2U(SCH_1):PAGE42_I10@PURE_QUANTA.SOCKET4677_AZIF0045P001C01CS(CHIPS)':
 'VSS1772': CDS_PINID='VSS1772';
NODE_NAME     U2 U84
 '@S9S_MB_2U_LIB.S9S_MB_2U(SCH_1):PAGE42_I10@PURE_QUANTA.SOCKET4677_AZIF0045P001C01CS(CHIPS)':
 'VSS1773': CDS_PINID='VSS1773';
NODE_NAME     U2 U88
 '@S9S_MB_2U_LIB.S9S_MB_2U(SCH_1):PAGE42_I10@PURE_QUANTA.SOCKET4677_AZIF0045P001C01CS(CHIPS)':
 'VSS1774': CDS_PINID='VSS1774';
NODE_NAME     U2 V12
 '@S9S_MB_2U_LIB.S9S_MB_2U(SCH_1):PAGE42_I10@PURE_QUANTA.SOCKET4677_AZIF0045P001C01CS(CHIPS)':
 'VSS1775': CDS_PINID='VSS1775';
NODE_NAME     U2 V16
 '@S9S_MB_2U_LIB.S9S_MB_2U(SCH_1):PAGE42_I10@PURE_QUANTA.SOCKET4677_AZIF0045P001C01CS(CHIPS)':
 'VSS1776': CDS_PINID='VSS1776';
NODE_NAME     U2 V18
 '@S9S_MB_2U_LIB.S9S_MB_2U(SCH_1):PAGE42_I10@PURE_QUANTA.SOCKET4677_AZIF0045P001C01CS(CHIPS)':
 'VSS1777': CDS_PINID='VSS1777';
NODE_NAME     U2 V20
 '@S9S_MB_2U_LIB.S9S_MB_2U(SCH_1):PAGE42_I10@PURE_QUANTA.SOCKET4677_AZIF0045P001C01CS(CHIPS)':
 'VSS1778': CDS_PINID='VSS1778';
NODE_NAME     U2 V22
 '@S9S_MB_2U_LIB.S9S_MB_2U(SCH_1):PAGE42_I10@PURE_QUANTA.SOCKET4677_AZIF0045P001C01CS(CHIPS)':
 'VSS1779': CDS_PINID='VSS1779';
NODE_NAME     U2 V24
 '@S9S_MB_2U_LIB.S9S_MB_2U(SCH_1):PAGE42_I10@PURE_QUANTA.SOCKET4677_AZIF0045P001C01CS(CHIPS)':
 'VSS1780': CDS_PINID='VSS1780';
NODE_NAME     U2 V26
 '@S9S_MB_2U_LIB.S9S_MB_2U(SCH_1):PAGE42_I10@PURE_QUANTA.SOCKET4677_AZIF0045P001C01CS(CHIPS)':
 'VSS1781': CDS_PINID='VSS1781';
NODE_NAME     U2 V28
 '@S9S_MB_2U_LIB.S9S_MB_2U(SCH_1):PAGE42_I10@PURE_QUANTA.SOCKET4677_AZIF0045P001C01CS(CHIPS)':
 'VSS1782': CDS_PINID='VSS1782';
NODE_NAME     U2 V30
 '@S9S_MB_2U_LIB.S9S_MB_2U(SCH_1):PAGE42_I10@PURE_QUANTA.SOCKET4677_AZIF0045P001C01CS(CHIPS)':
 'VSS1783': CDS_PINID='VSS1783';
NODE_NAME     U2 V32
 '@S9S_MB_2U_LIB.S9S_MB_2U(SCH_1):PAGE42_I10@PURE_QUANTA.SOCKET4677_AZIF0045P001C01CS(CHIPS)':
 'VSS1784': CDS_PINID='VSS1784';
NODE_NAME     U2 V34
 '@S9S_MB_2U_LIB.S9S_MB_2U(SCH_1):PAGE42_I10@PURE_QUANTA.SOCKET4677_AZIF0045P001C01CS(CHIPS)':
 'VSS1785': CDS_PINID='VSS1785';
NODE_NAME     U2 V36
 '@S9S_MB_2U_LIB.S9S_MB_2U(SCH_1):PAGE42_I10@PURE_QUANTA.SOCKET4677_AZIF0045P001C01CS(CHIPS)':
 'VSS1786': CDS_PINID='VSS1786';
NODE_NAME     U2 V38
 '@S9S_MB_2U_LIB.S9S_MB_2U(SCH_1):PAGE42_I10@PURE_QUANTA.SOCKET4677_AZIF0045P001C01CS(CHIPS)':
 'VSS1787': CDS_PINID='VSS1787';
NODE_NAME     U2 V4
 '@S9S_MB_2U_LIB.S9S_MB_2U(SCH_1):PAGE42_I10@PURE_QUANTA.SOCKET4677_AZIF0045P001C01CS(CHIPS)':
 'VSS1788': CDS_PINID='VSS1788';
NODE_NAME     U2 V49
 '@S9S_MB_2U_LIB.S9S_MB_2U(SCH_1):PAGE42_I10@PURE_QUANTA.SOCKET4677_AZIF0045P001C01CS(CHIPS)':
 'VSS1789': CDS_PINID='VSS1789';
NODE_NAME     U2 V40
 '@S9S_MB_2U_LIB.S9S_MB_2U(SCH_1):PAGE42_I10@PURE_QUANTA.SOCKET4677_AZIF0045P001C01CS(CHIPS)':
 'VSS1790': CDS_PINID='VSS1790';
NODE_NAME     U2 V42
 '@S9S_MB_2U_LIB.S9S_MB_2U(SCH_1):PAGE42_I10@PURE_QUANTA.SOCKET4677_AZIF0045P001C01CS(CHIPS)':
 'VSS1791': CDS_PINID='VSS1791';
NODE_NAME     U2 V44
 '@S9S_MB_2U_LIB.S9S_MB_2U(SCH_1):PAGE42_I10@PURE_QUANTA.SOCKET4677_AZIF0045P001C01CS(CHIPS)':
 'VSS1792': CDS_PINID='VSS1792';
NODE_NAME     U2 V47
 '@S9S_MB_2U_LIB.S9S_MB_2U(SCH_1):PAGE42_I10@PURE_QUANTA.SOCKET4677_AZIF0045P001C01CS(CHIPS)':
 'VSS1793': CDS_PINID='VSS1793';
NODE_NAME     U2 V51
 '@S9S_MB_2U_LIB.S9S_MB_2U(SCH_1):PAGE42_I10@PURE_QUANTA.SOCKET4677_AZIF0045P001C01CS(CHIPS)':
 'VSS1794': CDS_PINID='VSS1794';
NODE_NAME     U2 V53
 '@S9S_MB_2U_LIB.S9S_MB_2U(SCH_1):PAGE42_I10@PURE_QUANTA.SOCKET4677_AZIF0045P001C01CS(CHIPS)':
 'VSS1795': CDS_PINID='VSS1795';
NODE_NAME     U2 V55
 '@S9S_MB_2U_LIB.S9S_MB_2U(SCH_1):PAGE42_I10@PURE_QUANTA.SOCKET4677_AZIF0045P001C01CS(CHIPS)':
 'VSS1796': CDS_PINID='VSS1796';
NODE_NAME     U2 V57
 '@S9S_MB_2U_LIB.S9S_MB_2U(SCH_1):PAGE42_I10@PURE_QUANTA.SOCKET4677_AZIF0045P001C01CS(CHIPS)':
 'VSS1797': CDS_PINID='VSS1797';
NODE_NAME     U2 V59
 '@S9S_MB_2U_LIB.S9S_MB_2U(SCH_1):PAGE42_I10@PURE_QUANTA.SOCKET4677_AZIF0045P001C01CS(CHIPS)':
 'VSS1798': CDS_PINID='VSS1798';
NODE_NAME     U2 V61
 '@S9S_MB_2U_LIB.S9S_MB_2U(SCH_1):PAGE42_I10@PURE_QUANTA.SOCKET4677_AZIF0045P001C01CS(CHIPS)':
 'VSS1799': CDS_PINID='VSS1799';
NODE_NAME     U2 V71
 '@S9S_MB_2U_LIB.S9S_MB_2U(SCH_1):PAGE42_I10@PURE_QUANTA.SOCKET4677_AZIF0045P001C01CS(CHIPS)':
 'VSS1800': CDS_PINID='VSS1800';
NODE_NAME     U2 V73
 '@S9S_MB_2U_LIB.S9S_MB_2U(SCH_1):PAGE42_I10@PURE_QUANTA.SOCKET4677_AZIF0045P001C01CS(CHIPS)':
 'VSS1801': CDS_PINID='VSS1801';
NODE_NAME     U2 V63
 '@S9S_MB_2U_LIB.S9S_MB_2U(SCH_1):PAGE42_I10@PURE_QUANTA.SOCKET4677_AZIF0045P001C01CS(CHIPS)':
 'VSS1802': CDS_PINID='VSS1802';
NODE_NAME     U2 V65
 '@S9S_MB_2U_LIB.S9S_MB_2U(SCH_1):PAGE42_I10@PURE_QUANTA.SOCKET4677_AZIF0045P001C01CS(CHIPS)':
 'VSS1803': CDS_PINID='VSS1803';
NODE_NAME     U2 V67
 '@S9S_MB_2U_LIB.S9S_MB_2U(SCH_1):PAGE42_I10@PURE_QUANTA.SOCKET4677_AZIF0045P001C01CS(CHIPS)':
 'VSS1804': CDS_PINID='VSS1804';
NODE_NAME     U2 V69
 '@S9S_MB_2U_LIB.S9S_MB_2U(SCH_1):PAGE42_I10@PURE_QUANTA.SOCKET4677_AZIF0045P001C01CS(CHIPS)':
 'VSS1805': CDS_PINID='VSS1805';
NODE_NAME     U2 V75
 '@S9S_MB_2U_LIB.S9S_MB_2U(SCH_1):PAGE42_I10@PURE_QUANTA.SOCKET4677_AZIF0045P001C01CS(CHIPS)':
 'VSS1806': CDS_PINID='VSS1806';
NODE_NAME     U2 V91
 '@S9S_MB_2U_LIB.S9S_MB_2U(SCH_1):PAGE42_I10@PURE_QUANTA.SOCKET4677_AZIF0045P001C01CS(CHIPS)':
 'VSS1807': CDS_PINID='VSS1807';
NODE_NAME     U2 W1
 '@S9S_MB_2U_LIB.S9S_MB_2U(SCH_1):PAGE42_I10@PURE_QUANTA.SOCKET4677_AZIF0045P001C01CS(CHIPS)':
 'VSS1808': CDS_PINID='VSS1808';
NODE_NAME     U2 W13
 '@S9S_MB_2U_LIB.S9S_MB_2U(SCH_1):PAGE42_I10@PURE_QUANTA.SOCKET4677_AZIF0045P001C01CS(CHIPS)':
 'VSS1809': CDS_PINID='VSS1809';
NODE_NAME     U2 V77
 '@S9S_MB_2U_LIB.S9S_MB_2U(SCH_1):PAGE42_I10@PURE_QUANTA.SOCKET4677_AZIF0045P001C01CS(CHIPS)':
 'VSS1810': CDS_PINID='VSS1810';
NODE_NAME     U2 V79
 '@S9S_MB_2U_LIB.S9S_MB_2U(SCH_1):PAGE42_I10@PURE_QUANTA.SOCKET4677_AZIF0045P001C01CS(CHIPS)':
 'VSS1811': CDS_PINID='VSS1811';
NODE_NAME     U2 V8
 '@S9S_MB_2U_LIB.S9S_MB_2U(SCH_1):PAGE42_I10@PURE_QUANTA.SOCKET4677_AZIF0045P001C01CS(CHIPS)':
 'VSS1812': CDS_PINID='VSS1812';
NODE_NAME     U2 V87
 '@S9S_MB_2U_LIB.S9S_MB_2U(SCH_1):PAGE42_I10@PURE_QUANTA.SOCKET4677_AZIF0045P001C01CS(CHIPS)':
 'VSS1813': CDS_PINID='VSS1813';
NODE_NAME     U2 W5
 '@S9S_MB_2U_LIB.S9S_MB_2U(SCH_1):PAGE42_I10@PURE_QUANTA.SOCKET4677_AZIF0045P001C01CS(CHIPS)':
 'VSS1814': CDS_PINID='VSS1814';
NODE_NAME     U2 W52
 '@S9S_MB_2U_LIB.S9S_MB_2U(SCH_1):PAGE42_I10@PURE_QUANTA.SOCKET4677_AZIF0045P001C01CS(CHIPS)':
 'VSS1815': CDS_PINID='VSS1815';
NODE_NAME     U2 W39
 '@S9S_MB_2U_LIB.S9S_MB_2U(SCH_1):PAGE42_I10@PURE_QUANTA.SOCKET4677_AZIF0045P001C01CS(CHIPS)':
 'VSS1816': CDS_PINID='VSS1816';
NODE_NAME     U2 W84
 '@S9S_MB_2U_LIB.S9S_MB_2U(SCH_1):PAGE42_I10@PURE_QUANTA.SOCKET4677_AZIF0045P001C01CS(CHIPS)':
 'VSS1817': CDS_PINID='VSS1817';
NODE_NAME     U2 W88
 '@S9S_MB_2U_LIB.S9S_MB_2U(SCH_1):PAGE42_I10@PURE_QUANTA.SOCKET4677_AZIF0045P001C01CS(CHIPS)':
 'VSS1818': CDS_PINID='VSS1818';
NODE_NAME     U2 W9
 '@S9S_MB_2U_LIB.S9S_MB_2U(SCH_1):PAGE42_I10@PURE_QUANTA.SOCKET4677_AZIF0045P001C01CS(CHIPS)':
 'VSS1819': CDS_PINID='VSS1819';
NODE_NAME     U2 Y12
 '@S9S_MB_2U_LIB.S9S_MB_2U(SCH_1):PAGE42_I10@PURE_QUANTA.SOCKET4677_AZIF0045P001C01CS(CHIPS)':
 'VSS1820': CDS_PINID='VSS1820';
NODE_NAME     U2 Y16
 '@S9S_MB_2U_LIB.S9S_MB_2U(SCH_1):PAGE42_I10@PURE_QUANTA.SOCKET4677_AZIF0045P001C01CS(CHIPS)':
 'VSS1821': CDS_PINID='VSS1821';
NODE_NAME     U2 Y18
 '@S9S_MB_2U_LIB.S9S_MB_2U(SCH_1):PAGE42_I10@PURE_QUANTA.SOCKET4677_AZIF0045P001C01CS(CHIPS)':
 'VSS1822': CDS_PINID='VSS1822';
NODE_NAME     U2 Y24
 '@S9S_MB_2U_LIB.S9S_MB_2U(SCH_1):PAGE42_I10@PURE_QUANTA.SOCKET4677_AZIF0045P001C01CS(CHIPS)':
 'VSS1823': CDS_PINID='VSS1823';
NODE_NAME     U2 Y30
 '@S9S_MB_2U_LIB.S9S_MB_2U(SCH_1):PAGE42_I10@PURE_QUANTA.SOCKET4677_AZIF0045P001C01CS(CHIPS)':
 'VSS1824': CDS_PINID='VSS1824';
NODE_NAME     U2 Y36
 '@S9S_MB_2U_LIB.S9S_MB_2U(SCH_1):PAGE42_I10@PURE_QUANTA.SOCKET4677_AZIF0045P001C01CS(CHIPS)':
 'VSS1825': CDS_PINID='VSS1825';
NODE_NAME     U2 Y4
 '@S9S_MB_2U_LIB.S9S_MB_2U(SCH_1):PAGE42_I10@PURE_QUANTA.SOCKET4677_AZIF0045P001C01CS(CHIPS)':
 'VSS1826': CDS_PINID='VSS1826';
NODE_NAME     U2 Y42
 '@S9S_MB_2U_LIB.S9S_MB_2U(SCH_1):PAGE42_I10@PURE_QUANTA.SOCKET4677_AZIF0045P001C01CS(CHIPS)':
 'VSS1827': CDS_PINID='VSS1827';
NODE_NAME     U2 Y61
 '@S9S_MB_2U_LIB.S9S_MB_2U(SCH_1):PAGE42_I10@PURE_QUANTA.SOCKET4677_AZIF0045P001C01CS(CHIPS)':
 'VSS1828': CDS_PINID='VSS1828';
NODE_NAME     U2 Y67
 '@S9S_MB_2U_LIB.S9S_MB_2U(SCH_1):PAGE42_I10@PURE_QUANTA.SOCKET4677_AZIF0045P001C01CS(CHIPS)':
 'VSS1829': CDS_PINID='VSS1829';
NODE_NAME     U2 Y49
 '@S9S_MB_2U_LIB.S9S_MB_2U(SCH_1):PAGE42_I10@PURE_QUANTA.SOCKET4677_AZIF0045P001C01CS(CHIPS)':
 'VSS1830': CDS_PINID='VSS1830';
NODE_NAME     U2 Y55
 '@S9S_MB_2U_LIB.S9S_MB_2U(SCH_1):PAGE42_I10@PURE_QUANTA.SOCKET4677_AZIF0045P001C01CS(CHIPS)':
 'VSS1831': CDS_PINID='VSS1831';
NODE_NAME     U2 Y8
 '@S9S_MB_2U_LIB.S9S_MB_2U(SCH_1):PAGE42_I10@PURE_QUANTA.SOCKET4677_AZIF0045P001C01CS(CHIPS)':
 'VSS1832': CDS_PINID='VSS1832';
NODE_NAME     U2 Y73
 '@S9S_MB_2U_LIB.S9S_MB_2U(SCH_1):PAGE42_I10@PURE_QUANTA.SOCKET4677_AZIF0045P001C01CS(CHIPS)':
 'VSS1833': CDS_PINID='VSS1833';
NODE_NAME     U2 E52
 '@S9S_MB_2U_LIB.S9S_MB_2U(SCH_1):PAGE42_I11@PURE_QUANTA.SOCKET4677_AZIF0045P001C01CS(CHIPS)':
 'VSS1126': CDS_PINID='VSS1126';
NODE_NAME     U2 E74
 '@S9S_MB_2U_LIB.S9S_MB_2U(SCH_1):PAGE42_I11@PURE_QUANTA.SOCKET4677_AZIF0045P001C01CS(CHIPS)':
 'VSS1129': CDS_PINID='VSS1129';
NODE_NAME     U2 E78
 '@S9S_MB_2U_LIB.S9S_MB_2U(SCH_1):PAGE42_I11@PURE_QUANTA.SOCKET4677_AZIF0045P001C01CS(CHIPS)':
 'VSS1131': CDS_PINID='VSS1131';
NODE_NAME     U2 E76
 '@S9S_MB_2U_LIB.S9S_MB_2U(SCH_1):PAGE42_I11@PURE_QUANTA.SOCKET4677_AZIF0045P001C01CS(CHIPS)':
 'VSS1272': CDS_PINID='VSS1272';
NODE_NAME     U2 E86
 '@S9S_MB_2U_LIB.S9S_MB_2U(SCH_1):PAGE42_I11@PURE_QUANTA.SOCKET4677_AZIF0045P001C01CS(CHIPS)':
 'VSS1273': CDS_PINID='VSS1273';
NODE_NAME     U2 F12
 '@S9S_MB_2U_LIB.S9S_MB_2U(SCH_1):PAGE42_I11@PURE_QUANTA.SOCKET4677_AZIF0045P001C01CS(CHIPS)':
 'VSS1494': CDS_PINID='VSS1494';
NODE_NAME     U2 F18
 '@S9S_MB_2U_LIB.S9S_MB_2U(SCH_1):PAGE42_I11@PURE_QUANTA.SOCKET4677_AZIF0045P001C01CS(CHIPS)':
 'VSS1495': CDS_PINID='VSS1495';
NODE_NAME     U2 F42
 '@S9S_MB_2U_LIB.S9S_MB_2U(SCH_1):PAGE42_I11@PURE_QUANTA.SOCKET4677_AZIF0045P001C01CS(CHIPS)':
 'VSS1502': CDS_PINID='VSS1502';
NODE_NAME     U2 F55
 '@S9S_MB_2U_LIB.S9S_MB_2U(SCH_1):PAGE42_I11@PURE_QUANTA.SOCKET4677_AZIF0045P001C01CS(CHIPS)':
 'VSS1504': CDS_PINID='VSS1504';
NODE_NAME     U2 F6
 '@S9S_MB_2U_LIB.S9S_MB_2U(SCH_1):PAGE42_I11@PURE_QUANTA.SOCKET4677_AZIF0045P001C01CS(CHIPS)':
 'VSS1507': CDS_PINID='VSS1507';
NODE_NAME     U2 F61
 '@S9S_MB_2U_LIB.S9S_MB_2U(SCH_1):PAGE42_I11@PURE_QUANTA.SOCKET4677_AZIF0045P001C01CS(CHIPS)':
 'VSS1508': CDS_PINID='VSS1508';
NODE_NAME     U2 F67
 '@S9S_MB_2U_LIB.S9S_MB_2U(SCH_1):PAGE42_I11@PURE_QUANTA.SOCKET4677_AZIF0045P001C01CS(CHIPS)':
 'VSS1509': CDS_PINID='VSS1509';
NODE_NAME     U2 F73
 '@S9S_MB_2U_LIB.S9S_MB_2U(SCH_1):PAGE42_I11@PURE_QUANTA.SOCKET4677_AZIF0045P001C01CS(CHIPS)':
 'VSS1510': CDS_PINID='VSS1510';
NODE_NAME     U2 F79
 '@S9S_MB_2U_LIB.S9S_MB_2U(SCH_1):PAGE42_I11@PURE_QUANTA.SOCKET4677_AZIF0045P001C01CS(CHIPS)':
 'VSS1511': CDS_PINID='VSS1511';
NODE_NAME     U2 G11
 '@S9S_MB_2U_LIB.S9S_MB_2U(SCH_1):PAGE42_I11@PURE_QUANTA.SOCKET4677_AZIF0045P001C01CS(CHIPS)':
 'VSS1514': CDS_PINID='VSS1514';
NODE_NAME     U2 G17
 '@S9S_MB_2U_LIB.S9S_MB_2U(SCH_1):PAGE42_I11@PURE_QUANTA.SOCKET4677_AZIF0045P001C01CS(CHIPS)':
 'VSS1516': CDS_PINID='VSS1516';
NODE_NAME     U2 G25
 '@S9S_MB_2U_LIB.S9S_MB_2U(SCH_1):PAGE42_I11@PURE_QUANTA.SOCKET4677_AZIF0045P001C01CS(CHIPS)':
 'VSS1519': CDS_PINID='VSS1519';
NODE_NAME     U2 G3
 '@S9S_MB_2U_LIB.S9S_MB_2U(SCH_1):PAGE42_I11@PURE_QUANTA.SOCKET4677_AZIF0045P001C01CS(CHIPS)':
 'VSS1521': CDS_PINID='VSS1521';
NODE_NAME     U2 G35
 '@S9S_MB_2U_LIB.S9S_MB_2U(SCH_1):PAGE42_I11@PURE_QUANTA.SOCKET4677_AZIF0045P001C01CS(CHIPS)':
 'VSS1523': CDS_PINID='VSS1523';
NODE_NAME     U2 G48
 '@S9S_MB_2U_LIB.S9S_MB_2U(SCH_1):PAGE42_I11@PURE_QUANTA.SOCKET4677_AZIF0045P001C01CS(CHIPS)':
 'VSS1527': CDS_PINID='VSS1527';
NODE_NAME     U2 G60
 '@S9S_MB_2U_LIB.S9S_MB_2U(SCH_1):PAGE42_I11@PURE_QUANTA.SOCKET4677_AZIF0045P001C01CS(CHIPS)':
 'VSS1532': CDS_PINID='VSS1532';
NODE_NAME     U2 G66
 '@S9S_MB_2U_LIB.S9S_MB_2U(SCH_1):PAGE42_I11@PURE_QUANTA.SOCKET4677_AZIF0045P001C01CS(CHIPS)':
 'VSS1534': CDS_PINID='VSS1534';
NODE_NAME     U2 G68
 '@S9S_MB_2U_LIB.S9S_MB_2U(SCH_1):PAGE42_I11@PURE_QUANTA.SOCKET4677_AZIF0045P001C01CS(CHIPS)':
 'VSS1535': CDS_PINID='VSS1535';
NODE_NAME     U2 G7
 '@S9S_MB_2U_LIB.S9S_MB_2U(SCH_1):PAGE42_I11@PURE_QUANTA.SOCKET4677_AZIF0045P001C01CS(CHIPS)':
 'VSS1536': CDS_PINID='VSS1536';
NODE_NAME     U2 G74
 '@S9S_MB_2U_LIB.S9S_MB_2U(SCH_1):PAGE42_I11@PURE_QUANTA.SOCKET4677_AZIF0045P001C01CS(CHIPS)':
 'VSS1538': CDS_PINID='VSS1538';
NODE_NAME     U2 H14
 '@S9S_MB_2U_LIB.S9S_MB_2U(SCH_1):PAGE42_I11@PURE_QUANTA.SOCKET4677_AZIF0045P001C01CS(CHIPS)':
 'VSS1544': CDS_PINID='VSS1544';
NODE_NAME     U2 H2
 '@S9S_MB_2U_LIB.S9S_MB_2U(SCH_1):PAGE42_I11@PURE_QUANTA.SOCKET4677_AZIF0045P001C01CS(CHIPS)':
 'VSS1546': CDS_PINID='VSS1546';
NODE_NAME     U2 H51
 '@S9S_MB_2U_LIB.S9S_MB_2U(SCH_1):PAGE42_I11@PURE_QUANTA.SOCKET4677_AZIF0045P001C01CS(CHIPS)':
 'VSS1558': CDS_PINID='VSS1558';
NODE_NAME     U2 H57
 '@S9S_MB_2U_LIB.S9S_MB_2U(SCH_1):PAGE42_I11@PURE_QUANTA.SOCKET4677_AZIF0045P001C01CS(CHIPS)':
 'VSS1560': CDS_PINID='VSS1560';
NODE_NAME     U2 H65
 '@S9S_MB_2U_LIB.S9S_MB_2U(SCH_1):PAGE42_I11@PURE_QUANTA.SOCKET4677_AZIF0045P001C01CS(CHIPS)':
 'VSS1564': CDS_PINID='VSS1564';
NODE_NAME     U2 H75
 '@S9S_MB_2U_LIB.S9S_MB_2U(SCH_1):PAGE42_I11@PURE_QUANTA.SOCKET4677_AZIF0045P001C01CS(CHIPS)':
 'VSS1567': CDS_PINID='VSS1567';
NODE_NAME     U2 F24
 '@S9S_MB_2U_LIB.S9S_MB_2U(SCH_1):PAGE42_I11@PURE_QUANTA.SOCKET4677_AZIF0045P001C01CS(CHIPS)':
 'VSS1570': CDS_PINID='VSS1570';
NODE_NAME     U2 F30
 '@S9S_MB_2U_LIB.S9S_MB_2U(SCH_1):PAGE42_I11@PURE_QUANTA.SOCKET4677_AZIF0045P001C01CS(CHIPS)':
 'VSS1571': CDS_PINID='VSS1571';
NODE_NAME     U2 F36
 '@S9S_MB_2U_LIB.S9S_MB_2U(SCH_1):PAGE42_I11@PURE_QUANTA.SOCKET4677_AZIF0045P001C01CS(CHIPS)':
 'VSS1572': CDS_PINID='VSS1572';
NODE_NAME     U2 F4
 '@S9S_MB_2U_LIB.S9S_MB_2U(SCH_1):PAGE42_I11@PURE_QUANTA.SOCKET4677_AZIF0045P001C01CS(CHIPS)':
 'VSS1573': CDS_PINID='VSS1573';
NODE_NAME     U2 F49
 '@S9S_MB_2U_LIB.S9S_MB_2U(SCH_1):PAGE42_I11@PURE_QUANTA.SOCKET4677_AZIF0045P001C01CS(CHIPS)':
 'VSS1574': CDS_PINID='VSS1574';
NODE_NAME     U2 J21
 '@S9S_MB_2U_LIB.S9S_MB_2U(SCH_1):PAGE42_I11@PURE_QUANTA.SOCKET4677_AZIF0045P001C01CS(CHIPS)':
 'VSS1575': CDS_PINID='VSS1575';
NODE_NAME     U2 F83
 '@S9S_MB_2U_LIB.S9S_MB_2U(SCH_1):PAGE42_I11@PURE_QUANTA.SOCKET4677_AZIF0045P001C01CS(CHIPS)':
 'VSS1576': CDS_PINID='VSS1576';
NODE_NAME     U2 F89
 '@S9S_MB_2U_LIB.S9S_MB_2U(SCH_1):PAGE42_I11@PURE_QUANTA.SOCKET4677_AZIF0045P001C01CS(CHIPS)':
 'VSS1577': CDS_PINID='VSS1577';
NODE_NAME     U2 G13
 '@S9S_MB_2U_LIB.S9S_MB_2U(SCH_1):PAGE42_I11@PURE_QUANTA.SOCKET4677_AZIF0045P001C01CS(CHIPS)':
 'VSS1578': CDS_PINID='VSS1578';
NODE_NAME     U2 G19
 '@S9S_MB_2U_LIB.S9S_MB_2U(SCH_1):PAGE42_I11@PURE_QUANTA.SOCKET4677_AZIF0045P001C01CS(CHIPS)':
 'VSS1579': CDS_PINID='VSS1579';
NODE_NAME     U2 J39
 '@S9S_MB_2U_LIB.S9S_MB_2U(SCH_1):PAGE42_I11@PURE_QUANTA.SOCKET4677_AZIF0045P001C01CS(CHIPS)':
 'VSS1580': CDS_PINID='VSS1580';
NODE_NAME     U2 G23
 '@S9S_MB_2U_LIB.S9S_MB_2U(SCH_1):PAGE42_I11@PURE_QUANTA.SOCKET4677_AZIF0045P001C01CS(CHIPS)':
 'VSS1581': CDS_PINID='VSS1581';
NODE_NAME     U2 J5
 '@S9S_MB_2U_LIB.S9S_MB_2U(SCH_1):PAGE42_I11@PURE_QUANTA.SOCKET4677_AZIF0045P001C01CS(CHIPS)':
 'VSS1582': CDS_PINID='VSS1582';
NODE_NAME     U2 G29
 '@S9S_MB_2U_LIB.S9S_MB_2U(SCH_1):PAGE42_I11@PURE_QUANTA.SOCKET4677_AZIF0045P001C01CS(CHIPS)':
 'VSS1583': CDS_PINID='VSS1583';
NODE_NAME     U2 G31
 '@S9S_MB_2U_LIB.S9S_MB_2U(SCH_1):PAGE42_I11@PURE_QUANTA.SOCKET4677_AZIF0045P001C01CS(CHIPS)':
 'VSS1584': CDS_PINID='VSS1584';
NODE_NAME     U2 G37
 '@S9S_MB_2U_LIB.S9S_MB_2U(SCH_1):PAGE42_I11@PURE_QUANTA.SOCKET4677_AZIF0045P001C01CS(CHIPS)':
 'VSS1585': CDS_PINID='VSS1585';
NODE_NAME     U2 G41
 '@S9S_MB_2U_LIB.S9S_MB_2U(SCH_1):PAGE42_I11@PURE_QUANTA.SOCKET4677_AZIF0045P001C01CS(CHIPS)':
 'VSS1586': CDS_PINID='VSS1586';
NODE_NAME     U2 J64
 '@S9S_MB_2U_LIB.S9S_MB_2U(SCH_1):PAGE42_I11@PURE_QUANTA.SOCKET4677_AZIF0045P001C01CS(CHIPS)':
 'VSS1587': CDS_PINID='VSS1587';
NODE_NAME     U2 G43
 '@S9S_MB_2U_LIB.S9S_MB_2U(SCH_1):PAGE42_I11@PURE_QUANTA.SOCKET4677_AZIF0045P001C01CS(CHIPS)':
 'VSS1588': CDS_PINID='VSS1588';
NODE_NAME     U2 J70
 '@S9S_MB_2U_LIB.S9S_MB_2U(SCH_1):PAGE42_I11@PURE_QUANTA.SOCKET4677_AZIF0045P001C01CS(CHIPS)':
 'VSS1589': CDS_PINID='VSS1589';
NODE_NAME     U2 G50
 '@S9S_MB_2U_LIB.S9S_MB_2U(SCH_1):PAGE42_I11@PURE_QUANTA.SOCKET4677_AZIF0045P001C01CS(CHIPS)':
 'VSS1590': CDS_PINID='VSS1590';
NODE_NAME     U2 G54
 '@S9S_MB_2U_LIB.S9S_MB_2U(SCH_1):PAGE42_I11@PURE_QUANTA.SOCKET4677_AZIF0045P001C01CS(CHIPS)':
 'VSS1591': CDS_PINID='VSS1591';
NODE_NAME     U2 G56
 '@S9S_MB_2U_LIB.S9S_MB_2U(SCH_1):PAGE42_I11@PURE_QUANTA.SOCKET4677_AZIF0045P001C01CS(CHIPS)':
 'VSS1592': CDS_PINID='VSS1592';
NODE_NAME     U2 G62
 '@S9S_MB_2U_LIB.S9S_MB_2U(SCH_1):PAGE42_I11@PURE_QUANTA.SOCKET4677_AZIF0045P001C01CS(CHIPS)':
 'VSS1593': CDS_PINID='VSS1593';
NODE_NAME     U2 G72
 '@S9S_MB_2U_LIB.S9S_MB_2U(SCH_1):PAGE42_I11@PURE_QUANTA.SOCKET4677_AZIF0045P001C01CS(CHIPS)':
 'VSS1594': CDS_PINID='VSS1594';
NODE_NAME     U2 J88
 '@S9S_MB_2U_LIB.S9S_MB_2U(SCH_1):PAGE42_I11@PURE_QUANTA.SOCKET4677_AZIF0045P001C01CS(CHIPS)':
 'VSS1595': CDS_PINID='VSS1595';
NODE_NAME     U2 J9
 '@S9S_MB_2U_LIB.S9S_MB_2U(SCH_1):PAGE42_I11@PURE_QUANTA.SOCKET4677_AZIF0045P001C01CS(CHIPS)':
 'VSS1596': CDS_PINID='VSS1596';
NODE_NAME     U2 K12
 '@S9S_MB_2U_LIB.S9S_MB_2U(SCH_1):PAGE42_I11@PURE_QUANTA.SOCKET4677_AZIF0045P001C01CS(CHIPS)':
 'VSS1597': CDS_PINID='VSS1597';
NODE_NAME     U2 K14
 '@S9S_MB_2U_LIB.S9S_MB_2U(SCH_1):PAGE42_I11@PURE_QUANTA.SOCKET4677_AZIF0045P001C01CS(CHIPS)':
 'VSS1598': CDS_PINID='VSS1598';
NODE_NAME     U2 K2
 '@S9S_MB_2U_LIB.S9S_MB_2U(SCH_1):PAGE42_I11@PURE_QUANTA.SOCKET4677_AZIF0045P001C01CS(CHIPS)':
 'VSS1599': CDS_PINID='VSS1599';
NODE_NAME     U2 G84
 '@S9S_MB_2U_LIB.S9S_MB_2U(SCH_1):PAGE42_I11@PURE_QUANTA.SOCKET4677_AZIF0045P001C01CS(CHIPS)':
 'VSS1600': CDS_PINID='VSS1600';
NODE_NAME     U2 G88
 '@S9S_MB_2U_LIB.S9S_MB_2U(SCH_1):PAGE42_I11@PURE_QUANTA.SOCKET4677_AZIF0045P001C01CS(CHIPS)':
 'VSS1601': CDS_PINID='VSS1601';
NODE_NAME     U2 K42
 '@S9S_MB_2U_LIB.S9S_MB_2U(SCH_1):PAGE42_I11@PURE_QUANTA.SOCKET4677_AZIF0045P001C01CS(CHIPS)':
 'VSS1602': CDS_PINID='VSS1602';
NODE_NAME     U2 K49
 '@S9S_MB_2U_LIB.S9S_MB_2U(SCH_1):PAGE42_I11@PURE_QUANTA.SOCKET4677_AZIF0045P001C01CS(CHIPS)':
 'VSS1603': CDS_PINID='VSS1603';
NODE_NAME     U2 G90
 '@S9S_MB_2U_LIB.S9S_MB_2U(SCH_1):PAGE42_I11@PURE_QUANTA.SOCKET4677_AZIF0045P001C01CS(CHIPS)':
 'VSS1604': CDS_PINID='VSS1604';
NODE_NAME     U2 H10
 '@S9S_MB_2U_LIB.S9S_MB_2U(SCH_1):PAGE42_I11@PURE_QUANTA.SOCKET4677_AZIF0045P001C01CS(CHIPS)':
 'VSS1605': CDS_PINID='VSS1605';
NODE_NAME     U2 H16
 '@S9S_MB_2U_LIB.S9S_MB_2U(SCH_1):PAGE42_I11@PURE_QUANTA.SOCKET4677_AZIF0045P001C01CS(CHIPS)':
 'VSS1606': CDS_PINID='VSS1606';
NODE_NAME     U2 H20
 '@S9S_MB_2U_LIB.S9S_MB_2U(SCH_1):PAGE42_I11@PURE_QUANTA.SOCKET4677_AZIF0045P001C01CS(CHIPS)':
 'VSS1607': CDS_PINID='VSS1607';
NODE_NAME     U2 H22
 '@S9S_MB_2U_LIB.S9S_MB_2U(SCH_1):PAGE42_I11@PURE_QUANTA.SOCKET4677_AZIF0045P001C01CS(CHIPS)':
 'VSS1608': CDS_PINID='VSS1608';
NODE_NAME     U2 H26
 '@S9S_MB_2U_LIB.S9S_MB_2U(SCH_1):PAGE42_I11@PURE_QUANTA.SOCKET4677_AZIF0045P001C01CS(CHIPS)':
 'VSS1609': CDS_PINID='VSS1609';
NODE_NAME     U2 H28
 '@S9S_MB_2U_LIB.S9S_MB_2U(SCH_1):PAGE42_I11@PURE_QUANTA.SOCKET4677_AZIF0045P001C01CS(CHIPS)':
 'VSS1610': CDS_PINID='VSS1610';
NODE_NAME     U2 H32
 '@S9S_MB_2U_LIB.S9S_MB_2U(SCH_1):PAGE42_I11@PURE_QUANTA.SOCKET4677_AZIF0045P001C01CS(CHIPS)':
 'VSS1611': CDS_PINID='VSS1611';
NODE_NAME     U2 H34
 '@S9S_MB_2U_LIB.S9S_MB_2U(SCH_1):PAGE42_I11@PURE_QUANTA.SOCKET4677_AZIF0045P001C01CS(CHIPS)':
 'VSS1612': CDS_PINID='VSS1612';
NODE_NAME     U2 H38
 '@S9S_MB_2U_LIB.S9S_MB_2U(SCH_1):PAGE42_I11@PURE_QUANTA.SOCKET4677_AZIF0045P001C01CS(CHIPS)':
 'VSS1613': CDS_PINID='VSS1613';
NODE_NAME     U2 L19
 '@S9S_MB_2U_LIB.S9S_MB_2U(SCH_1):PAGE42_I11@PURE_QUANTA.SOCKET4677_AZIF0045P001C01CS(CHIPS)':
 'VSS1614': CDS_PINID='VSS1614';
NODE_NAME     U2 H4
 '@S9S_MB_2U_LIB.S9S_MB_2U(SCH_1):PAGE42_I11@PURE_QUANTA.SOCKET4677_AZIF0045P001C01CS(CHIPS)':
 'VSS1615': CDS_PINID='VSS1615';
NODE_NAME     U2 H40
 '@S9S_MB_2U_LIB.S9S_MB_2U(SCH_1):PAGE42_I11@PURE_QUANTA.SOCKET4677_AZIF0045P001C01CS(CHIPS)':
 'VSS1616': CDS_PINID='VSS1616';
NODE_NAME     U2 H44
 '@S9S_MB_2U_LIB.S9S_MB_2U(SCH_1):PAGE42_I11@PURE_QUANTA.SOCKET4677_AZIF0045P001C01CS(CHIPS)':
 'VSS1617': CDS_PINID='VSS1617';
NODE_NAME     U2 H47
 '@S9S_MB_2U_LIB.S9S_MB_2U(SCH_1):PAGE42_I11@PURE_QUANTA.SOCKET4677_AZIF0045P001C01CS(CHIPS)':
 'VSS1618': CDS_PINID='VSS1618';
NODE_NAME     U2 H53
 '@S9S_MB_2U_LIB.S9S_MB_2U(SCH_1):PAGE42_I11@PURE_QUANTA.SOCKET4677_AZIF0045P001C01CS(CHIPS)':
 'VSS1619': CDS_PINID='VSS1619';
NODE_NAME     U2 H59
 '@S9S_MB_2U_LIB.S9S_MB_2U(SCH_1):PAGE42_I11@PURE_QUANTA.SOCKET4677_AZIF0045P001C01CS(CHIPS)':
 'VSS1620': CDS_PINID='VSS1620';
NODE_NAME     U2 H6
 '@S9S_MB_2U_LIB.S9S_MB_2U(SCH_1):PAGE42_I11@PURE_QUANTA.SOCKET4677_AZIF0045P001C01CS(CHIPS)':
 'VSS1621': CDS_PINID='VSS1621';
NODE_NAME     U2 H63
 '@S9S_MB_2U_LIB.S9S_MB_2U(SCH_1):PAGE42_I11@PURE_QUANTA.SOCKET4677_AZIF0045P001C01CS(CHIPS)':
 'VSS1622': CDS_PINID='VSS1622';
NODE_NAME     U2 H69
 '@S9S_MB_2U_LIB.S9S_MB_2U(SCH_1):PAGE42_I11@PURE_QUANTA.SOCKET4677_AZIF0045P001C01CS(CHIPS)':
 'VSS1623': CDS_PINID='VSS1623';
NODE_NAME     U2 H71
 '@S9S_MB_2U_LIB.S9S_MB_2U(SCH_1):PAGE42_I11@PURE_QUANTA.SOCKET4677_AZIF0045P001C01CS(CHIPS)':
 'VSS1624': CDS_PINID='VSS1624';
NODE_NAME     U2 H79
 '@S9S_MB_2U_LIB.S9S_MB_2U(SCH_1):PAGE42_I11@PURE_QUANTA.SOCKET4677_AZIF0045P001C01CS(CHIPS)':
 'VSS1625': CDS_PINID='VSS1625';
NODE_NAME     U2 H8
 '@S9S_MB_2U_LIB.S9S_MB_2U(SCH_1):PAGE42_I11@PURE_QUANTA.SOCKET4677_AZIF0045P001C01CS(CHIPS)':
 'VSS1626': CDS_PINID='VSS1626';
NODE_NAME     U2 H81
 '@S9S_MB_2U_LIB.S9S_MB_2U(SCH_1):PAGE42_I11@PURE_QUANTA.SOCKET4677_AZIF0045P001C01CS(CHIPS)':
 'VSS1627': CDS_PINID='VSS1627';
NODE_NAME     U2 J15
 '@S9S_MB_2U_LIB.S9S_MB_2U(SCH_1):PAGE42_I11@PURE_QUANTA.SOCKET4677_AZIF0045P001C01CS(CHIPS)':
 'VSS1628': CDS_PINID='VSS1628';
NODE_NAME     U2 J27
 '@S9S_MB_2U_LIB.S9S_MB_2U(SCH_1):PAGE42_I11@PURE_QUANTA.SOCKET4677_AZIF0045P001C01CS(CHIPS)':
 'VSS1629': CDS_PINID='VSS1629';
NODE_NAME     U2 J33
 '@S9S_MB_2U_LIB.S9S_MB_2U(SCH_1):PAGE42_I11@PURE_QUANTA.SOCKET4677_AZIF0045P001C01CS(CHIPS)':
 'VSS1630': CDS_PINID='VSS1630';
NODE_NAME     U2 J45
 '@S9S_MB_2U_LIB.S9S_MB_2U(SCH_1):PAGE42_I11@PURE_QUANTA.SOCKET4677_AZIF0045P001C01CS(CHIPS)':
 'VSS1631': CDS_PINID='VSS1631';
NODE_NAME     U2 J52
 '@S9S_MB_2U_LIB.S9S_MB_2U(SCH_1):PAGE42_I11@PURE_QUANTA.SOCKET4677_AZIF0045P001C01CS(CHIPS)':
 'VSS1632': CDS_PINID='VSS1632';
NODE_NAME     U2 J58
 '@S9S_MB_2U_LIB.S9S_MB_2U(SCH_1):PAGE42_I11@PURE_QUANTA.SOCKET4677_AZIF0045P001C01CS(CHIPS)':
 'VSS1633': CDS_PINID='VSS1633';
NODE_NAME     U2 L58
 '@S9S_MB_2U_LIB.S9S_MB_2U(SCH_1):PAGE42_I11@PURE_QUANTA.SOCKET4677_AZIF0045P001C01CS(CHIPS)':
 'VSS1634': CDS_PINID='VSS1634';
NODE_NAME     U2 J76
 '@S9S_MB_2U_LIB.S9S_MB_2U(SCH_1):PAGE42_I11@PURE_QUANTA.SOCKET4677_AZIF0045P001C01CS(CHIPS)':
 'VSS1635': CDS_PINID='VSS1635';
NODE_NAME     U2 J78
 '@S9S_MB_2U_LIB.S9S_MB_2U(SCH_1):PAGE42_I11@PURE_QUANTA.SOCKET4677_AZIF0045P001C01CS(CHIPS)':
 'VSS1636': CDS_PINID='VSS1636';
NODE_NAME     U2 J84
 '@S9S_MB_2U_LIB.S9S_MB_2U(SCH_1):PAGE42_I11@PURE_QUANTA.SOCKET4677_AZIF0045P001C01CS(CHIPS)':
 'VSS1637': CDS_PINID='VSS1637';
NODE_NAME     U2 J86
 '@S9S_MB_2U_LIB.S9S_MB_2U(SCH_1):PAGE42_I11@PURE_QUANTA.SOCKET4677_AZIF0045P001C01CS(CHIPS)':
 'VSS1638': CDS_PINID='VSS1638';
NODE_NAME     U2 K77
 '@S9S_MB_2U_LIB.S9S_MB_2U(SCH_1):PAGE42_I11@PURE_QUANTA.SOCKET4677_AZIF0045P001C01CS(CHIPS)':
 'VSS1639': CDS_PINID='VSS1639';
NODE_NAME     U2 L70
 '@S9S_MB_2U_LIB.S9S_MB_2U(SCH_1):PAGE42_I11@PURE_QUANTA.SOCKET4677_AZIF0045P001C01CS(CHIPS)':
 'VSS1640': CDS_PINID='VSS1640';
NODE_NAME     U2 K8
 '@S9S_MB_2U_LIB.S9S_MB_2U(SCH_1):PAGE42_I11@PURE_QUANTA.SOCKET4677_AZIF0045P001C01CS(CHIPS)':
 'VSS1641': CDS_PINID='VSS1641';
NODE_NAME     U2 K83
 '@S9S_MB_2U_LIB.S9S_MB_2U(SCH_1):PAGE42_I11@PURE_QUANTA.SOCKET4677_AZIF0045P001C01CS(CHIPS)':
 'VSS1642': CDS_PINID='VSS1642';
NODE_NAME     U2 K85
 '@S9S_MB_2U_LIB.S9S_MB_2U(SCH_1):PAGE42_I11@PURE_QUANTA.SOCKET4677_AZIF0045P001C01CS(CHIPS)':
 'VSS1643': CDS_PINID='VSS1643';
NODE_NAME     U2 L13
 '@S9S_MB_2U_LIB.S9S_MB_2U(SCH_1):PAGE42_I11@PURE_QUANTA.SOCKET4677_AZIF0045P001C01CS(CHIPS)':
 'VSS1644': CDS_PINID='VSS1644';
NODE_NAME     U2 L15
 '@S9S_MB_2U_LIB.S9S_MB_2U(SCH_1):PAGE42_I11@PURE_QUANTA.SOCKET4677_AZIF0045P001C01CS(CHIPS)':
 'VSS1645': CDS_PINID='VSS1645';
NODE_NAME     U2 L88
 '@S9S_MB_2U_LIB.S9S_MB_2U(SCH_1):PAGE42_I11@PURE_QUANTA.SOCKET4677_AZIF0045P001C01CS(CHIPS)':
 'VSS1646': CDS_PINID='VSS1646';
NODE_NAME     U2 L9
 '@S9S_MB_2U_LIB.S9S_MB_2U(SCH_1):PAGE42_I11@PURE_QUANTA.SOCKET4677_AZIF0045P001C01CS(CHIPS)':
 'VSS1647': CDS_PINID='VSS1647';
NODE_NAME     U2 L90
 '@S9S_MB_2U_LIB.S9S_MB_2U(SCH_1):PAGE42_I11@PURE_QUANTA.SOCKET4677_AZIF0045P001C01CS(CHIPS)':
 'VSS1648': CDS_PINID='VSS1648';
NODE_NAME     U2 M12
 '@S9S_MB_2U_LIB.S9S_MB_2U(SCH_1):PAGE42_I11@PURE_QUANTA.SOCKET4677_AZIF0045P001C01CS(CHIPS)':
 'VSS1649': CDS_PINID='VSS1649';
NODE_NAME     U2 L17
 '@S9S_MB_2U_LIB.S9S_MB_2U(SCH_1):PAGE42_I11@PURE_QUANTA.SOCKET4677_AZIF0045P001C01CS(CHIPS)':
 'VSS1650': CDS_PINID='VSS1650';
NODE_NAME     U2 L21
 '@S9S_MB_2U_LIB.S9S_MB_2U(SCH_1):PAGE42_I11@PURE_QUANTA.SOCKET4677_AZIF0045P001C01CS(CHIPS)':
 'VSS1651': CDS_PINID='VSS1651';
NODE_NAME     U2 M4
 '@S9S_MB_2U_LIB.S9S_MB_2U(SCH_1):PAGE42_I11@PURE_QUANTA.SOCKET4677_AZIF0045P001C01CS(CHIPS)':
 'VSS1652': CDS_PINID='VSS1652';
NODE_NAME     U2 M42
 '@S9S_MB_2U_LIB.S9S_MB_2U(SCH_1):PAGE42_I11@PURE_QUANTA.SOCKET4677_AZIF0045P001C01CS(CHIPS)':
 'VSS1653': CDS_PINID='VSS1653';
NODE_NAME     U2 M49
 '@S9S_MB_2U_LIB.S9S_MB_2U(SCH_1):PAGE42_I11@PURE_QUANTA.SOCKET4677_AZIF0045P001C01CS(CHIPS)':
 'VSS1654': CDS_PINID='VSS1654';
NODE_NAME     U2 L23
 '@S9S_MB_2U_LIB.S9S_MB_2U(SCH_1):PAGE42_I11@PURE_QUANTA.SOCKET4677_AZIF0045P001C01CS(CHIPS)':
 'VSS1655': CDS_PINID='VSS1655';
NODE_NAME     U2 L25
 '@S9S_MB_2U_LIB.S9S_MB_2U(SCH_1):PAGE42_I11@PURE_QUANTA.SOCKET4677_AZIF0045P001C01CS(CHIPS)':
 'VSS1656': CDS_PINID='VSS1656';
NODE_NAME     U2 M8
 '@S9S_MB_2U_LIB.S9S_MB_2U(SCH_1):PAGE42_I11@PURE_QUANTA.SOCKET4677_AZIF0045P001C01CS(CHIPS)':
 'VSS1657': CDS_PINID='VSS1657';
NODE_NAME     U2 L27
 '@S9S_MB_2U_LIB.S9S_MB_2U(SCH_1):PAGE42_I11@PURE_QUANTA.SOCKET4677_AZIF0045P001C01CS(CHIPS)':
 'VSS1658': CDS_PINID='VSS1658';
NODE_NAME     U2 L29
 '@S9S_MB_2U_LIB.S9S_MB_2U(SCH_1):PAGE42_I11@PURE_QUANTA.SOCKET4677_AZIF0045P001C01CS(CHIPS)':
 'VSS1659': CDS_PINID='VSS1659';
NODE_NAME     U2 L31
 '@S9S_MB_2U_LIB.S9S_MB_2U(SCH_1):PAGE42_I11@PURE_QUANTA.SOCKET4677_AZIF0045P001C01CS(CHIPS)':
 'VSS1660': CDS_PINID='VSS1660';
NODE_NAME     U2 L33
 '@S9S_MB_2U_LIB.S9S_MB_2U(SCH_1):PAGE42_I11@PURE_QUANTA.SOCKET4677_AZIF0045P001C01CS(CHIPS)':
 'VSS1661': CDS_PINID='VSS1661';
NODE_NAME     U2 L35
 '@S9S_MB_2U_LIB.S9S_MB_2U(SCH_1):PAGE42_I11@PURE_QUANTA.SOCKET4677_AZIF0045P001C01CS(CHIPS)':
 'VSS1662': CDS_PINID='VSS1662';
NODE_NAME     U2 L37
 '@S9S_MB_2U_LIB.S9S_MB_2U(SCH_1):PAGE42_I11@PURE_QUANTA.SOCKET4677_AZIF0045P001C01CS(CHIPS)':
 'VSS1663': CDS_PINID='VSS1663';
NODE_NAME     U2 N21
 '@S9S_MB_2U_LIB.S9S_MB_2U(SCH_1):PAGE42_I11@PURE_QUANTA.SOCKET4677_AZIF0045P001C01CS(CHIPS)':
 'VSS1664': CDS_PINID='VSS1664';
NODE_NAME     U2 L39
 '@S9S_MB_2U_LIB.S9S_MB_2U(SCH_1):PAGE42_I11@PURE_QUANTA.SOCKET4677_AZIF0045P001C01CS(CHIPS)':
 'VSS1665': CDS_PINID='VSS1665';
NODE_NAME     U2 L41
 '@S9S_MB_2U_LIB.S9S_MB_2U(SCH_1):PAGE42_I11@PURE_QUANTA.SOCKET4677_AZIF0045P001C01CS(CHIPS)':
 'VSS1666': CDS_PINID='VSS1666';
NODE_NAME     U2 L43
 '@S9S_MB_2U_LIB.S9S_MB_2U(SCH_1):PAGE42_I11@PURE_QUANTA.SOCKET4677_AZIF0045P001C01CS(CHIPS)':
 'VSS1667': CDS_PINID='VSS1667';
NODE_NAME     U2 L45
 '@S9S_MB_2U_LIB.S9S_MB_2U(SCH_1):PAGE42_I11@PURE_QUANTA.SOCKET4677_AZIF0045P001C01CS(CHIPS)':
 'VSS1668': CDS_PINID='VSS1668';
NODE_NAME     U2 N39
 '@S9S_MB_2U_LIB.S9S_MB_2U(SCH_1):PAGE42_I11@PURE_QUANTA.SOCKET4677_AZIF0045P001C01CS(CHIPS)':
 'VSS1669': CDS_PINID='VSS1669';
NODE_NAME     U2 L48
 '@S9S_MB_2U_LIB.S9S_MB_2U(SCH_1):PAGE42_I11@PURE_QUANTA.SOCKET4677_AZIF0045P001C01CS(CHIPS)':
 'VSS1670': CDS_PINID='VSS1670';
NODE_NAME     U2 L5
 '@S9S_MB_2U_LIB.S9S_MB_2U(SCH_1):PAGE42_I11@PURE_QUANTA.SOCKET4677_AZIF0045P001C01CS(CHIPS)':
 'VSS1671': CDS_PINID='VSS1671';
NODE_NAME     U2 L50
 '@S9S_MB_2U_LIB.S9S_MB_2U(SCH_1):PAGE42_I11@PURE_QUANTA.SOCKET4677_AZIF0045P001C01CS(CHIPS)':
 'VSS1672': CDS_PINID='VSS1672';
NODE_NAME     U2 L52
 '@S9S_MB_2U_LIB.S9S_MB_2U(SCH_1):PAGE42_I11@PURE_QUANTA.SOCKET4677_AZIF0045P001C01CS(CHIPS)':
 'VSS1673': CDS_PINID='VSS1673';
NODE_NAME     U2 L54
 '@S9S_MB_2U_LIB.S9S_MB_2U(SCH_1):PAGE42_I11@PURE_QUANTA.SOCKET4677_AZIF0045P001C01CS(CHIPS)':
 'VSS1674': CDS_PINID='VSS1674';
NODE_NAME     U2 N64
 '@S9S_MB_2U_LIB.S9S_MB_2U(SCH_1):PAGE42_I11@PURE_QUANTA.SOCKET4677_AZIF0045P001C01CS(CHIPS)':
 'VSS1675': CDS_PINID='VSS1675';
NODE_NAME     U2 L56
 '@S9S_MB_2U_LIB.S9S_MB_2U(SCH_1):PAGE42_I11@PURE_QUANTA.SOCKET4677_AZIF0045P001C01CS(CHIPS)':
 'VSS1676': CDS_PINID='VSS1676';
NODE_NAME     U2 L60
 '@S9S_MB_2U_LIB.S9S_MB_2U(SCH_1):PAGE42_I11@PURE_QUANTA.SOCKET4677_AZIF0045P001C01CS(CHIPS)':
 'VSS1677': CDS_PINID='VSS1677';
NODE_NAME     U2 L62
 '@S9S_MB_2U_LIB.S9S_MB_2U(SCH_1):PAGE42_I11@PURE_QUANTA.SOCKET4677_AZIF0045P001C01CS(CHIPS)':
 'VSS1678': CDS_PINID='VSS1678';
NODE_NAME     U2 L64
 '@S9S_MB_2U_LIB.S9S_MB_2U(SCH_1):PAGE42_I11@PURE_QUANTA.SOCKET4677_AZIF0045P001C01CS(CHIPS)':
 'VSS1679': CDS_PINID='VSS1679';
NODE_NAME     U2 L66
 '@S9S_MB_2U_LIB.S9S_MB_2U(SCH_1):PAGE42_I11@PURE_QUANTA.SOCKET4677_AZIF0045P001C01CS(CHIPS)':
 'VSS1680': CDS_PINID='VSS1680';
NODE_NAME     U2 L68
 '@S9S_MB_2U_LIB.S9S_MB_2U(SCH_1):PAGE42_I11@PURE_QUANTA.SOCKET4677_AZIF0045P001C01CS(CHIPS)':
 'VSS1681': CDS_PINID='VSS1681';
NODE_NAME     U2 L72
 '@S9S_MB_2U_LIB.S9S_MB_2U(SCH_1):PAGE42_I11@PURE_QUANTA.SOCKET4677_AZIF0045P001C01CS(CHIPS)':
 'VSS1682': CDS_PINID='VSS1682';
NODE_NAME     U2 L74
 '@S9S_MB_2U_LIB.S9S_MB_2U(SCH_1):PAGE42_I11@PURE_QUANTA.SOCKET4677_AZIF0045P001C01CS(CHIPS)':
 'VSS1683': CDS_PINID='VSS1683';
NODE_NAME     U2 L76
 '@S9S_MB_2U_LIB.S9S_MB_2U(SCH_1):PAGE42_I11@PURE_QUANTA.SOCKET4677_AZIF0045P001C01CS(CHIPS)':
 'VSS1684': CDS_PINID='VSS1684';
NODE_NAME     U2 L78
 '@S9S_MB_2U_LIB.S9S_MB_2U(SCH_1):PAGE42_I11@PURE_QUANTA.SOCKET4677_AZIF0045P001C01CS(CHIPS)':
 'VSS1685': CDS_PINID='VSS1685';
NODE_NAME     U2 M81
 '@S9S_MB_2U_LIB.S9S_MB_2U(SCH_1):PAGE42_I11@PURE_QUANTA.SOCKET4677_AZIF0045P001C01CS(CHIPS)':
 'VSS1686': CDS_PINID='VSS1686';
NODE_NAME     U2 M83
 '@S9S_MB_2U_LIB.S9S_MB_2U(SCH_1):PAGE42_I11@PURE_QUANTA.SOCKET4677_AZIF0045P001C01CS(CHIPS)':
 'VSS1687': CDS_PINID='VSS1687';
NODE_NAME     U2 N15
 '@S9S_MB_2U_LIB.S9S_MB_2U(SCH_1):PAGE42_I11@PURE_QUANTA.SOCKET4677_AZIF0045P001C01CS(CHIPS)':
 'VSS1688': CDS_PINID='VSS1688';
NODE_NAME     U2 N27
 '@S9S_MB_2U_LIB.S9S_MB_2U(SCH_1):PAGE42_I11@PURE_QUANTA.SOCKET4677_AZIF0045P001C01CS(CHIPS)':
 'VSS1689': CDS_PINID='VSS1689';
NODE_NAME     U2 N33
 '@S9S_MB_2U_LIB.S9S_MB_2U(SCH_1):PAGE42_I11@PURE_QUANTA.SOCKET4677_AZIF0045P001C01CS(CHIPS)':
 'VSS1691': CDS_PINID='VSS1691';
NODE_NAME     U2 N45
 '@S9S_MB_2U_LIB.S9S_MB_2U(SCH_1):PAGE42_I11@PURE_QUANTA.SOCKET4677_AZIF0045P001C01CS(CHIPS)':
 'VSS1692': CDS_PINID='VSS1692';
NODE_NAME     U2 N52
 '@S9S_MB_2U_LIB.S9S_MB_2U(SCH_1):PAGE42_I11@PURE_QUANTA.SOCKET4677_AZIF0045P001C01CS(CHIPS)':
 'VSS1693': CDS_PINID='VSS1693';
NODE_NAME     U2 N58
 '@S9S_MB_2U_LIB.S9S_MB_2U(SCH_1):PAGE42_I11@PURE_QUANTA.SOCKET4677_AZIF0045P001C01CS(CHIPS)':
 'VSS1694': CDS_PINID='VSS1694';
NODE_NAME     U2 N70
 '@S9S_MB_2U_LIB.S9S_MB_2U(SCH_1):PAGE42_I11@PURE_QUANTA.SOCKET4677_AZIF0045P001C01CS(CHIPS)':
 'VSS1695': CDS_PINID='VSS1695';
NODE_NAME     U2 A11
 '@S9S_MB_2U_LIB.S9S_MB_2U(SCH_1):PAGE42_I12@PURE_QUANTA.SOCKET4677_AZIF0045P001C01CS(CHIPS)':
 'VSS1': CDS_PINID='VSS1';
NODE_NAME     U2 A13
 '@S9S_MB_2U_LIB.S9S_MB_2U(SCH_1):PAGE42_I12@PURE_QUANTA.SOCKET4677_AZIF0045P001C01CS(CHIPS)':
 'VSS2': CDS_PINID='VSS2';
NODE_NAME     U2 A17
 '@S9S_MB_2U_LIB.S9S_MB_2U(SCH_1):PAGE42_I12@PURE_QUANTA.SOCKET4677_AZIF0045P001C01CS(CHIPS)':
 'VSS3': CDS_PINID='VSS3';
NODE_NAME     U2 A19
 '@S9S_MB_2U_LIB.S9S_MB_2U(SCH_1):PAGE42_I12@PURE_QUANTA.SOCKET4677_AZIF0045P001C01CS(CHIPS)':
 'VSS4': CDS_PINID='VSS4';
NODE_NAME     U2 A23
 '@S9S_MB_2U_LIB.S9S_MB_2U(SCH_1):PAGE42_I12@PURE_QUANTA.SOCKET4677_AZIF0045P001C01CS(CHIPS)':
 'VSS5': CDS_PINID='VSS5';
NODE_NAME     U2 A25
 '@S9S_MB_2U_LIB.S9S_MB_2U(SCH_1):PAGE42_I12@PURE_QUANTA.SOCKET4677_AZIF0045P001C01CS(CHIPS)':
 'VSS6': CDS_PINID='VSS6';
NODE_NAME     U2 A29
 '@S9S_MB_2U_LIB.S9S_MB_2U(SCH_1):PAGE42_I12@PURE_QUANTA.SOCKET4677_AZIF0045P001C01CS(CHIPS)':
 'VSS7': CDS_PINID='VSS7';
NODE_NAME     U2 A31
 '@S9S_MB_2U_LIB.S9S_MB_2U(SCH_1):PAGE42_I12@PURE_QUANTA.SOCKET4677_AZIF0045P001C01CS(CHIPS)':
 'VSS8': CDS_PINID='VSS8';
NODE_NAME     U2 A35
 '@S9S_MB_2U_LIB.S9S_MB_2U(SCH_1):PAGE42_I12@PURE_QUANTA.SOCKET4677_AZIF0045P001C01CS(CHIPS)':
 'VSS9': CDS_PINID='VSS9';
NODE_NAME     U2 A37
 '@S9S_MB_2U_LIB.S9S_MB_2U(SCH_1):PAGE42_I12@PURE_QUANTA.SOCKET4677_AZIF0045P001C01CS(CHIPS)':
 'VSS10': CDS_PINID='VSS10';
NODE_NAME     U2 A41
 '@S9S_MB_2U_LIB.S9S_MB_2U(SCH_1):PAGE42_I12@PURE_QUANTA.SOCKET4677_AZIF0045P001C01CS(CHIPS)':
 'VSS11': CDS_PINID='VSS11';
NODE_NAME     U2 A50
 '@S9S_MB_2U_LIB.S9S_MB_2U(SCH_1):PAGE42_I12@PURE_QUANTA.SOCKET4677_AZIF0045P001C01CS(CHIPS)':
 'VSS12': CDS_PINID='VSS12';
NODE_NAME     U2 A54
 '@S9S_MB_2U_LIB.S9S_MB_2U(SCH_1):PAGE42_I12@PURE_QUANTA.SOCKET4677_AZIF0045P001C01CS(CHIPS)':
 'VSS13': CDS_PINID='VSS13';
NODE_NAME     U2 A56
 '@S9S_MB_2U_LIB.S9S_MB_2U(SCH_1):PAGE42_I12@PURE_QUANTA.SOCKET4677_AZIF0045P001C01CS(CHIPS)':
 'VSS14': CDS_PINID='VSS14';
NODE_NAME     U2 A60
 '@S9S_MB_2U_LIB.S9S_MB_2U(SCH_1):PAGE42_I12@PURE_QUANTA.SOCKET4677_AZIF0045P001C01CS(CHIPS)':
 'VSS15': CDS_PINID='VSS15';
NODE_NAME     U2 A62
 '@S9S_MB_2U_LIB.S9S_MB_2U(SCH_1):PAGE42_I12@PURE_QUANTA.SOCKET4677_AZIF0045P001C01CS(CHIPS)':
 'VSS16': CDS_PINID='VSS16';
NODE_NAME     U2 B12
 '@S9S_MB_2U_LIB.S9S_MB_2U(SCH_1):PAGE42_I12@PURE_QUANTA.SOCKET4677_AZIF0045P001C01CS(CHIPS)':
 'VSS378': CDS_PINID='VSS378';
NODE_NAME     U2 B18
 '@S9S_MB_2U_LIB.S9S_MB_2U(SCH_1):PAGE42_I12@PURE_QUANTA.SOCKET4677_AZIF0045P001C01CS(CHIPS)':
 'VSS379': CDS_PINID='VSS379';
NODE_NAME     U2 B24
 '@S9S_MB_2U_LIB.S9S_MB_2U(SCH_1):PAGE42_I12@PURE_QUANTA.SOCKET4677_AZIF0045P001C01CS(CHIPS)':
 'VSS380': CDS_PINID='VSS380';
NODE_NAME     U2 B30
 '@S9S_MB_2U_LIB.S9S_MB_2U(SCH_1):PAGE42_I12@PURE_QUANTA.SOCKET4677_AZIF0045P001C01CS(CHIPS)':
 'VSS381': CDS_PINID='VSS381';
NODE_NAME     U2 B36
 '@S9S_MB_2U_LIB.S9S_MB_2U(SCH_1):PAGE42_I12@PURE_QUANTA.SOCKET4677_AZIF0045P001C01CS(CHIPS)':
 'VSS382': CDS_PINID='VSS382';
NODE_NAME     U2 B42
 '@S9S_MB_2U_LIB.S9S_MB_2U(SCH_1):PAGE42_I12@PURE_QUANTA.SOCKET4677_AZIF0045P001C01CS(CHIPS)':
 'VSS384': CDS_PINID='VSS384';
NODE_NAME     U2 B49
 '@S9S_MB_2U_LIB.S9S_MB_2U(SCH_1):PAGE42_I12@PURE_QUANTA.SOCKET4677_AZIF0045P001C01CS(CHIPS)':
 'VSS385': CDS_PINID='VSS385';
NODE_NAME     U2 B55
 '@S9S_MB_2U_LIB.S9S_MB_2U(SCH_1):PAGE42_I12@PURE_QUANTA.SOCKET4677_AZIF0045P001C01CS(CHIPS)':
 'VSS386': CDS_PINID='VSS386';
NODE_NAME     U2 B6
 '@S9S_MB_2U_LIB.S9S_MB_2U(SCH_1):PAGE42_I12@PURE_QUANTA.SOCKET4677_AZIF0045P001C01CS(CHIPS)':
 'VSS387': CDS_PINID='VSS387';
NODE_NAME     U2 B61
 '@S9S_MB_2U_LIB.S9S_MB_2U(SCH_1):PAGE42_I12@PURE_QUANTA.SOCKET4677_AZIF0045P001C01CS(CHIPS)':
 'VSS388': CDS_PINID='VSS388';
NODE_NAME     U2 B67
 '@S9S_MB_2U_LIB.S9S_MB_2U(SCH_1):PAGE42_I12@PURE_QUANTA.SOCKET4677_AZIF0045P001C01CS(CHIPS)':
 'VSS389': CDS_PINID='VSS389';
NODE_NAME     U2 B75
 '@S9S_MB_2U_LIB.S9S_MB_2U(SCH_1):PAGE42_I12@PURE_QUANTA.SOCKET4677_AZIF0045P001C01CS(CHIPS)':
 'VSS390': CDS_PINID='VSS390';
NODE_NAME     U2 B83
 '@S9S_MB_2U_LIB.S9S_MB_2U(SCH_1):PAGE42_I12@PURE_QUANTA.SOCKET4677_AZIF0045P001C01CS(CHIPS)':
 'VSS391': CDS_PINID='VSS391';
NODE_NAME     U2 B87
 '@S9S_MB_2U_LIB.S9S_MB_2U(SCH_1):PAGE42_I12@PURE_QUANTA.SOCKET4677_AZIF0045P001C01CS(CHIPS)':
 'VSS392': CDS_PINID='VSS392';
NODE_NAME     U2 C39
 '@S9S_MB_2U_LIB.S9S_MB_2U(SCH_1):PAGE42_I12@PURE_QUANTA.SOCKET4677_AZIF0045P001C01CS(CHIPS)':
 'VSS609': CDS_PINID='VSS609';
NODE_NAME     U2 C45
 '@S9S_MB_2U_LIB.S9S_MB_2U(SCH_1):PAGE42_I12@PURE_QUANTA.SOCKET4677_AZIF0045P001C01CS(CHIPS)':
 'VSS610': CDS_PINID='VSS610';
NODE_NAME     U2 C5
 '@S9S_MB_2U_LIB.S9S_MB_2U(SCH_1):PAGE42_I12@PURE_QUANTA.SOCKET4677_AZIF0045P001C01CS(CHIPS)':
 'VSS612': CDS_PINID='VSS612';
NODE_NAME     U2 C52
 '@S9S_MB_2U_LIB.S9S_MB_2U(SCH_1):PAGE42_I12@PURE_QUANTA.SOCKET4677_AZIF0045P001C01CS(CHIPS)':
 'VSS613': CDS_PINID='VSS613';
NODE_NAME     U2 C72
 '@S9S_MB_2U_LIB.S9S_MB_2U(SCH_1):PAGE42_I12@PURE_QUANTA.SOCKET4677_AZIF0045P001C01CS(CHIPS)':
 'VSS614': CDS_PINID='VSS614';
NODE_NAME     U2 C74
 '@S9S_MB_2U_LIB.S9S_MB_2U(SCH_1):PAGE42_I12@PURE_QUANTA.SOCKET4677_AZIF0045P001C01CS(CHIPS)':
 'VSS615': CDS_PINID='VSS615';
NODE_NAME     U2 C78
 '@S9S_MB_2U_LIB.S9S_MB_2U(SCH_1):PAGE42_I12@PURE_QUANTA.SOCKET4677_AZIF0045P001C01CS(CHIPS)':
 'VSS616': CDS_PINID='VSS616';
NODE_NAME     U2 C80
 '@S9S_MB_2U_LIB.S9S_MB_2U(SCH_1):PAGE42_I12@PURE_QUANTA.SOCKET4677_AZIF0045P001C01CS(CHIPS)':
 'VSS617': CDS_PINID='VSS617';
NODE_NAME     U2 C82
 '@S9S_MB_2U_LIB.S9S_MB_2U(SCH_1):PAGE42_I12@PURE_QUANTA.SOCKET4677_AZIF0045P001C01CS(CHIPS)':
 'VSS618': CDS_PINID='VSS618';
NODE_NAME     U2 C86
 '@S9S_MB_2U_LIB.S9S_MB_2U(SCH_1):PAGE42_I12@PURE_QUANTA.SOCKET4677_AZIF0045P001C01CS(CHIPS)':
 'VSS619': CDS_PINID='VSS619';
NODE_NAME     U2 D63
 '@S9S_MB_2U_LIB.S9S_MB_2U(SCH_1):PAGE42_I12@PURE_QUANTA.SOCKET4677_AZIF0045P001C01CS(CHIPS)':
 'VSS657': CDS_PINID='VSS657';
NODE_NAME     U2 D65
 '@S9S_MB_2U_LIB.S9S_MB_2U(SCH_1):PAGE42_I12@PURE_QUANTA.SOCKET4677_AZIF0045P001C01CS(CHIPS)':
 'VSS658': CDS_PINID='VSS658';
NODE_NAME     U2 D67
 '@S9S_MB_2U_LIB.S9S_MB_2U(SCH_1):PAGE42_I12@PURE_QUANTA.SOCKET4677_AZIF0045P001C01CS(CHIPS)':
 'VSS659': CDS_PINID='VSS659';
NODE_NAME     U2 D79
 '@S9S_MB_2U_LIB.S9S_MB_2U(SCH_1):PAGE42_I12@PURE_QUANTA.SOCKET4677_AZIF0045P001C01CS(CHIPS)':
 'VSS662': CDS_PINID='VSS662';
NODE_NAME     U2 D8
 '@S9S_MB_2U_LIB.S9S_MB_2U(SCH_1):PAGE42_I12@PURE_QUANTA.SOCKET4677_AZIF0045P001C01CS(CHIPS)':
 'VSS663': CDS_PINID='VSS663';
NODE_NAME     U2 D10
 '@S9S_MB_2U_LIB.S9S_MB_2U(SCH_1):PAGE42_I12@PURE_QUANTA.SOCKET4677_AZIF0045P001C01CS(CHIPS)':
 'VSS864': CDS_PINID='VSS864';
NODE_NAME     U2 D12
 '@S9S_MB_2U_LIB.S9S_MB_2U(SCH_1):PAGE42_I12@PURE_QUANTA.SOCKET4677_AZIF0045P001C01CS(CHIPS)':
 'VSS865': CDS_PINID='VSS865';
NODE_NAME     U2 D14
 '@S9S_MB_2U_LIB.S9S_MB_2U(SCH_1):PAGE42_I12@PURE_QUANTA.SOCKET4677_AZIF0045P001C01CS(CHIPS)':
 'VSS866': CDS_PINID='VSS866';
NODE_NAME     U2 D16
 '@S9S_MB_2U_LIB.S9S_MB_2U(SCH_1):PAGE42_I12@PURE_QUANTA.SOCKET4677_AZIF0045P001C01CS(CHIPS)':
 'VSS868': CDS_PINID='VSS868';
NODE_NAME     U2 D18
 '@S9S_MB_2U_LIB.S9S_MB_2U(SCH_1):PAGE42_I12@PURE_QUANTA.SOCKET4677_AZIF0045P001C01CS(CHIPS)':
 'VSS869': CDS_PINID='VSS869';
NODE_NAME     U2 D20
 '@S9S_MB_2U_LIB.S9S_MB_2U(SCH_1):PAGE42_I12@PURE_QUANTA.SOCKET4677_AZIF0045P001C01CS(CHIPS)':
 'VSS871': CDS_PINID='VSS871';
NODE_NAME     U2 D22
 '@S9S_MB_2U_LIB.S9S_MB_2U(SCH_1):PAGE42_I12@PURE_QUANTA.SOCKET4677_AZIF0045P001C01CS(CHIPS)':
 'VSS873': CDS_PINID='VSS873';
NODE_NAME     U2 D24
 '@S9S_MB_2U_LIB.S9S_MB_2U(SCH_1):PAGE42_I12@PURE_QUANTA.SOCKET4677_AZIF0045P001C01CS(CHIPS)':
 'VSS874': CDS_PINID='VSS874';
NODE_NAME     U2 D26
 '@S9S_MB_2U_LIB.S9S_MB_2U(SCH_1):PAGE42_I12@PURE_QUANTA.SOCKET4677_AZIF0045P001C01CS(CHIPS)':
 'VSS875': CDS_PINID='VSS875';
NODE_NAME     U2 D28
 '@S9S_MB_2U_LIB.S9S_MB_2U(SCH_1):PAGE42_I12@PURE_QUANTA.SOCKET4677_AZIF0045P001C01CS(CHIPS)':
 'VSS876': CDS_PINID='VSS876';
NODE_NAME     U2 D30
 '@S9S_MB_2U_LIB.S9S_MB_2U(SCH_1):PAGE42_I12@PURE_QUANTA.SOCKET4677_AZIF0045P001C01CS(CHIPS)':
 'VSS877': CDS_PINID='VSS877';
NODE_NAME     U2 D32
 '@S9S_MB_2U_LIB.S9S_MB_2U(SCH_1):PAGE42_I12@PURE_QUANTA.SOCKET4677_AZIF0045P001C01CS(CHIPS)':
 'VSS878': CDS_PINID='VSS878';
NODE_NAME     U2 D34
 '@S9S_MB_2U_LIB.S9S_MB_2U(SCH_1):PAGE42_I12@PURE_QUANTA.SOCKET4677_AZIF0045P001C01CS(CHIPS)':
 'VSS879': CDS_PINID='VSS879';
NODE_NAME     U2 D36
 '@S9S_MB_2U_LIB.S9S_MB_2U(SCH_1):PAGE42_I12@PURE_QUANTA.SOCKET4677_AZIF0045P001C01CS(CHIPS)':
 'VSS881': CDS_PINID='VSS881';
NODE_NAME     U2 D38
 '@S9S_MB_2U_LIB.S9S_MB_2U(SCH_1):PAGE42_I12@PURE_QUANTA.SOCKET4677_AZIF0045P001C01CS(CHIPS)':
 'VSS884': CDS_PINID='VSS884';
NODE_NAME     U2 D40
 '@S9S_MB_2U_LIB.S9S_MB_2U(SCH_1):PAGE42_I12@PURE_QUANTA.SOCKET4677_AZIF0045P001C01CS(CHIPS)':
 'VSS885': CDS_PINID='VSS885';
NODE_NAME     U2 D42
 '@S9S_MB_2U_LIB.S9S_MB_2U(SCH_1):PAGE42_I12@PURE_QUANTA.SOCKET4677_AZIF0045P001C01CS(CHIPS)':
 'VSS886': CDS_PINID='VSS886';
NODE_NAME     U2 D44
 '@S9S_MB_2U_LIB.S9S_MB_2U(SCH_1):PAGE42_I12@PURE_QUANTA.SOCKET4677_AZIF0045P001C01CS(CHIPS)':
 'VSS888': CDS_PINID='VSS888';
NODE_NAME     U2 D47
 '@S9S_MB_2U_LIB.S9S_MB_2U(SCH_1):PAGE42_I12@PURE_QUANTA.SOCKET4677_AZIF0045P001C01CS(CHIPS)':
 'VSS889': CDS_PINID='VSS889';
NODE_NAME     U2 D49
 '@S9S_MB_2U_LIB.S9S_MB_2U(SCH_1):PAGE42_I12@PURE_QUANTA.SOCKET4677_AZIF0045P001C01CS(CHIPS)':
 'VSS891': CDS_PINID='VSS891';
NODE_NAME     U2 D51
 '@S9S_MB_2U_LIB.S9S_MB_2U(SCH_1):PAGE42_I12@PURE_QUANTA.SOCKET4677_AZIF0045P001C01CS(CHIPS)':
 'VSS892': CDS_PINID='VSS892';
NODE_NAME     U2 D53
 '@S9S_MB_2U_LIB.S9S_MB_2U(SCH_1):PAGE42_I12@PURE_QUANTA.SOCKET4677_AZIF0045P001C01CS(CHIPS)':
 'VSS895': CDS_PINID='VSS895';
NODE_NAME     U2 D55
 '@S9S_MB_2U_LIB.S9S_MB_2U(SCH_1):PAGE42_I12@PURE_QUANTA.SOCKET4677_AZIF0045P001C01CS(CHIPS)':
 'VSS896': CDS_PINID='VSS896';
NODE_NAME     U2 D57
 '@S9S_MB_2U_LIB.S9S_MB_2U(SCH_1):PAGE42_I12@PURE_QUANTA.SOCKET4677_AZIF0045P001C01CS(CHIPS)':
 'VSS897': CDS_PINID='VSS897';
NODE_NAME     U2 D59
 '@S9S_MB_2U_LIB.S9S_MB_2U(SCH_1):PAGE42_I12@PURE_QUANTA.SOCKET4677_AZIF0045P001C01CS(CHIPS)':
 'VSS898': CDS_PINID='VSS898';
NODE_NAME     U2 D6
 '@S9S_MB_2U_LIB.S9S_MB_2U(SCH_1):PAGE42_I12@PURE_QUANTA.SOCKET4677_AZIF0045P001C01CS(CHIPS)':
 'VSS899': CDS_PINID='VSS899';
NODE_NAME     U2 D61
 '@S9S_MB_2U_LIB.S9S_MB_2U(SCH_1):PAGE42_I12@PURE_QUANTA.SOCKET4677_AZIF0045P001C01CS(CHIPS)':
 'VSS900': CDS_PINID='VSS900';
NODE_NAME     U2 D69
 '@S9S_MB_2U_LIB.S9S_MB_2U(SCH_1):PAGE42_I12@PURE_QUANTA.SOCKET4677_AZIF0045P001C01CS(CHIPS)':
 'VSS901': CDS_PINID='VSS901';
NODE_NAME     U2 D71
 '@S9S_MB_2U_LIB.S9S_MB_2U(SCH_1):PAGE42_I12@PURE_QUANTA.SOCKET4677_AZIF0045P001C01CS(CHIPS)':
 'VSS902': CDS_PINID='VSS902';
NODE_NAME     U2 D81
 '@S9S_MB_2U_LIB.S9S_MB_2U(SCH_1):PAGE42_I12@PURE_QUANTA.SOCKET4677_AZIF0045P001C01CS(CHIPS)':
 'VSS906': CDS_PINID='VSS906';
NODE_NAME     U2 D83
 '@S9S_MB_2U_LIB.S9S_MB_2U(SCH_1):PAGE42_I12@PURE_QUANTA.SOCKET4677_AZIF0045P001C01CS(CHIPS)':
 'VSS907': CDS_PINID='VSS907';
NODE_NAME     U2 E5
 '@S9S_MB_2U_LIB.S9S_MB_2U(SCH_1):PAGE42_I12@PURE_QUANTA.SOCKET4677_AZIF0045P001C01CS(CHIPS)':
 'VSS1125': CDS_PINID='VSS1125';
NODE_NAME     U2 E39
 '@S9S_MB_2U_LIB.S9S_MB_2U(SCH_1):PAGE42_I12@PURE_QUANTA.SOCKET4677_AZIF0045P001C01CS(CHIPS)':
 'VSS1271': CDS_PINID='VSS1271';
NODE_NAME     R69 2
 '@S9S_MB_2U_LIB.S9S_MB_2U(SCH_1):PAGE43_I16@PURE_QUANTA.Q_RES(CHIPS)':
 'B': CDS_PINID='B';
NODE_NAME     R70 2
 '@S9S_MB_2U_LIB.S9S_MB_2U(SCH_1):PAGE43_I17@PURE_QUANTA.Q_RES(CHIPS)':
 'B': CDS_PINID='B';
NODE_NAME     R1226 2
 '@S9S_MB_2U_LIB.S9S_MB_2U(SCH_1):PAGE43_I52@PURE_QUANTA.Q_RES(CHIPS)':
 'B': CDS_PINID='B';
NODE_NAME     R1227 2
 '@S9S_MB_2U_LIB.S9S_MB_2U(SCH_1):PAGE43_I56@PURE_QUANTA.Q_RES(CHIPS)':
 'B': CDS_PINID='B';
NODE_NAME     R1270 2
 '@S9S_MB_2U_LIB.S9S_MB_2U(SCH_1):PAGE44_I55@PURE_QUANTA.Q_RES(CHIPS)':
 'B': CDS_PINID='B';
NODE_NAME     U1 EJ80
 '@S9S_MB_2U_LIB.S9S_MB_2U(SCH_1):PAGE66_I16@PURE_QUANTA.SOCKET4677_AZIF0045P001C01CS(CHIPS)':
 'UPI3_RX_DN0': CDS_PINID='UPI3_RX_DN0';
NODE_NAME     U1 EP81
 '@S9S_MB_2U_LIB.S9S_MB_2U(SCH_1):PAGE66_I16@PURE_QUANTA.SOCKET4677_AZIF0045P001C01CS(CHIPS)':
 'UPI3_RX_DN1': CDS_PINID='UPI3_RX_DN1';
NODE_NAME     U1 EL82
 '@S9S_MB_2U_LIB.S9S_MB_2U(SCH_1):PAGE66_I16@PURE_QUANTA.SOCKET4677_AZIF0045P001C01CS(CHIPS)':
 'UPI3_RX_DN2': CDS_PINID='UPI3_RX_DN2';
NODE_NAME     U1 EK81
 '@S9S_MB_2U_LIB.S9S_MB_2U(SCH_1):PAGE66_I16@PURE_QUANTA.SOCKET4677_AZIF0045P001C01CS(CHIPS)':
 'UPI3_RX_DN3': CDS_PINID='UPI3_RX_DN3';
NODE_NAME     U1 EF81
 '@S9S_MB_2U_LIB.S9S_MB_2U(SCH_1):PAGE66_I16@PURE_QUANTA.SOCKET4677_AZIF0045P001C01CS(CHIPS)':
 'UPI3_RX_DN4': CDS_PINID='UPI3_RX_DN4';
NODE_NAME     U1 ED83
 '@S9S_MB_2U_LIB.S9S_MB_2U(SCH_1):PAGE66_I16@PURE_QUANTA.SOCKET4677_AZIF0045P001C01CS(CHIPS)':
 'UPI3_RX_DN5': CDS_PINID='UPI3_RX_DN5';
NODE_NAME     U1 EC80
 '@S9S_MB_2U_LIB.S9S_MB_2U(SCH_1):PAGE66_I16@PURE_QUANTA.SOCKET4677_AZIF0045P001C01CS(CHIPS)':
 'UPI3_RX_DN6': CDS_PINID='UPI3_RX_DN6';
NODE_NAME     U1 EA82
 '@S9S_MB_2U_LIB.S9S_MB_2U(SCH_1):PAGE66_I16@PURE_QUANTA.SOCKET4677_AZIF0045P001C01CS(CHIPS)':
 'UPI3_RX_DN7': CDS_PINID='UPI3_RX_DN7';
NODE_NAME     U1 DY81
 '@S9S_MB_2U_LIB.S9S_MB_2U(SCH_1):PAGE66_I16@PURE_QUANTA.SOCKET4677_AZIF0045P001C01CS(CHIPS)':
 'UPI3_RX_DN8': CDS_PINID='UPI3_RX_DN8';
NODE_NAME     U1 DJ78
 '@S9S_MB_2U_LIB.S9S_MB_2U(SCH_1):PAGE66_I16@PURE_QUANTA.SOCKET4677_AZIF0045P001C01CS(CHIPS)':
 'UPI3_RX_DN9': CDS_PINID='UPI3_RX_DN9';
NODE_NAME     U1 DG78
 '@S9S_MB_2U_LIB.S9S_MB_2U(SCH_1):PAGE66_I16@PURE_QUANTA.SOCKET4677_AZIF0045P001C01CS(CHIPS)':
 'UPI3_RX_DN10': CDS_PINID='UPI3_RX_DN10';
NODE_NAME     U1 DH81
 '@S9S_MB_2U_LIB.S9S_MB_2U(SCH_1):PAGE66_I16@PURE_QUANTA.SOCKET4677_AZIF0045P001C01CS(CHIPS)':
 'UPI3_RX_DN11': CDS_PINID='UPI3_RX_DN11';
NODE_NAME     U1 DF83
 '@S9S_MB_2U_LIB.S9S_MB_2U(SCH_1):PAGE66_I16@PURE_QUANTA.SOCKET4677_AZIF0045P001C01CS(CHIPS)':
 'UPI3_RX_DN12': CDS_PINID='UPI3_RX_DN12';
NODE_NAME     U1 DE80
 '@S9S_MB_2U_LIB.S9S_MB_2U(SCH_1):PAGE66_I16@PURE_QUANTA.SOCKET4677_AZIF0045P001C01CS(CHIPS)':
 'UPI3_RX_DN13': CDS_PINID='UPI3_RX_DN13';
NODE_NAME     U1 DC82
 '@S9S_MB_2U_LIB.S9S_MB_2U(SCH_1):PAGE66_I16@PURE_QUANTA.SOCKET4677_AZIF0045P001C01CS(CHIPS)':
 'UPI3_RX_DN14': CDS_PINID='UPI3_RX_DN14';
NODE_NAME     U1 DB81
 '@S9S_MB_2U_LIB.S9S_MB_2U(SCH_1):PAGE66_I16@PURE_QUANTA.SOCKET4677_AZIF0045P001C01CS(CHIPS)':
 'UPI3_RX_DN15': CDS_PINID='UPI3_RX_DN15';
NODE_NAME     U1 DF77
 '@S9S_MB_2U_LIB.S9S_MB_2U(SCH_1):PAGE66_I16@PURE_QUANTA.SOCKET4677_AZIF0045P001C01CS(CHIPS)':
 'UPI3_RX_DN16': CDS_PINID='UPI3_RX_DN16';
NODE_NAME     U1 CU82
 '@S9S_MB_2U_LIB.S9S_MB_2U(SCH_1):PAGE66_I16@PURE_QUANTA.SOCKET4677_AZIF0045P001C01CS(CHIPS)':
 'UPI3_RX_DN17': CDS_PINID='UPI3_RX_DN17';
NODE_NAME     U1 CR82
 '@S9S_MB_2U_LIB.S9S_MB_2U(SCH_1):PAGE66_I16@PURE_QUANTA.SOCKET4677_AZIF0045P001C01CS(CHIPS)':
 'UPI3_RX_DN18': CDS_PINID='UPI3_RX_DN18';
NODE_NAME     U1 CW80
 '@S9S_MB_2U_LIB.S9S_MB_2U(SCH_1):PAGE66_I16@PURE_QUANTA.SOCKET4677_AZIF0045P001C01CS(CHIPS)':
 'UPI3_RX_DN19': CDS_PINID='UPI3_RX_DN19';
NODE_NAME     U1 CP81
 '@S9S_MB_2U_LIB.S9S_MB_2U(SCH_1):PAGE66_I16@PURE_QUANTA.SOCKET4677_AZIF0045P001C01CS(CHIPS)':
 'UPI3_RX_DN20': CDS_PINID='UPI3_RX_DN20';
NODE_NAME     U1 CN80
 '@S9S_MB_2U_LIB.S9S_MB_2U(SCH_1):PAGE66_I16@PURE_QUANTA.SOCKET4677_AZIF0045P001C01CS(CHIPS)':
 'UPI3_RX_DN21': CDS_PINID='UPI3_RX_DN21';
NODE_NAME     U1 CT79
 '@S9S_MB_2U_LIB.S9S_MB_2U(SCH_1):PAGE66_I16@PURE_QUANTA.SOCKET4677_AZIF0045P001C01CS(CHIPS)':
 'UPI3_RX_DN22': CDS_PINID='UPI3_RX_DN22';
NODE_NAME     U1 DA78
 '@S9S_MB_2U_LIB.S9S_MB_2U(SCH_1):PAGE66_I16@PURE_QUANTA.SOCKET4677_AZIF0045P001C01CS(CHIPS)':
 'UPI3_RX_DN23': CDS_PINID='UPI3_RX_DN23';
NODE_NAME     U1 EL80
 '@S9S_MB_2U_LIB.S9S_MB_2U(SCH_1):PAGE66_I16@PURE_QUANTA.SOCKET4677_AZIF0045P001C01CS(CHIPS)':
 'UPI3_RX_DP0': CDS_PINID='UPI3_RX_DP0';
NODE_NAME     U1 ER82
 '@S9S_MB_2U_LIB.S9S_MB_2U(SCH_1):PAGE66_I16@PURE_QUANTA.SOCKET4677_AZIF0045P001C01CS(CHIPS)':
 'UPI3_RX_DP1': CDS_PINID='UPI3_RX_DP1';
NODE_NAME     U1 EN82
 '@S9S_MB_2U_LIB.S9S_MB_2U(SCH_1):PAGE66_I16@PURE_QUANTA.SOCKET4677_AZIF0045P001C01CS(CHIPS)':
 'UPI3_RX_DP2': CDS_PINID='UPI3_RX_DP2';
NODE_NAME     U1 EJ82
 '@S9S_MB_2U_LIB.S9S_MB_2U(SCH_1):PAGE66_I16@PURE_QUANTA.SOCKET4677_AZIF0045P001C01CS(CHIPS)':
 'UPI3_RX_DP3': CDS_PINID='UPI3_RX_DP3';
NODE_NAME     U1 EE82
 '@S9S_MB_2U_LIB.S9S_MB_2U(SCH_1):PAGE66_I16@PURE_QUANTA.SOCKET4677_AZIF0045P001C01CS(CHIPS)':
 'UPI3_RX_DP4': CDS_PINID='UPI3_RX_DP4';
NODE_NAME     U1 EF83
 '@S9S_MB_2U_LIB.S9S_MB_2U(SCH_1):PAGE66_I16@PURE_QUANTA.SOCKET4677_AZIF0045P001C01CS(CHIPS)':
 'UPI3_RX_DP5': CDS_PINID='UPI3_RX_DP5';
NODE_NAME     U1 ED81
 '@S9S_MB_2U_LIB.S9S_MB_2U(SCH_1):PAGE66_I16@PURE_QUANTA.SOCKET4677_AZIF0045P001C01CS(CHIPS)':
 'UPI3_RX_DP6': CDS_PINID='UPI3_RX_DP6';
NODE_NAME     U1 DY83
 '@S9S_MB_2U_LIB.S9S_MB_2U(SCH_1):PAGE66_I16@PURE_QUANTA.SOCKET4677_AZIF0045P001C01CS(CHIPS)':
 'UPI3_RX_DP7': CDS_PINID='UPI3_RX_DP7';
NODE_NAME     U1 EB81
 '@S9S_MB_2U_LIB.S9S_MB_2U(SCH_1):PAGE66_I16@PURE_QUANTA.SOCKET4677_AZIF0045P001C01CS(CHIPS)':
 'UPI3_RX_DP8': CDS_PINID='UPI3_RX_DP8';
NODE_NAME     U1 DL78
 '@S9S_MB_2U_LIB.S9S_MB_2U(SCH_1):PAGE66_I16@PURE_QUANTA.SOCKET4677_AZIF0045P001C01CS(CHIPS)':
 'UPI3_RX_DP9': CDS_PINID='UPI3_RX_DP9';
NODE_NAME     U1 DH79
 '@S9S_MB_2U_LIB.S9S_MB_2U(SCH_1):PAGE66_I16@PURE_QUANTA.SOCKET4677_AZIF0045P001C01CS(CHIPS)':
 'UPI3_RX_DP10': CDS_PINID='UPI3_RX_DP10';
NODE_NAME     U1 DG82
 '@S9S_MB_2U_LIB.S9S_MB_2U(SCH_1):PAGE66_I16@PURE_QUANTA.SOCKET4677_AZIF0045P001C01CS(CHIPS)':
 'UPI3_RX_DP11': CDS_PINID='UPI3_RX_DP11';
NODE_NAME     U1 DH83
 '@S9S_MB_2U_LIB.S9S_MB_2U(SCH_1):PAGE66_I16@PURE_QUANTA.SOCKET4677_AZIF0045P001C01CS(CHIPS)':
 'UPI3_RX_DP12': CDS_PINID='UPI3_RX_DP12';
NODE_NAME     U1 DF81
 '@S9S_MB_2U_LIB.S9S_MB_2U(SCH_1):PAGE66_I16@PURE_QUANTA.SOCKET4677_AZIF0045P001C01CS(CHIPS)':
 'UPI3_RX_DP13': CDS_PINID='UPI3_RX_DP13';
NODE_NAME     U1 DB83
 '@S9S_MB_2U_LIB.S9S_MB_2U(SCH_1):PAGE66_I16@PURE_QUANTA.SOCKET4677_AZIF0045P001C01CS(CHIPS)':
 'UPI3_RX_DP14': CDS_PINID='UPI3_RX_DP14';
NODE_NAME     U1 DD81
 '@S9S_MB_2U_LIB.S9S_MB_2U(SCH_1):PAGE66_I16@PURE_QUANTA.SOCKET4677_AZIF0045P001C01CS(CHIPS)':
 'UPI3_RX_DP15': CDS_PINID='UPI3_RX_DP15';
NODE_NAME     U1 DE78
 '@S9S_MB_2U_LIB.S9S_MB_2U(SCH_1):PAGE66_I16@PURE_QUANTA.SOCKET4677_AZIF0045P001C01CS(CHIPS)':
 'UPI3_RX_DP16': CDS_PINID='UPI3_RX_DP16';
NODE_NAME     U1 CW82
 '@S9S_MB_2U_LIB.S9S_MB_2U(SCH_1):PAGE66_I16@PURE_QUANTA.SOCKET4677_AZIF0045P001C01CS(CHIPS)':
 'UPI3_RX_DP17': CDS_PINID='UPI3_RX_DP17';
NODE_NAME     U1 CT83
 '@S9S_MB_2U_LIB.S9S_MB_2U(SCH_1):PAGE66_I16@PURE_QUANTA.SOCKET4677_AZIF0045P001C01CS(CHIPS)':
 'UPI3_RX_DP18': CDS_PINID='UPI3_RX_DP18';
NODE_NAME     U1 CV81
 '@S9S_MB_2U_LIB.S9S_MB_2U(SCH_1):PAGE66_I16@PURE_QUANTA.SOCKET4677_AZIF0045P001C01CS(CHIPS)':
 'UPI3_RX_DP19': CDS_PINID='UPI3_RX_DP19';
NODE_NAME     U1 CN82
 '@S9S_MB_2U_LIB.S9S_MB_2U(SCH_1):PAGE66_I16@PURE_QUANTA.SOCKET4677_AZIF0045P001C01CS(CHIPS)':
 'UPI3_RX_DP20': CDS_PINID='UPI3_RX_DP20';
NODE_NAME     U1 CR80
 '@S9S_MB_2U_LIB.S9S_MB_2U(SCH_1):PAGE66_I16@PURE_QUANTA.SOCKET4677_AZIF0045P001C01CS(CHIPS)':
 'UPI3_RX_DP21': CDS_PINID='UPI3_RX_DP21';
NODE_NAME     U1 CU80
 '@S9S_MB_2U_LIB.S9S_MB_2U(SCH_1):PAGE66_I16@PURE_QUANTA.SOCKET4677_AZIF0045P001C01CS(CHIPS)':
 'UPI3_RX_DP22': CDS_PINID='UPI3_RX_DP22';
NODE_NAME     U1 DB79
 '@S9S_MB_2U_LIB.S9S_MB_2U(SCH_1):PAGE66_I16@PURE_QUANTA.SOCKET4677_AZIF0045P001C01CS(CHIPS)':
 'UPI3_RX_DP23': CDS_PINID='UPI3_RX_DP23';
NODE_NAME     C71 2
 '@S9S_MB_2U_LIB.S9S_MB_2U(SCH_1):PAGE68_I4@PURE_QUANTA.Q_CAP(CHIPS)':
 'B': CDS_PINID='B';
NODE_NAME     U1 EH42
 '@S9S_MB_2U_LIB.S9S_MB_2U(SCH_1):PAGE70_I2@PURE_QUANTA.SOCKET4677_AZIF0045P001C01CS(CHIPS)':
 'VSS1312': CDS_PINID='VSS1312';
NODE_NAME     U1 EH55
 '@S9S_MB_2U_LIB.S9S_MB_2U(SCH_1):PAGE70_I2@PURE_QUANTA.SOCKET4677_AZIF0045P001C01CS(CHIPS)':
 'VSS1315': CDS_PINID='VSS1315';
NODE_NAME     U1 EH61
 '@S9S_MB_2U_LIB.S9S_MB_2U(SCH_1):PAGE70_I2@PURE_QUANTA.SOCKET4677_AZIF0045P001C01CS(CHIPS)':
 'VSS1319': CDS_PINID='VSS1319';
NODE_NAME     U1 EH67
 '@S9S_MB_2U_LIB.S9S_MB_2U(SCH_1):PAGE70_I2@PURE_QUANTA.SOCKET4677_AZIF0045P001C01CS(CHIPS)':
 'VSS1320': CDS_PINID='VSS1320';
NODE_NAME     U1 EH79
 '@S9S_MB_2U_LIB.S9S_MB_2U(SCH_1):PAGE70_I2@PURE_QUANTA.SOCKET4677_AZIF0045P001C01CS(CHIPS)':
 'VSS1322': CDS_PINID='VSS1322';
NODE_NAME     U1 EJ11
 '@S9S_MB_2U_LIB.S9S_MB_2U(SCH_1):PAGE70_I2@PURE_QUANTA.SOCKET4677_AZIF0045P001C01CS(CHIPS)':
 'VSS1325': CDS_PINID='VSS1325';
NODE_NAME     U1 EJ17
 '@S9S_MB_2U_LIB.S9S_MB_2U(SCH_1):PAGE70_I2@PURE_QUANTA.SOCKET4677_AZIF0045P001C01CS(CHIPS)':
 'VSS1328': CDS_PINID='VSS1328';
NODE_NAME     U1 EJ25
 '@S9S_MB_2U_LIB.S9S_MB_2U(SCH_1):PAGE70_I2@PURE_QUANTA.SOCKET4677_AZIF0045P001C01CS(CHIPS)':
 'VSS1331': CDS_PINID='VSS1331';
NODE_NAME     U1 EJ35
 '@S9S_MB_2U_LIB.S9S_MB_2U(SCH_1):PAGE70_I2@PURE_QUANTA.SOCKET4677_AZIF0045P001C01CS(CHIPS)':
 'VSS1334': CDS_PINID='VSS1334';
NODE_NAME     U1 EJ54
 '@S9S_MB_2U_LIB.S9S_MB_2U(SCH_1):PAGE70_I2@PURE_QUANTA.SOCKET4677_AZIF0045P001C01CS(CHIPS)':
 'VSS1340': CDS_PINID='VSS1340';
NODE_NAME     U1 EJ62
 '@S9S_MB_2U_LIB.S9S_MB_2U(SCH_1):PAGE70_I2@PURE_QUANTA.SOCKET4677_AZIF0045P001C01CS(CHIPS)':
 'VSS1343': CDS_PINID='VSS1343';
NODE_NAME     U1 EJ68
 '@S9S_MB_2U_LIB.S9S_MB_2U(SCH_1):PAGE70_I2@PURE_QUANTA.SOCKET4677_AZIF0045P001C01CS(CHIPS)':
 'VSS1345': CDS_PINID='VSS1345';
NODE_NAME     U1 EJ72
 '@S9S_MB_2U_LIB.S9S_MB_2U(SCH_1):PAGE70_I2@PURE_QUANTA.SOCKET4677_AZIF0045P001C01CS(CHIPS)':
 'VSS1347': CDS_PINID='VSS1347';
NODE_NAME     U1 EK16
 '@S9S_MB_2U_LIB.S9S_MB_2U(SCH_1):PAGE70_I2@PURE_QUANTA.SOCKET4677_AZIF0045P001C01CS(CHIPS)':
 'VSS1355': CDS_PINID='VSS1355';
NODE_NAME     U1 EK20
 '@S9S_MB_2U_LIB.S9S_MB_2U(SCH_1):PAGE70_I2@PURE_QUANTA.SOCKET4677_AZIF0045P001C01CS(CHIPS)':
 'VSS1357': CDS_PINID='VSS1357';
NODE_NAME     U1 EK26
 '@S9S_MB_2U_LIB.S9S_MB_2U(SCH_1):PAGE70_I2@PURE_QUANTA.SOCKET4677_AZIF0045P001C01CS(CHIPS)':
 'VSS1359': CDS_PINID='VSS1359';
NODE_NAME     U1 EK44
 '@S9S_MB_2U_LIB.S9S_MB_2U(SCH_1):PAGE70_I2@PURE_QUANTA.SOCKET4677_AZIF0045P001C01CS(CHIPS)':
 'VSS1366': CDS_PINID='VSS1366';
NODE_NAME     U1 EK51
 '@S9S_MB_2U_LIB.S9S_MB_2U(SCH_1):PAGE70_I2@PURE_QUANTA.SOCKET4677_AZIF0045P001C01CS(CHIPS)':
 'VSS1368': CDS_PINID='VSS1368';
NODE_NAME     U1 EK53
 '@S9S_MB_2U_LIB.S9S_MB_2U(SCH_1):PAGE70_I2@PURE_QUANTA.SOCKET4677_AZIF0045P001C01CS(CHIPS)':
 'VSS1369': CDS_PINID='VSS1369';
NODE_NAME     U1 EK59
 '@S9S_MB_2U_LIB.S9S_MB_2U(SCH_1):PAGE70_I2@PURE_QUANTA.SOCKET4677_AZIF0045P001C01CS(CHIPS)':
 'VSS1371': CDS_PINID='VSS1371';
NODE_NAME     U1 EK63
 '@S9S_MB_2U_LIB.S9S_MB_2U(SCH_1):PAGE70_I2@PURE_QUANTA.SOCKET4677_AZIF0045P001C01CS(CHIPS)':
 'VSS1372': CDS_PINID='VSS1372';
NODE_NAME     U1 EK71
 '@S9S_MB_2U_LIB.S9S_MB_2U(SCH_1):PAGE70_I2@PURE_QUANTA.SOCKET4677_AZIF0045P001C01CS(CHIPS)':
 'VSS1375': CDS_PINID='VSS1375';
NODE_NAME     U1 EK77
 '@S9S_MB_2U_LIB.S9S_MB_2U(SCH_1):PAGE70_I2@PURE_QUANTA.SOCKET4677_AZIF0045P001C01CS(CHIPS)':
 'VSS1377': CDS_PINID='VSS1377';
NODE_NAME     U1 EK79
 '@S9S_MB_2U_LIB.S9S_MB_2U(SCH_1):PAGE70_I2@PURE_QUANTA.SOCKET4677_AZIF0045P001C01CS(CHIPS)':
 'VSS1378': CDS_PINID='VSS1378';
NODE_NAME     U1 EK83
 '@S9S_MB_2U_LIB.S9S_MB_2U(SCH_1):PAGE70_I2@PURE_QUANTA.SOCKET4677_AZIF0045P001C01CS(CHIPS)':
 'VSS1379': CDS_PINID='VSS1379';
NODE_NAME     U1 EK89
 '@S9S_MB_2U_LIB.S9S_MB_2U(SCH_1):PAGE70_I2@PURE_QUANTA.SOCKET4677_AZIF0045P001C01CS(CHIPS)':
 'VSS1380': CDS_PINID='VSS1380';
NODE_NAME     U1 EL15
 '@S9S_MB_2U_LIB.S9S_MB_2U(SCH_1):PAGE70_I2@PURE_QUANTA.SOCKET4677_AZIF0045P001C01CS(CHIPS)':
 'VSS1381': CDS_PINID='VSS1381';
NODE_NAME     U1 EL52
 '@S9S_MB_2U_LIB.S9S_MB_2U(SCH_1):PAGE70_I2@PURE_QUANTA.SOCKET4677_AZIF0045P001C01CS(CHIPS)':
 'VSS1391': CDS_PINID='VSS1391';
NODE_NAME     U1 EL58
 '@S9S_MB_2U_LIB.S9S_MB_2U(SCH_1):PAGE70_I2@PURE_QUANTA.SOCKET4677_AZIF0045P001C01CS(CHIPS)':
 'VSS1394': CDS_PINID='VSS1394';
NODE_NAME     U1 EL7
 '@S9S_MB_2U_LIB.S9S_MB_2U(SCH_1):PAGE70_I2@PURE_QUANTA.SOCKET4677_AZIF0045P001C01CS(CHIPS)':
 'VSS1396': CDS_PINID='VSS1396';
NODE_NAME     U1 EL70
 '@S9S_MB_2U_LIB.S9S_MB_2U(SCH_1):PAGE70_I2@PURE_QUANTA.SOCKET4677_AZIF0045P001C01CS(CHIPS)':
 'VSS1397': CDS_PINID='VSS1397';
NODE_NAME     U1 EL72
 '@S9S_MB_2U_LIB.S9S_MB_2U(SCH_1):PAGE70_I2@PURE_QUANTA.SOCKET4677_AZIF0045P001C01CS(CHIPS)':
 'VSS1398': CDS_PINID='VSS1398';
NODE_NAME     U1 EL86
 '@S9S_MB_2U_LIB.S9S_MB_2U(SCH_1):PAGE70_I2@PURE_QUANTA.SOCKET4677_AZIF0045P001C01CS(CHIPS)':
 'VSS1400': CDS_PINID='VSS1400';
NODE_NAME     U1 EL9
 '@S9S_MB_2U_LIB.S9S_MB_2U(SCH_1):PAGE70_I2@PURE_QUANTA.SOCKET4677_AZIF0045P001C01CS(CHIPS)':
 'VSS1401': CDS_PINID='VSS1401';
NODE_NAME     U1 EM49
 '@S9S_MB_2U_LIB.S9S_MB_2U(SCH_1):PAGE70_I2@PURE_QUANTA.SOCKET4677_AZIF0045P001C01CS(CHIPS)':
 'VSS1405': CDS_PINID='VSS1405';
NODE_NAME     U1 EM79
 '@S9S_MB_2U_LIB.S9S_MB_2U(SCH_1):PAGE70_I2@PURE_QUANTA.SOCKET4677_AZIF0045P001C01CS(CHIPS)':
 'VSS1409': CDS_PINID='VSS1409';
NODE_NAME     U1 EH36
 '@S9S_MB_2U_LIB.S9S_MB_2U(SCH_1):PAGE70_I2@PURE_QUANTA.SOCKET4677_AZIF0045P001C01CS(CHIPS)':
 'VSS1419': CDS_PINID='VSS1419';
NODE_NAME     U1 EH49
 '@S9S_MB_2U_LIB.S9S_MB_2U(SCH_1):PAGE70_I2@PURE_QUANTA.SOCKET4677_AZIF0045P001C01CS(CHIPS)':
 'VSS1421': CDS_PINID='VSS1421';
NODE_NAME     U1 EH73
 '@S9S_MB_2U_LIB.S9S_MB_2U(SCH_1):PAGE70_I2@PURE_QUANTA.SOCKET4677_AZIF0045P001C01CS(CHIPS)':
 'VSS1422': CDS_PINID='VSS1422';
NODE_NAME     U1 EH81
 '@S9S_MB_2U_LIB.S9S_MB_2U(SCH_1):PAGE70_I2@PURE_QUANTA.SOCKET4677_AZIF0045P001C01CS(CHIPS)':
 'VSS1423': CDS_PINID='VSS1423';
NODE_NAME     U1 EH83
 '@S9S_MB_2U_LIB.S9S_MB_2U(SCH_1):PAGE70_I2@PURE_QUANTA.SOCKET4677_AZIF0045P001C01CS(CHIPS)':
 'VSS1424': CDS_PINID='VSS1424';
NODE_NAME     U1 EJ13
 '@S9S_MB_2U_LIB.S9S_MB_2U(SCH_1):PAGE70_I2@PURE_QUANTA.SOCKET4677_AZIF0045P001C01CS(CHIPS)':
 'VSS1425': CDS_PINID='VSS1425';
NODE_NAME     U1 EJ19
 '@S9S_MB_2U_LIB.S9S_MB_2U(SCH_1):PAGE70_I2@PURE_QUANTA.SOCKET4677_AZIF0045P001C01CS(CHIPS)':
 'VSS1426': CDS_PINID='VSS1426';
NODE_NAME     U1 EN39
 '@S9S_MB_2U_LIB.S9S_MB_2U(SCH_1):PAGE70_I2@PURE_QUANTA.SOCKET4677_AZIF0045P001C01CS(CHIPS)':
 'VSS1427': CDS_PINID='VSS1427';
NODE_NAME     U1 EJ23
 '@S9S_MB_2U_LIB.S9S_MB_2U(SCH_1):PAGE70_I2@PURE_QUANTA.SOCKET4677_AZIF0045P001C01CS(CHIPS)':
 'VSS1428': CDS_PINID='VSS1428';
NODE_NAME     U1 EJ29
 '@S9S_MB_2U_LIB.S9S_MB_2U(SCH_1):PAGE70_I2@PURE_QUANTA.SOCKET4677_AZIF0045P001C01CS(CHIPS)':
 'VSS1429': CDS_PINID='VSS1429';
NODE_NAME     U1 EJ31
 '@S9S_MB_2U_LIB.S9S_MB_2U(SCH_1):PAGE70_I2@PURE_QUANTA.SOCKET4677_AZIF0045P001C01CS(CHIPS)':
 'VSS1430': CDS_PINID='VSS1430';
NODE_NAME     U1 EJ37
 '@S9S_MB_2U_LIB.S9S_MB_2U(SCH_1):PAGE70_I2@PURE_QUANTA.SOCKET4677_AZIF0045P001C01CS(CHIPS)':
 'VSS1431': CDS_PINID='VSS1431';
NODE_NAME     U1 EJ41
 '@S9S_MB_2U_LIB.S9S_MB_2U(SCH_1):PAGE70_I2@PURE_QUANTA.SOCKET4677_AZIF0045P001C01CS(CHIPS)':
 'VSS1432': CDS_PINID='VSS1432';
NODE_NAME     U1 EJ43
 '@S9S_MB_2U_LIB.S9S_MB_2U(SCH_1):PAGE70_I2@PURE_QUANTA.SOCKET4677_AZIF0045P001C01CS(CHIPS)':
 'VSS1433': CDS_PINID='VSS1433';
NODE_NAME     U1 EJ48
 '@S9S_MB_2U_LIB.S9S_MB_2U(SCH_1):PAGE70_I2@PURE_QUANTA.SOCKET4677_AZIF0045P001C01CS(CHIPS)':
 'VSS1434': CDS_PINID='VSS1434';
NODE_NAME     U1 EJ50
 '@S9S_MB_2U_LIB.S9S_MB_2U(SCH_1):PAGE70_I2@PURE_QUANTA.SOCKET4677_AZIF0045P001C01CS(CHIPS)':
 'VSS1435': CDS_PINID='VSS1435';
NODE_NAME     U1 EN58
 '@S9S_MB_2U_LIB.S9S_MB_2U(SCH_1):PAGE70_I2@PURE_QUANTA.SOCKET4677_AZIF0045P001C01CS(CHIPS)':
 'VSS1436': CDS_PINID='VSS1436';
NODE_NAME     U1 EN60
 '@S9S_MB_2U_LIB.S9S_MB_2U(SCH_1):PAGE70_I2@PURE_QUANTA.SOCKET4677_AZIF0045P001C01CS(CHIPS)':
 'VSS1437': CDS_PINID='VSS1437';
NODE_NAME     U1 EN62
 '@S9S_MB_2U_LIB.S9S_MB_2U(SCH_1):PAGE70_I2@PURE_QUANTA.SOCKET4677_AZIF0045P001C01CS(CHIPS)':
 'VSS1438': CDS_PINID='VSS1438';
NODE_NAME     U1 EJ56
 '@S9S_MB_2U_LIB.S9S_MB_2U(SCH_1):PAGE70_I2@PURE_QUANTA.SOCKET4677_AZIF0045P001C01CS(CHIPS)':
 'VSS1439': CDS_PINID='VSS1439';
NODE_NAME     U1 EN66
 '@S9S_MB_2U_LIB.S9S_MB_2U(SCH_1):PAGE70_I2@PURE_QUANTA.SOCKET4677_AZIF0045P001C01CS(CHIPS)':
 'VSS1440': CDS_PINID='VSS1440';
NODE_NAME     U1 EN72
 '@S9S_MB_2U_LIB.S9S_MB_2U(SCH_1):PAGE70_I2@PURE_QUANTA.SOCKET4677_AZIF0045P001C01CS(CHIPS)':
 'VSS1441': CDS_PINID='VSS1441';
NODE_NAME     U1 EJ60
 '@S9S_MB_2U_LIB.S9S_MB_2U(SCH_1):PAGE70_I2@PURE_QUANTA.SOCKET4677_AZIF0045P001C01CS(CHIPS)':
 'VSS1442': CDS_PINID='VSS1442';
NODE_NAME     U1 EJ66
 '@S9S_MB_2U_LIB.S9S_MB_2U(SCH_1):PAGE70_I2@PURE_QUANTA.SOCKET4677_AZIF0045P001C01CS(CHIPS)':
 'VSS1443': CDS_PINID='VSS1443';
NODE_NAME     U1 EJ7
 '@S9S_MB_2U_LIB.S9S_MB_2U(SCH_1):PAGE70_I2@PURE_QUANTA.SOCKET4677_AZIF0045P001C01CS(CHIPS)':
 'VSS1444': CDS_PINID='VSS1444';
NODE_NAME     U1 EN88
 '@S9S_MB_2U_LIB.S9S_MB_2U(SCH_1):PAGE70_I2@PURE_QUANTA.SOCKET4677_AZIF0045P001C01CS(CHIPS)':
 'VSS1445': CDS_PINID='VSS1445';
NODE_NAME     U1 EN9
 '@S9S_MB_2U_LIB.S9S_MB_2U(SCH_1):PAGE70_I2@PURE_QUANTA.SOCKET4677_AZIF0045P001C01CS(CHIPS)':
 'VSS1446': CDS_PINID='VSS1446';
NODE_NAME     U1 EJ74
 '@S9S_MB_2U_LIB.S9S_MB_2U(SCH_1):PAGE70_I2@PURE_QUANTA.SOCKET4677_AZIF0045P001C01CS(CHIPS)':
 'VSS1447': CDS_PINID='VSS1447';
NODE_NAME     U1 EJ78
 '@S9S_MB_2U_LIB.S9S_MB_2U(SCH_1):PAGE70_I2@PURE_QUANTA.SOCKET4677_AZIF0045P001C01CS(CHIPS)':
 'VSS1448': CDS_PINID='VSS1448';
NODE_NAME     U1 EJ88
 '@S9S_MB_2U_LIB.S9S_MB_2U(SCH_1):PAGE70_I2@PURE_QUANTA.SOCKET4677_AZIF0045P001C01CS(CHIPS)':
 'VSS1449': CDS_PINID='VSS1449';
NODE_NAME     U1 EJ9
 '@S9S_MB_2U_LIB.S9S_MB_2U(SCH_1):PAGE70_I2@PURE_QUANTA.SOCKET4677_AZIF0045P001C01CS(CHIPS)':
 'VSS1450': CDS_PINID='VSS1450';
NODE_NAME     U1 EK10
 '@S9S_MB_2U_LIB.S9S_MB_2U(SCH_1):PAGE70_I2@PURE_QUANTA.SOCKET4677_AZIF0045P001C01CS(CHIPS)':
 'VSS1451': CDS_PINID='VSS1451';
NODE_NAME     U1 EP69
 '@S9S_MB_2U_LIB.S9S_MB_2U(SCH_1):PAGE70_I2@PURE_QUANTA.SOCKET4677_AZIF0045P001C01CS(CHIPS)':
 'VSS1452': CDS_PINID='VSS1452';
NODE_NAME     U1 EP71
 '@S9S_MB_2U_LIB.S9S_MB_2U(SCH_1):PAGE70_I2@PURE_QUANTA.SOCKET4677_AZIF0045P001C01CS(CHIPS)':
 'VSS1453': CDS_PINID='VSS1453';
NODE_NAME     U1 EP77
 '@S9S_MB_2U_LIB.S9S_MB_2U(SCH_1):PAGE70_I2@PURE_QUANTA.SOCKET4677_AZIF0045P001C01CS(CHIPS)':
 'VSS1454': CDS_PINID='VSS1454';
NODE_NAME     U1 EK14
 '@S9S_MB_2U_LIB.S9S_MB_2U(SCH_1):PAGE70_I2@PURE_QUANTA.SOCKET4677_AZIF0045P001C01CS(CHIPS)':
 'VSS1455': CDS_PINID='VSS1455';
NODE_NAME     U1 ER15
 '@S9S_MB_2U_LIB.S9S_MB_2U(SCH_1):PAGE70_I2@PURE_QUANTA.SOCKET4677_AZIF0045P001C01CS(CHIPS)':
 'VSS1456': CDS_PINID='VSS1456';
NODE_NAME     U1 ER21
 '@S9S_MB_2U_LIB.S9S_MB_2U(SCH_1):PAGE70_I2@PURE_QUANTA.SOCKET4677_AZIF0045P001C01CS(CHIPS)':
 'VSS1457': CDS_PINID='VSS1457';
NODE_NAME     U1 EK2
 '@S9S_MB_2U_LIB.S9S_MB_2U(SCH_1):PAGE70_I2@PURE_QUANTA.SOCKET4677_AZIF0045P001C01CS(CHIPS)':
 'VSS1458': CDS_PINID='VSS1458';
NODE_NAME     U1 EK22
 '@S9S_MB_2U_LIB.S9S_MB_2U(SCH_1):PAGE70_I2@PURE_QUANTA.SOCKET4677_AZIF0045P001C01CS(CHIPS)':
 'VSS1459': CDS_PINID='VSS1459';
NODE_NAME     U1 EK28
 '@S9S_MB_2U_LIB.S9S_MB_2U(SCH_1):PAGE70_I2@PURE_QUANTA.SOCKET4677_AZIF0045P001C01CS(CHIPS)':
 'VSS1460': CDS_PINID='VSS1460';
NODE_NAME     U1 EK32
 '@S9S_MB_2U_LIB.S9S_MB_2U(SCH_1):PAGE70_I2@PURE_QUANTA.SOCKET4677_AZIF0045P001C01CS(CHIPS)':
 'VSS1461': CDS_PINID='VSS1461';
NODE_NAME     U1 ER39
 '@S9S_MB_2U_LIB.S9S_MB_2U(SCH_1):PAGE70_I2@PURE_QUANTA.SOCKET4677_AZIF0045P001C01CS(CHIPS)':
 'VSS1462': CDS_PINID='VSS1462';
NODE_NAME     U1 EK34
 '@S9S_MB_2U_LIB.S9S_MB_2U(SCH_1):PAGE70_I2@PURE_QUANTA.SOCKET4677_AZIF0045P001C01CS(CHIPS)':
 'VSS1463': CDS_PINID='VSS1463';
NODE_NAME     U1 ER52
 '@S9S_MB_2U_LIB.S9S_MB_2U(SCH_1):PAGE70_I2@PURE_QUANTA.SOCKET4677_AZIF0045P001C01CS(CHIPS)':
 'VSS1464': CDS_PINID='VSS1464';
NODE_NAME     U1 EK38
 '@S9S_MB_2U_LIB.S9S_MB_2U(SCH_1):PAGE70_I2@PURE_QUANTA.SOCKET4677_AZIF0045P001C01CS(CHIPS)':
 'VSS1465': CDS_PINID='VSS1465';
NODE_NAME     U1 EK4
 '@S9S_MB_2U_LIB.S9S_MB_2U(SCH_1):PAGE70_I2@PURE_QUANTA.SOCKET4677_AZIF0045P001C01CS(CHIPS)':
 'VSS1466': CDS_PINID='VSS1466';
NODE_NAME     U1 ER58
 '@S9S_MB_2U_LIB.S9S_MB_2U(SCH_1):PAGE70_I2@PURE_QUANTA.SOCKET4677_AZIF0045P001C01CS(CHIPS)':
 'VSS1467': CDS_PINID='VSS1467';
NODE_NAME     U1 ER64
 '@S9S_MB_2U_LIB.S9S_MB_2U(SCH_1):PAGE70_I2@PURE_QUANTA.SOCKET4677_AZIF0045P001C01CS(CHIPS)':
 'VSS1468': CDS_PINID='VSS1468';
NODE_NAME     U1 EK40
 '@S9S_MB_2U_LIB.S9S_MB_2U(SCH_1):PAGE70_I2@PURE_QUANTA.SOCKET4677_AZIF0045P001C01CS(CHIPS)':
 'VSS1469': CDS_PINID='VSS1469';
NODE_NAME     U1 EK47
 '@S9S_MB_2U_LIB.S9S_MB_2U(SCH_1):PAGE70_I2@PURE_QUANTA.SOCKET4677_AZIF0045P001C01CS(CHIPS)':
 'VSS1470': CDS_PINID='VSS1470';
NODE_NAME     U1 EK57
 '@S9S_MB_2U_LIB.S9S_MB_2U(SCH_1):PAGE70_I2@PURE_QUANTA.SOCKET4677_AZIF0045P001C01CS(CHIPS)':
 'VSS1471': CDS_PINID='VSS1471';
NODE_NAME     U1 EK65
 '@S9S_MB_2U_LIB.S9S_MB_2U(SCH_1):PAGE70_I2@PURE_QUANTA.SOCKET4677_AZIF0045P001C01CS(CHIPS)':
 'VSS1472': CDS_PINID='VSS1472';
NODE_NAME     U1 EK69
 '@S9S_MB_2U_LIB.S9S_MB_2U(SCH_1):PAGE70_I2@PURE_QUANTA.SOCKET4677_AZIF0045P001C01CS(CHIPS)':
 'VSS1473': CDS_PINID='VSS1473';
NODE_NAME     U1 EK75
 '@S9S_MB_2U_LIB.S9S_MB_2U(SCH_1):PAGE70_I2@PURE_QUANTA.SOCKET4677_AZIF0045P001C01CS(CHIPS)':
 'VSS1474': CDS_PINID='VSS1474';
NODE_NAME     U1 EL21
 '@S9S_MB_2U_LIB.S9S_MB_2U(SCH_1):PAGE70_I2@PURE_QUANTA.SOCKET4677_AZIF0045P001C01CS(CHIPS)':
 'VSS1475': CDS_PINID='VSS1475';
NODE_NAME     U1 ER9
 '@S9S_MB_2U_LIB.S9S_MB_2U(SCH_1):PAGE70_I2@PURE_QUANTA.SOCKET4677_AZIF0045P001C01CS(CHIPS)':
 'VSS1476': CDS_PINID='VSS1476';
NODE_NAME     U1 EL27
 '@S9S_MB_2U_LIB.S9S_MB_2U(SCH_1):PAGE70_I2@PURE_QUANTA.SOCKET4677_AZIF0045P001C01CS(CHIPS)':
 'VSS1477': CDS_PINID='VSS1477';
NODE_NAME     U1 ET14
 '@S9S_MB_2U_LIB.S9S_MB_2U(SCH_1):PAGE70_I2@PURE_QUANTA.SOCKET4677_AZIF0045P001C01CS(CHIPS)':
 'VSS1478': CDS_PINID='VSS1478';
NODE_NAME     U1 EL3
 '@S9S_MB_2U_LIB.S9S_MB_2U(SCH_1):PAGE70_I2@PURE_QUANTA.SOCKET4677_AZIF0045P001C01CS(CHIPS)':
 'VSS1479': CDS_PINID='VSS1479';
NODE_NAME     U1 ET20
 '@S9S_MB_2U_LIB.S9S_MB_2U(SCH_1):PAGE70_I2@PURE_QUANTA.SOCKET4677_AZIF0045P001C01CS(CHIPS)':
 'VSS1480': CDS_PINID='VSS1480';
NODE_NAME     U1 EL33
 '@S9S_MB_2U_LIB.S9S_MB_2U(SCH_1):PAGE70_I2@PURE_QUANTA.SOCKET4677_AZIF0045P001C01CS(CHIPS)':
 'VSS1481': CDS_PINID='VSS1481';
NODE_NAME     U1 ET26
 '@S9S_MB_2U_LIB.S9S_MB_2U(SCH_1):PAGE70_I2@PURE_QUANTA.SOCKET4677_AZIF0045P001C01CS(CHIPS)':
 'VSS1482': CDS_PINID='VSS1482';
NODE_NAME     U1 EL39
 '@S9S_MB_2U_LIB.S9S_MB_2U(SCH_1):PAGE70_I2@PURE_QUANTA.SOCKET4677_AZIF0045P001C01CS(CHIPS)':
 'VSS1483': CDS_PINID='VSS1483';
NODE_NAME     U1 ET32
 '@S9S_MB_2U_LIB.S9S_MB_2U(SCH_1):PAGE70_I2@PURE_QUANTA.SOCKET4677_AZIF0045P001C01CS(CHIPS)':
 'VSS1484': CDS_PINID='VSS1484';
NODE_NAME     U1 EL45
 '@S9S_MB_2U_LIB.S9S_MB_2U(SCH_1):PAGE70_I2@PURE_QUANTA.SOCKET4677_AZIF0045P001C01CS(CHIPS)':
 'VSS1485': CDS_PINID='VSS1485';
NODE_NAME     U1 EL5
 '@S9S_MB_2U_LIB.S9S_MB_2U(SCH_1):PAGE70_I2@PURE_QUANTA.SOCKET4677_AZIF0045P001C01CS(CHIPS)':
 'VSS1486': CDS_PINID='VSS1486';
NODE_NAME     U1 EL64
 '@S9S_MB_2U_LIB.S9S_MB_2U(SCH_1):PAGE70_I2@PURE_QUANTA.SOCKET4677_AZIF0045P001C01CS(CHIPS)':
 'VSS1488': CDS_PINID='VSS1488';
NODE_NAME     U1 EL76
 '@S9S_MB_2U_LIB.S9S_MB_2U(SCH_1):PAGE70_I2@PURE_QUANTA.SOCKET4677_AZIF0045P001C01CS(CHIPS)':
 'VSS1489': CDS_PINID='VSS1489';
NODE_NAME     U1 ET53
 '@S9S_MB_2U_LIB.S9S_MB_2U(SCH_1):PAGE70_I2@PURE_QUANTA.SOCKET4677_AZIF0045P001C01CS(CHIPS)':
 'VSS1491': CDS_PINID='VSS1491';
NODE_NAME     U1 EM42
 '@S9S_MB_2U_LIB.S9S_MB_2U(SCH_1):PAGE70_I2@PURE_QUANTA.SOCKET4677_AZIF0045P001C01CS(CHIPS)':
 'VSS1492': CDS_PINID='VSS1492';
NODE_NAME     U1 ET59
 '@S9S_MB_2U_LIB.S9S_MB_2U(SCH_1):PAGE70_I2@PURE_QUANTA.SOCKET4677_AZIF0045P001C01CS(CHIPS)':
 'VSS1493': CDS_PINID='VSS1493';
NODE_NAME     U1 EM73
 '@S9S_MB_2U_LIB.S9S_MB_2U(SCH_1):PAGE70_I2@PURE_QUANTA.SOCKET4677_AZIF0045P001C01CS(CHIPS)':
 'VSS1496': CDS_PINID='VSS1496';
NODE_NAME     U1 EM8
 '@S9S_MB_2U_LIB.S9S_MB_2U(SCH_1):PAGE70_I2@PURE_QUANTA.SOCKET4677_AZIF0045P001C01CS(CHIPS)':
 'VSS1497': CDS_PINID='VSS1497';
NODE_NAME     U1 EM81
 '@S9S_MB_2U_LIB.S9S_MB_2U(SCH_1):PAGE70_I2@PURE_QUANTA.SOCKET4677_AZIF0045P001C01CS(CHIPS)':
 'VSS1498': CDS_PINID='VSS1498';
NODE_NAME     U1 EM83
 '@S9S_MB_2U_LIB.S9S_MB_2U(SCH_1):PAGE70_I2@PURE_QUANTA.SOCKET4677_AZIF0045P001C01CS(CHIPS)':
 'VSS1499': CDS_PINID='VSS1499';
NODE_NAME     U1 EN11
 '@S9S_MB_2U_LIB.S9S_MB_2U(SCH_1):PAGE70_I2@PURE_QUANTA.SOCKET4677_AZIF0045P001C01CS(CHIPS)':
 'VSS1500': CDS_PINID='VSS1500';
NODE_NAME     U1 EN13
 '@S9S_MB_2U_LIB.S9S_MB_2U(SCH_1):PAGE70_I2@PURE_QUANTA.SOCKET4677_AZIF0045P001C01CS(CHIPS)':
 'VSS1501': CDS_PINID='VSS1501';
NODE_NAME     U1 EN15
 '@S9S_MB_2U_LIB.S9S_MB_2U(SCH_1):PAGE70_I2@PURE_QUANTA.SOCKET4677_AZIF0045P001C01CS(CHIPS)':
 'VSS1503': CDS_PINID='VSS1503';
NODE_NAME     U1 EN17
 '@S9S_MB_2U_LIB.S9S_MB_2U(SCH_1):PAGE70_I2@PURE_QUANTA.SOCKET4677_AZIF0045P001C01CS(CHIPS)':
 'VSS1505': CDS_PINID='VSS1505';
NODE_NAME     U1 EN19
 '@S9S_MB_2U_LIB.S9S_MB_2U(SCH_1):PAGE70_I2@PURE_QUANTA.SOCKET4677_AZIF0045P001C01CS(CHIPS)':
 'VSS1506': CDS_PINID='VSS1506';
NODE_NAME     U1 EN21
 '@S9S_MB_2U_LIB.S9S_MB_2U(SCH_1):PAGE70_I2@PURE_QUANTA.SOCKET4677_AZIF0045P001C01CS(CHIPS)':
 'VSS1512': CDS_PINID='VSS1512';
NODE_NAME     U1 EN23
 '@S9S_MB_2U_LIB.S9S_MB_2U(SCH_1):PAGE70_I2@PURE_QUANTA.SOCKET4677_AZIF0045P001C01CS(CHIPS)':
 'VSS1513': CDS_PINID='VSS1513';
NODE_NAME     U1 EN25
 '@S9S_MB_2U_LIB.S9S_MB_2U(SCH_1):PAGE70_I2@PURE_QUANTA.SOCKET4677_AZIF0045P001C01CS(CHIPS)':
 'VSS1515': CDS_PINID='VSS1515';
NODE_NAME     U1 EN27
 '@S9S_MB_2U_LIB.S9S_MB_2U(SCH_1):PAGE70_I2@PURE_QUANTA.SOCKET4677_AZIF0045P001C01CS(CHIPS)':
 'VSS1517': CDS_PINID='VSS1517';
NODE_NAME     U1 EN29
 '@S9S_MB_2U_LIB.S9S_MB_2U(SCH_1):PAGE70_I2@PURE_QUANTA.SOCKET4677_AZIF0045P001C01CS(CHIPS)':
 'VSS1518': CDS_PINID='VSS1518';
NODE_NAME     U1 EN31
 '@S9S_MB_2U_LIB.S9S_MB_2U(SCH_1):PAGE70_I2@PURE_QUANTA.SOCKET4677_AZIF0045P001C01CS(CHIPS)':
 'VSS1520': CDS_PINID='VSS1520';
NODE_NAME     U1 EN33
 '@S9S_MB_2U_LIB.S9S_MB_2U(SCH_1):PAGE70_I2@PURE_QUANTA.SOCKET4677_AZIF0045P001C01CS(CHIPS)':
 'VSS1522': CDS_PINID='VSS1522';
NODE_NAME     U1 EN35
 '@S9S_MB_2U_LIB.S9S_MB_2U(SCH_1):PAGE70_I2@PURE_QUANTA.SOCKET4677_AZIF0045P001C01CS(CHIPS)':
 'VSS1524': CDS_PINID='VSS1524';
NODE_NAME     U1 EN37
 '@S9S_MB_2U_LIB.S9S_MB_2U(SCH_1):PAGE70_I2@PURE_QUANTA.SOCKET4677_AZIF0045P001C01CS(CHIPS)':
 'VSS1525': CDS_PINID='VSS1525';
NODE_NAME     U1 EN41
 '@S9S_MB_2U_LIB.S9S_MB_2U(SCH_1):PAGE70_I2@PURE_QUANTA.SOCKET4677_AZIF0045P001C01CS(CHIPS)':
 'VSS1526': CDS_PINID='VSS1526';
NODE_NAME     U1 EN43
 '@S9S_MB_2U_LIB.S9S_MB_2U(SCH_1):PAGE70_I2@PURE_QUANTA.SOCKET4677_AZIF0045P001C01CS(CHIPS)':
 'VSS1528': CDS_PINID='VSS1528';
NODE_NAME     U1 EN45
 '@S9S_MB_2U_LIB.S9S_MB_2U(SCH_1):PAGE70_I2@PURE_QUANTA.SOCKET4677_AZIF0045P001C01CS(CHIPS)':
 'VSS1529': CDS_PINID='VSS1529';
NODE_NAME     U1 EN48
 '@S9S_MB_2U_LIB.S9S_MB_2U(SCH_1):PAGE70_I2@PURE_QUANTA.SOCKET4677_AZIF0045P001C01CS(CHIPS)':
 'VSS1530': CDS_PINID='VSS1530';
NODE_NAME     U1 EN50
 '@S9S_MB_2U_LIB.S9S_MB_2U(SCH_1):PAGE70_I2@PURE_QUANTA.SOCKET4677_AZIF0045P001C01CS(CHIPS)':
 'VSS1531': CDS_PINID='VSS1531';
NODE_NAME     U1 EN52
 '@S9S_MB_2U_LIB.S9S_MB_2U(SCH_1):PAGE70_I2@PURE_QUANTA.SOCKET4677_AZIF0045P001C01CS(CHIPS)':
 'VSS1533': CDS_PINID='VSS1533';
NODE_NAME     U1 EN54
 '@S9S_MB_2U_LIB.S9S_MB_2U(SCH_1):PAGE70_I2@PURE_QUANTA.SOCKET4677_AZIF0045P001C01CS(CHIPS)':
 'VSS1537': CDS_PINID='VSS1537';
NODE_NAME     U1 EN56
 '@S9S_MB_2U_LIB.S9S_MB_2U(SCH_1):PAGE70_I2@PURE_QUANTA.SOCKET4677_AZIF0045P001C01CS(CHIPS)':
 'VSS1539': CDS_PINID='VSS1539';
NODE_NAME     U1 EN64
 '@S9S_MB_2U_LIB.S9S_MB_2U(SCH_1):PAGE70_I2@PURE_QUANTA.SOCKET4677_AZIF0045P001C01CS(CHIPS)':
 'VSS1540': CDS_PINID='VSS1540';
NODE_NAME     U1 EN78
 '@S9S_MB_2U_LIB.S9S_MB_2U(SCH_1):PAGE70_I2@PURE_QUANTA.SOCKET4677_AZIF0045P001C01CS(CHIPS)':
 'VSS1541': CDS_PINID='VSS1541';
NODE_NAME     U1 EN80
 '@S9S_MB_2U_LIB.S9S_MB_2U(SCH_1):PAGE70_I2@PURE_QUANTA.SOCKET4677_AZIF0045P001C01CS(CHIPS)':
 'VSS1542': CDS_PINID='VSS1542';
NODE_NAME     U1 EP67
 '@S9S_MB_2U_LIB.S9S_MB_2U(SCH_1):PAGE70_I2@PURE_QUANTA.SOCKET4677_AZIF0045P001C01CS(CHIPS)':
 'VSS1543': CDS_PINID='VSS1543';
NODE_NAME     U1 EP83
 '@S9S_MB_2U_LIB.S9S_MB_2U(SCH_1):PAGE70_I2@PURE_QUANTA.SOCKET4677_AZIF0045P001C01CS(CHIPS)':
 'VSS1545': CDS_PINID='VSS1545';
NODE_NAME     U1 ER27
 '@S9S_MB_2U_LIB.S9S_MB_2U(SCH_1):PAGE70_I2@PURE_QUANTA.SOCKET4677_AZIF0045P001C01CS(CHIPS)':
 'VSS1547': CDS_PINID='VSS1547';
NODE_NAME     U1 ER33
 '@S9S_MB_2U_LIB.S9S_MB_2U(SCH_1):PAGE70_I2@PURE_QUANTA.SOCKET4677_AZIF0045P001C01CS(CHIPS)':
 'VSS1548': CDS_PINID='VSS1548';
NODE_NAME     U1 ER5
 '@S9S_MB_2U_LIB.S9S_MB_2U(SCH_1):PAGE70_I2@PURE_QUANTA.SOCKET4677_AZIF0045P001C01CS(CHIPS)':
 'VSS1549': CDS_PINID='VSS1549';
NODE_NAME     U1 ER7
 '@S9S_MB_2U_LIB.S9S_MB_2U(SCH_1):PAGE70_I2@PURE_QUANTA.SOCKET4677_AZIF0045P001C01CS(CHIPS)':
 'VSS1550': CDS_PINID='VSS1550';
NODE_NAME     U1 ER70
 '@S9S_MB_2U_LIB.S9S_MB_2U(SCH_1):PAGE70_I2@PURE_QUANTA.SOCKET4677_AZIF0045P001C01CS(CHIPS)':
 'VSS1551': CDS_PINID='VSS1551';
NODE_NAME     U1 ER74
 '@S9S_MB_2U_LIB.S9S_MB_2U(SCH_1):PAGE70_I2@PURE_QUANTA.SOCKET4677_AZIF0045P001C01CS(CHIPS)':
 'VSS1552': CDS_PINID='VSS1552';
NODE_NAME     U1 ER78
 '@S9S_MB_2U_LIB.S9S_MB_2U(SCH_1):PAGE70_I2@PURE_QUANTA.SOCKET4677_AZIF0045P001C01CS(CHIPS)':
 'VSS1553': CDS_PINID='VSS1553';
NODE_NAME     U1 ER80
 '@S9S_MB_2U_LIB.S9S_MB_2U(SCH_1):PAGE70_I2@PURE_QUANTA.SOCKET4677_AZIF0045P001C01CS(CHIPS)':
 'VSS1554': CDS_PINID='VSS1554';
NODE_NAME     U1 ER84
 '@S9S_MB_2U_LIB.S9S_MB_2U(SCH_1):PAGE70_I2@PURE_QUANTA.SOCKET4677_AZIF0045P001C01CS(CHIPS)':
 'VSS1555': CDS_PINID='VSS1555';
NODE_NAME     U1 ER86
 '@S9S_MB_2U_LIB.S9S_MB_2U(SCH_1):PAGE70_I2@PURE_QUANTA.SOCKET4677_AZIF0045P001C01CS(CHIPS)':
 'VSS1556': CDS_PINID='VSS1556';
NODE_NAME     U1 ET10
 '@S9S_MB_2U_LIB.S9S_MB_2U(SCH_1):PAGE70_I2@PURE_QUANTA.SOCKET4677_AZIF0045P001C01CS(CHIPS)':
 'VSS1557': CDS_PINID='VSS1557';
NODE_NAME     U1 ET16
 '@S9S_MB_2U_LIB.S9S_MB_2U(SCH_1):PAGE70_I2@PURE_QUANTA.SOCKET4677_AZIF0045P001C01CS(CHIPS)':
 'VSS1559': CDS_PINID='VSS1559';
NODE_NAME     U1 ET22
 '@S9S_MB_2U_LIB.S9S_MB_2U(SCH_1):PAGE70_I2@PURE_QUANTA.SOCKET4677_AZIF0045P001C01CS(CHIPS)':
 'VSS1561': CDS_PINID='VSS1561';
NODE_NAME     U1 ET28
 '@S9S_MB_2U_LIB.S9S_MB_2U(SCH_1):PAGE70_I2@PURE_QUANTA.SOCKET4677_AZIF0045P001C01CS(CHIPS)':
 'VSS1562': CDS_PINID='VSS1562';
NODE_NAME     U1 ET34
 '@S9S_MB_2U_LIB.S9S_MB_2U(SCH_1):PAGE70_I2@PURE_QUANTA.SOCKET4677_AZIF0045P001C01CS(CHIPS)':
 'VSS1563': CDS_PINID='VSS1563';
NODE_NAME     U1 ET38
 '@S9S_MB_2U_LIB.S9S_MB_2U(SCH_1):PAGE70_I2@PURE_QUANTA.SOCKET4677_AZIF0045P001C01CS(CHIPS)':
 'VSS1565': CDS_PINID='VSS1565';
NODE_NAME     U1 ET57
 '@S9S_MB_2U_LIB.S9S_MB_2U(SCH_1):PAGE70_I2@PURE_QUANTA.SOCKET4677_AZIF0045P001C01CS(CHIPS)':
 'VSS1569': CDS_PINID='VSS1569';
NODE_NAME     U1 ER41
 '@S9S_MB_2U_LIB.S9S_MB_2U(SCH_1):PAGE70_I2@PURE_QUANTA.SOCKET4677_AZIF0045P001C01CS(CHIPS)':
 'VSS1834': CDS_PINID='VSS1834';
NODE_NAME     U1 ER43
 '@S9S_MB_2U_LIB.S9S_MB_2U(SCH_1):PAGE70_I2@PURE_QUANTA.SOCKET4677_AZIF0045P001C01CS(CHIPS)':
 'VSS1835': CDS_PINID='VSS1835';
NODE_NAME     U1 ER48
 '@S9S_MB_2U_LIB.S9S_MB_2U(SCH_1):PAGE70_I2@PURE_QUANTA.SOCKET4677_AZIF0045P001C01CS(CHIPS)':
 'VSS1836': CDS_PINID='VSS1836';
NODE_NAME     U1 ER50
 '@S9S_MB_2U_LIB.S9S_MB_2U(SCH_1):PAGE70_I2@PURE_QUANTA.SOCKET4677_AZIF0045P001C01CS(CHIPS)':
 'VSS1837': CDS_PINID='VSS1837';
NODE_NAME     U1 DY12
 '@S9S_MB_2U_LIB.S9S_MB_2U(SCH_1):PAGE70_I5@PURE_QUANTA.SOCKET4677_AZIF0045P001C01CS(CHIPS)':
 'VSS1111': CDS_PINID='VSS1111';
NODE_NAME     U1 DY16
 '@S9S_MB_2U_LIB.S9S_MB_2U(SCH_1):PAGE70_I5@PURE_QUANTA.SOCKET4677_AZIF0045P001C01CS(CHIPS)':
 'VSS1112': CDS_PINID='VSS1112';
NODE_NAME     U1 DY4
 '@S9S_MB_2U_LIB.S9S_MB_2U(SCH_1):PAGE70_I5@PURE_QUANTA.SOCKET4677_AZIF0045P001C01CS(CHIPS)':
 'VSS1115': CDS_PINID='VSS1115';
NODE_NAME     U1 DY42
 '@S9S_MB_2U_LIB.S9S_MB_2U(SCH_1):PAGE70_I5@PURE_QUANTA.SOCKET4677_AZIF0045P001C01CS(CHIPS)':
 'VSS1116': CDS_PINID='VSS1116';
NODE_NAME     U1 EA39
 '@S9S_MB_2U_LIB.S9S_MB_2U(SCH_1):PAGE70_I5@PURE_QUANTA.SOCKET4677_AZIF0045P001C01CS(CHIPS)':
 'VSS1141': CDS_PINID='VSS1141';
NODE_NAME     U1 EA45
 '@S9S_MB_2U_LIB.S9S_MB_2U(SCH_1):PAGE70_I5@PURE_QUANTA.SOCKET4677_AZIF0045P001C01CS(CHIPS)':
 'VSS1142': CDS_PINID='VSS1142';
NODE_NAME     U1 EA52
 '@S9S_MB_2U_LIB.S9S_MB_2U(SCH_1):PAGE70_I5@PURE_QUANTA.SOCKET4677_AZIF0045P001C01CS(CHIPS)':
 'VSS1144': CDS_PINID='VSS1144';
NODE_NAME     U1 EA58
 '@S9S_MB_2U_LIB.S9S_MB_2U(SCH_1):PAGE70_I5@PURE_QUANTA.SOCKET4677_AZIF0045P001C01CS(CHIPS)':
 'VSS1145': CDS_PINID='VSS1145';
NODE_NAME     U1 EA64
 '@S9S_MB_2U_LIB.S9S_MB_2U(SCH_1):PAGE70_I5@PURE_QUANTA.SOCKET4677_AZIF0045P001C01CS(CHIPS)':
 'VSS1146': CDS_PINID='VSS1146';
NODE_NAME     U1 EB16
 '@S9S_MB_2U_LIB.S9S_MB_2U(SCH_1):PAGE70_I5@PURE_QUANTA.SOCKET4677_AZIF0045P001C01CS(CHIPS)':
 'VSS1155': CDS_PINID='VSS1155';
NODE_NAME     U1 EB20
 '@S9S_MB_2U_LIB.S9S_MB_2U(SCH_1):PAGE70_I5@PURE_QUANTA.SOCKET4677_AZIF0045P001C01CS(CHIPS)':
 'VSS1156': CDS_PINID='VSS1156';
NODE_NAME     U1 EB26
 '@S9S_MB_2U_LIB.S9S_MB_2U(SCH_1):PAGE70_I5@PURE_QUANTA.SOCKET4677_AZIF0045P001C01CS(CHIPS)':
 'VSS1158': CDS_PINID='VSS1158';
NODE_NAME     U1 EB34
 '@S9S_MB_2U_LIB.S9S_MB_2U(SCH_1):PAGE70_I5@PURE_QUANTA.SOCKET4677_AZIF0045P001C01CS(CHIPS)':
 'VSS1161': CDS_PINID='VSS1161';
NODE_NAME     U1 EB4
 '@S9S_MB_2U_LIB.S9S_MB_2U(SCH_1):PAGE70_I5@PURE_QUANTA.SOCKET4677_AZIF0045P001C01CS(CHIPS)':
 'VSS1163': CDS_PINID='VSS1163';
NODE_NAME     U1 EB44
 '@S9S_MB_2U_LIB.S9S_MB_2U(SCH_1):PAGE70_I5@PURE_QUANTA.SOCKET4677_AZIF0045P001C01CS(CHIPS)':
 'VSS1165': CDS_PINID='VSS1165';
NODE_NAME     U1 EB51
 '@S9S_MB_2U_LIB.S9S_MB_2U(SCH_1):PAGE70_I5@PURE_QUANTA.SOCKET4677_AZIF0045P001C01CS(CHIPS)':
 'VSS1167': CDS_PINID='VSS1167';
NODE_NAME     U1 EB53
 '@S9S_MB_2U_LIB.S9S_MB_2U(SCH_1):PAGE70_I5@PURE_QUANTA.SOCKET4677_AZIF0045P001C01CS(CHIPS)':
 'VSS1168': CDS_PINID='VSS1168';
NODE_NAME     U1 EB59
 '@S9S_MB_2U_LIB.S9S_MB_2U(SCH_1):PAGE70_I5@PURE_QUANTA.SOCKET4677_AZIF0045P001C01CS(CHIPS)':
 'VSS1170': CDS_PINID='VSS1170';
NODE_NAME     U1 EB63
 '@S9S_MB_2U_LIB.S9S_MB_2U(SCH_1):PAGE70_I5@PURE_QUANTA.SOCKET4677_AZIF0045P001C01CS(CHIPS)':
 'VSS1171': CDS_PINID='VSS1171';
NODE_NAME     U1 EB91
 '@S9S_MB_2U_LIB.S9S_MB_2U(SCH_1):PAGE70_I5@PURE_QUANTA.SOCKET4677_AZIF0045P001C01CS(CHIPS)':
 'VSS1180': CDS_PINID='VSS1180';
NODE_NAME     U1 EC25
 '@S9S_MB_2U_LIB.S9S_MB_2U(SCH_1):PAGE70_I5@PURE_QUANTA.SOCKET4677_AZIF0045P001C01CS(CHIPS)':
 'VSS1185': CDS_PINID='VSS1185';
NODE_NAME     U1 EC35
 '@S9S_MB_2U_LIB.S9S_MB_2U(SCH_1):PAGE70_I5@PURE_QUANTA.SOCKET4677_AZIF0045P001C01CS(CHIPS)':
 'VSS1188': CDS_PINID='VSS1188';
NODE_NAME     U1 EC5
 '@S9S_MB_2U_LIB.S9S_MB_2U(SCH_1):PAGE70_I5@PURE_QUANTA.SOCKET4677_AZIF0045P001C01CS(CHIPS)':
 'VSS1193': CDS_PINID='VSS1193';
NODE_NAME     U1 EC54
 '@S9S_MB_2U_LIB.S9S_MB_2U(SCH_1):PAGE70_I5@PURE_QUANTA.SOCKET4677_AZIF0045P001C01CS(CHIPS)':
 'VSS1195': CDS_PINID='VSS1195';
NODE_NAME     U1 EC60
 '@S9S_MB_2U_LIB.S9S_MB_2U(SCH_1):PAGE70_I5@PURE_QUANTA.SOCKET4677_AZIF0045P001C01CS(CHIPS)':
 'VSS1197': CDS_PINID='VSS1197';
NODE_NAME     U1 EC62
 '@S9S_MB_2U_LIB.S9S_MB_2U(SCH_1):PAGE70_I5@PURE_QUANTA.SOCKET4677_AZIF0045P001C01CS(CHIPS)':
 'VSS1198': CDS_PINID='VSS1198';
NODE_NAME     U1 EC68
 '@S9S_MB_2U_LIB.S9S_MB_2U(SCH_1):PAGE70_I5@PURE_QUANTA.SOCKET4677_AZIF0045P001C01CS(CHIPS)':
 'VSS1200': CDS_PINID='VSS1200';
NODE_NAME     U1 ED12
 '@S9S_MB_2U_LIB.S9S_MB_2U(SCH_1):PAGE70_I5@PURE_QUANTA.SOCKET4677_AZIF0045P001C01CS(CHIPS)':
 'VSS1208': CDS_PINID='VSS1208';
NODE_NAME     U1 ED18
 '@S9S_MB_2U_LIB.S9S_MB_2U(SCH_1):PAGE70_I5@PURE_QUANTA.SOCKET4677_AZIF0045P001C01CS(CHIPS)':
 'VSS1210': CDS_PINID='VSS1210';
NODE_NAME     U1 ED42
 '@S9S_MB_2U_LIB.S9S_MB_2U(SCH_1):PAGE70_I5@PURE_QUANTA.SOCKET4677_AZIF0045P001C01CS(CHIPS)':
 'VSS1217': CDS_PINID='VSS1217';
NODE_NAME     U1 ED55
 '@S9S_MB_2U_LIB.S9S_MB_2U(SCH_1):PAGE70_I5@PURE_QUANTA.SOCKET4677_AZIF0045P001C01CS(CHIPS)':
 'VSS1220': CDS_PINID='VSS1220';
NODE_NAME     U1 ED61
 '@S9S_MB_2U_LIB.S9S_MB_2U(SCH_1):PAGE70_I5@PURE_QUANTA.SOCKET4677_AZIF0045P001C01CS(CHIPS)':
 'VSS1223': CDS_PINID='VSS1223';
NODE_NAME     U1 ED67
 '@S9S_MB_2U_LIB.S9S_MB_2U(SCH_1):PAGE70_I5@PURE_QUANTA.SOCKET4677_AZIF0045P001C01CS(CHIPS)':
 'VSS1224': CDS_PINID='VSS1224';
NODE_NAME     U1 ED73
 '@S9S_MB_2U_LIB.S9S_MB_2U(SCH_1):PAGE70_I5@PURE_QUANTA.SOCKET4677_AZIF0045P001C01CS(CHIPS)':
 'VSS1225': CDS_PINID='VSS1225';
NODE_NAME     U1 EE17
 '@S9S_MB_2U_LIB.S9S_MB_2U(SCH_1):PAGE70_I5@PURE_QUANTA.SOCKET4677_AZIF0045P001C01CS(CHIPS)':
 'VSS1232': CDS_PINID='VSS1232';
NODE_NAME     U1 EE39
 '@S9S_MB_2U_LIB.S9S_MB_2U(SCH_1):PAGE70_I5@PURE_QUANTA.SOCKET4677_AZIF0045P001C01CS(CHIPS)':
 'VSS1235': CDS_PINID='VSS1235';
NODE_NAME     U1 EE52
 '@S9S_MB_2U_LIB.S9S_MB_2U(SCH_1):PAGE70_I5@PURE_QUANTA.SOCKET4677_AZIF0045P001C01CS(CHIPS)':
 'VSS1237': CDS_PINID='VSS1237';
NODE_NAME     U1 DW66
 '@S9S_MB_2U_LIB.S9S_MB_2U(SCH_1):PAGE70_I5@PURE_QUANTA.SOCKET4677_AZIF0045P001C01CS(CHIPS)':
 'VSS1257': CDS_PINID='VSS1257';
NODE_NAME     U1 DW68
 '@S9S_MB_2U_LIB.S9S_MB_2U(SCH_1):PAGE70_I5@PURE_QUANTA.SOCKET4677_AZIF0045P001C01CS(CHIPS)':
 'VSS1258': CDS_PINID='VSS1258';
NODE_NAME     U1 DW70
 '@S9S_MB_2U_LIB.S9S_MB_2U(SCH_1):PAGE70_I5@PURE_QUANTA.SOCKET4677_AZIF0045P001C01CS(CHIPS)':
 'VSS1259': CDS_PINID='VSS1259';
NODE_NAME     U1 DW72
 '@S9S_MB_2U_LIB.S9S_MB_2U(SCH_1):PAGE70_I5@PURE_QUANTA.SOCKET4677_AZIF0045P001C01CS(CHIPS)':
 'VSS1260': CDS_PINID='VSS1260';
NODE_NAME     U1 DW74
 '@S9S_MB_2U_LIB.S9S_MB_2U(SCH_1):PAGE70_I5@PURE_QUANTA.SOCKET4677_AZIF0045P001C01CS(CHIPS)':
 'VSS1261': CDS_PINID='VSS1261';
NODE_NAME     U1 DW76
 '@S9S_MB_2U_LIB.S9S_MB_2U(SCH_1):PAGE70_I5@PURE_QUANTA.SOCKET4677_AZIF0045P001C01CS(CHIPS)':
 'VSS1262': CDS_PINID='VSS1262';
NODE_NAME     U1 DW80
 '@S9S_MB_2U_LIB.S9S_MB_2U(SCH_1):PAGE70_I5@PURE_QUANTA.SOCKET4677_AZIF0045P001C01CS(CHIPS)':
 'VSS1263': CDS_PINID='VSS1263';
NODE_NAME     U1 DW82
 '@S9S_MB_2U_LIB.S9S_MB_2U(SCH_1):PAGE70_I5@PURE_QUANTA.SOCKET4677_AZIF0045P001C01CS(CHIPS)':
 'VSS1264': CDS_PINID='VSS1264';
NODE_NAME     U1 EF51
 '@S9S_MB_2U_LIB.S9S_MB_2U(SCH_1):PAGE70_I5@PURE_QUANTA.SOCKET4677_AZIF0045P001C01CS(CHIPS)':
 'VSS1265': CDS_PINID='VSS1265';
NODE_NAME     U1 DW84
 '@S9S_MB_2U_LIB.S9S_MB_2U(SCH_1):PAGE70_I5@PURE_QUANTA.SOCKET4677_AZIF0045P001C01CS(CHIPS)':
 'VSS1266': CDS_PINID='VSS1266';
NODE_NAME     U1 DW88
 '@S9S_MB_2U_LIB.S9S_MB_2U(SCH_1):PAGE70_I5@PURE_QUANTA.SOCKET4677_AZIF0045P001C01CS(CHIPS)':
 'VSS1267': CDS_PINID='VSS1267';
NODE_NAME     U1 DY77
 '@S9S_MB_2U_LIB.S9S_MB_2U(SCH_1):PAGE70_I5@PURE_QUANTA.SOCKET4677_AZIF0045P001C01CS(CHIPS)':
 'VSS1269': CDS_PINID='VSS1269';
NODE_NAME     U1 DY8
 '@S9S_MB_2U_LIB.S9S_MB_2U(SCH_1):PAGE70_I5@PURE_QUANTA.SOCKET4677_AZIF0045P001C01CS(CHIPS)':
 'VSS1270': CDS_PINID='VSS1270';
NODE_NAME     U1 EA21
 '@S9S_MB_2U_LIB.S9S_MB_2U(SCH_1):PAGE70_I5@PURE_QUANTA.SOCKET4677_AZIF0045P001C01CS(CHIPS)':
 'VSS1274': CDS_PINID='VSS1274';
NODE_NAME     U1 EA27
 '@S9S_MB_2U_LIB.S9S_MB_2U(SCH_1):PAGE70_I5@PURE_QUANTA.SOCKET4677_AZIF0045P001C01CS(CHIPS)':
 'VSS1275': CDS_PINID='VSS1275';
NODE_NAME     U1 EF73
 '@S9S_MB_2U_LIB.S9S_MB_2U(SCH_1):PAGE70_I5@PURE_QUANTA.SOCKET4677_AZIF0045P001C01CS(CHIPS)':
 'VSS1276': CDS_PINID='VSS1276';
NODE_NAME     U1 EF75
 '@S9S_MB_2U_LIB.S9S_MB_2U(SCH_1):PAGE70_I5@PURE_QUANTA.SOCKET4677_AZIF0045P001C01CS(CHIPS)':
 'VSS1277': CDS_PINID='VSS1277';
NODE_NAME     U1 EA33
 '@S9S_MB_2U_LIB.S9S_MB_2U(SCH_1):PAGE70_I5@PURE_QUANTA.SOCKET4677_AZIF0045P001C01CS(CHIPS)':
 'VSS1278': CDS_PINID='VSS1278';
NODE_NAME     U1 EA70
 '@S9S_MB_2U_LIB.S9S_MB_2U(SCH_1):PAGE70_I5@PURE_QUANTA.SOCKET4677_AZIF0045P001C01CS(CHIPS)':
 'VSS1279': CDS_PINID='VSS1279';
NODE_NAME     U1 EA76
 '@S9S_MB_2U_LIB.S9S_MB_2U(SCH_1):PAGE70_I5@PURE_QUANTA.SOCKET4677_AZIF0045P001C01CS(CHIPS)':
 'VSS1280': CDS_PINID='VSS1280';
NODE_NAME     U1 EA78
 '@S9S_MB_2U_LIB.S9S_MB_2U(SCH_1):PAGE70_I5@PURE_QUANTA.SOCKET4677_AZIF0045P001C01CS(CHIPS)':
 'VSS1281': CDS_PINID='VSS1281';
NODE_NAME     U1 EA80
 '@S9S_MB_2U_LIB.S9S_MB_2U(SCH_1):PAGE70_I5@PURE_QUANTA.SOCKET4677_AZIF0045P001C01CS(CHIPS)':
 'VSS1282': CDS_PINID='VSS1282';
NODE_NAME     U1 EF89
 '@S9S_MB_2U_LIB.S9S_MB_2U(SCH_1):PAGE70_I5@PURE_QUANTA.SOCKET4677_AZIF0045P001C01CS(CHIPS)':
 'VSS1283': CDS_PINID='VSS1283';
NODE_NAME     U1 EG13
 '@S9S_MB_2U_LIB.S9S_MB_2U(SCH_1):PAGE70_I5@PURE_QUANTA.SOCKET4677_AZIF0045P001C01CS(CHIPS)':
 'VSS1284': CDS_PINID='VSS1284';
NODE_NAME     U1 EA84
 '@S9S_MB_2U_LIB.S9S_MB_2U(SCH_1):PAGE70_I5@PURE_QUANTA.SOCKET4677_AZIF0045P001C01CS(CHIPS)':
 'VSS1285': CDS_PINID='VSS1285';
NODE_NAME     U1 EA88
 '@S9S_MB_2U_LIB.S9S_MB_2U(SCH_1):PAGE70_I5@PURE_QUANTA.SOCKET4677_AZIF0045P001C01CS(CHIPS)':
 'VSS1286': CDS_PINID='VSS1286';
NODE_NAME     U1 EB12
 '@S9S_MB_2U_LIB.S9S_MB_2U(SCH_1):PAGE70_I5@PURE_QUANTA.SOCKET4677_AZIF0045P001C01CS(CHIPS)':
 'VSS1287': CDS_PINID='VSS1287';
NODE_NAME     U1 EB22
 '@S9S_MB_2U_LIB.S9S_MB_2U(SCH_1):PAGE70_I5@PURE_QUANTA.SOCKET4677_AZIF0045P001C01CS(CHIPS)':
 'VSS1288': CDS_PINID='VSS1288';
NODE_NAME     U1 EB28
 '@S9S_MB_2U_LIB.S9S_MB_2U(SCH_1):PAGE70_I5@PURE_QUANTA.SOCKET4677_AZIF0045P001C01CS(CHIPS)':
 'VSS1289': CDS_PINID='VSS1289';
NODE_NAME     U1 EG5
 '@S9S_MB_2U_LIB.S9S_MB_2U(SCH_1):PAGE70_I5@PURE_QUANTA.SOCKET4677_AZIF0045P001C01CS(CHIPS)':
 'VSS1290': CDS_PINID='VSS1290';
NODE_NAME     U1 EG52
 '@S9S_MB_2U_LIB.S9S_MB_2U(SCH_1):PAGE70_I5@PURE_QUANTA.SOCKET4677_AZIF0045P001C01CS(CHIPS)':
 'VSS1291': CDS_PINID='VSS1291';
NODE_NAME     U1 EB32
 '@S9S_MB_2U_LIB.S9S_MB_2U(SCH_1):PAGE70_I5@PURE_QUANTA.SOCKET4677_AZIF0045P001C01CS(CHIPS)':
 'VSS1292': CDS_PINID='VSS1292';
NODE_NAME     U1 EB38
 '@S9S_MB_2U_LIB.S9S_MB_2U(SCH_1):PAGE70_I5@PURE_QUANTA.SOCKET4677_AZIF0045P001C01CS(CHIPS)':
 'VSS1293': CDS_PINID='VSS1293';
NODE_NAME     U1 EG7
 '@S9S_MB_2U_LIB.S9S_MB_2U(SCH_1):PAGE70_I5@PURE_QUANTA.SOCKET4677_AZIF0045P001C01CS(CHIPS)':
 'VSS1294': CDS_PINID='VSS1294';
NODE_NAME     U1 EB40
 '@S9S_MB_2U_LIB.S9S_MB_2U(SCH_1):PAGE70_I5@PURE_QUANTA.SOCKET4677_AZIF0045P001C01CS(CHIPS)':
 'VSS1295': CDS_PINID='VSS1295';
NODE_NAME     U1 EB47
 '@S9S_MB_2U_LIB.S9S_MB_2U(SCH_1):PAGE70_I5@PURE_QUANTA.SOCKET4677_AZIF0045P001C01CS(CHIPS)':
 'VSS1296': CDS_PINID='VSS1296';
NODE_NAME     U1 EB57
 '@S9S_MB_2U_LIB.S9S_MB_2U(SCH_1):PAGE70_I5@PURE_QUANTA.SOCKET4677_AZIF0045P001C01CS(CHIPS)':
 'VSS1297': CDS_PINID='VSS1297';
NODE_NAME     U1 EB65
 '@S9S_MB_2U_LIB.S9S_MB_2U(SCH_1):PAGE70_I5@PURE_QUANTA.SOCKET4677_AZIF0045P001C01CS(CHIPS)':
 'VSS1298': CDS_PINID='VSS1298';
NODE_NAME     U1 EB69
 '@S9S_MB_2U_LIB.S9S_MB_2U(SCH_1):PAGE70_I5@PURE_QUANTA.SOCKET4677_AZIF0045P001C01CS(CHIPS)':
 'VSS1299': CDS_PINID='VSS1299';
NODE_NAME     U1 EB71
 '@S9S_MB_2U_LIB.S9S_MB_2U(SCH_1):PAGE70_I5@PURE_QUANTA.SOCKET4677_AZIF0045P001C01CS(CHIPS)':
 'VSS1300': CDS_PINID='VSS1300';
NODE_NAME     U1 EB75
 '@S9S_MB_2U_LIB.S9S_MB_2U(SCH_1):PAGE70_I5@PURE_QUANTA.SOCKET4677_AZIF0045P001C01CS(CHIPS)':
 'VSS1301': CDS_PINID='VSS1301';
NODE_NAME     U1 EH12
 '@S9S_MB_2U_LIB.S9S_MB_2U(SCH_1):PAGE70_I5@PURE_QUANTA.SOCKET4677_AZIF0045P001C01CS(CHIPS)':
 'VSS1302': CDS_PINID='VSS1302';
NODE_NAME     U1 EH14
 '@S9S_MB_2U_LIB.S9S_MB_2U(SCH_1):PAGE70_I5@PURE_QUANTA.SOCKET4677_AZIF0045P001C01CS(CHIPS)':
 'VSS1303': CDS_PINID='VSS1303';
NODE_NAME     U1 EB79
 '@S9S_MB_2U_LIB.S9S_MB_2U(SCH_1):PAGE70_I5@PURE_QUANTA.SOCKET4677_AZIF0045P001C01CS(CHIPS)':
 'VSS1304': CDS_PINID='VSS1304';
NODE_NAME     U1 EH18
 '@S9S_MB_2U_LIB.S9S_MB_2U(SCH_1):PAGE70_I5@PURE_QUANTA.SOCKET4677_AZIF0045P001C01CS(CHIPS)':
 'VSS1305': CDS_PINID='VSS1305';
NODE_NAME     U1 EB8
 '@S9S_MB_2U_LIB.S9S_MB_2U(SCH_1):PAGE70_I5@PURE_QUANTA.SOCKET4677_AZIF0045P001C01CS(CHIPS)':
 'VSS1306': CDS_PINID='VSS1306';
NODE_NAME     U1 EB83
 '@S9S_MB_2U_LIB.S9S_MB_2U(SCH_1):PAGE70_I5@PURE_QUANTA.SOCKET4677_AZIF0045P001C01CS(CHIPS)':
 'VSS1307': CDS_PINID='VSS1307';
NODE_NAME     U1 EB87
 '@S9S_MB_2U_LIB.S9S_MB_2U(SCH_1):PAGE70_I5@PURE_QUANTA.SOCKET4677_AZIF0045P001C01CS(CHIPS)':
 'VSS1308': CDS_PINID='VSS1308';
NODE_NAME     U1 EC1
 '@S9S_MB_2U_LIB.S9S_MB_2U(SCH_1):PAGE70_I5@PURE_QUANTA.SOCKET4677_AZIF0045P001C01CS(CHIPS)':
 'VSS1309': CDS_PINID='VSS1309';
NODE_NAME     U1 EC13
 '@S9S_MB_2U_LIB.S9S_MB_2U(SCH_1):PAGE70_I5@PURE_QUANTA.SOCKET4677_AZIF0045P001C01CS(CHIPS)':
 'VSS1310': CDS_PINID='VSS1310';
NODE_NAME     U1 EC19
 '@S9S_MB_2U_LIB.S9S_MB_2U(SCH_1):PAGE70_I5@PURE_QUANTA.SOCKET4677_AZIF0045P001C01CS(CHIPS)':
 'VSS1311': CDS_PINID='VSS1311';
NODE_NAME     U1 EC23
 '@S9S_MB_2U_LIB.S9S_MB_2U(SCH_1):PAGE70_I5@PURE_QUANTA.SOCKET4677_AZIF0045P001C01CS(CHIPS)':
 'VSS1313': CDS_PINID='VSS1313';
NODE_NAME     U1 EC29
 '@S9S_MB_2U_LIB.S9S_MB_2U(SCH_1):PAGE70_I5@PURE_QUANTA.SOCKET4677_AZIF0045P001C01CS(CHIPS)':
 'VSS1314': CDS_PINID='VSS1314';
NODE_NAME     U1 EC31
 '@S9S_MB_2U_LIB.S9S_MB_2U(SCH_1):PAGE70_I5@PURE_QUANTA.SOCKET4677_AZIF0045P001C01CS(CHIPS)':
 'VSS1316': CDS_PINID='VSS1316';
NODE_NAME     U1 EC37
 '@S9S_MB_2U_LIB.S9S_MB_2U(SCH_1):PAGE70_I5@PURE_QUANTA.SOCKET4677_AZIF0045P001C01CS(CHIPS)':
 'VSS1317': CDS_PINID='VSS1317';
NODE_NAME     U1 EH6
 '@S9S_MB_2U_LIB.S9S_MB_2U(SCH_1):PAGE70_I5@PURE_QUANTA.SOCKET4677_AZIF0045P001C01CS(CHIPS)':
 'VSS1318': CDS_PINID='VSS1318';
NODE_NAME     U1 EC41
 '@S9S_MB_2U_LIB.S9S_MB_2U(SCH_1):PAGE70_I5@PURE_QUANTA.SOCKET4677_AZIF0045P001C01CS(CHIPS)':
 'VSS1321': CDS_PINID='VSS1321';
NODE_NAME     U1 EC43
 '@S9S_MB_2U_LIB.S9S_MB_2U(SCH_1):PAGE70_I5@PURE_QUANTA.SOCKET4677_AZIF0045P001C01CS(CHIPS)':
 'VSS1323': CDS_PINID='VSS1323';
NODE_NAME     U1 EC48
 '@S9S_MB_2U_LIB.S9S_MB_2U(SCH_1):PAGE70_I5@PURE_QUANTA.SOCKET4677_AZIF0045P001C01CS(CHIPS)':
 'VSS1324': CDS_PINID='VSS1324';
NODE_NAME     U1 EC50
 '@S9S_MB_2U_LIB.S9S_MB_2U(SCH_1):PAGE70_I5@PURE_QUANTA.SOCKET4677_AZIF0045P001C01CS(CHIPS)':
 'VSS1326': CDS_PINID='VSS1326';
NODE_NAME     U1 EC56
 '@S9S_MB_2U_LIB.S9S_MB_2U(SCH_1):PAGE70_I5@PURE_QUANTA.SOCKET4677_AZIF0045P001C01CS(CHIPS)':
 'VSS1327': CDS_PINID='VSS1327';
NODE_NAME     U1 EC66
 '@S9S_MB_2U_LIB.S9S_MB_2U(SCH_1):PAGE70_I5@PURE_QUANTA.SOCKET4677_AZIF0045P001C01CS(CHIPS)':
 'VSS1329': CDS_PINID='VSS1329';
NODE_NAME     U1 EC72
 '@S9S_MB_2U_LIB.S9S_MB_2U(SCH_1):PAGE70_I5@PURE_QUANTA.SOCKET4677_AZIF0045P001C01CS(CHIPS)':
 'VSS1330': CDS_PINID='VSS1330';
NODE_NAME     U1 EC74
 '@S9S_MB_2U_LIB.S9S_MB_2U(SCH_1):PAGE70_I5@PURE_QUANTA.SOCKET4677_AZIF0045P001C01CS(CHIPS)':
 'VSS1332': CDS_PINID='VSS1332';
NODE_NAME     U1 EC82
 '@S9S_MB_2U_LIB.S9S_MB_2U(SCH_1):PAGE70_I5@PURE_QUANTA.SOCKET4677_AZIF0045P001C01CS(CHIPS)':
 'VSS1333': CDS_PINID='VSS1333';
NODE_NAME     U1 EC84
 '@S9S_MB_2U_LIB.S9S_MB_2U(SCH_1):PAGE70_I5@PURE_QUANTA.SOCKET4677_AZIF0045P001C01CS(CHIPS)':
 'VSS1335': CDS_PINID='VSS1335';
NODE_NAME     U1 EC88
 '@S9S_MB_2U_LIB.S9S_MB_2U(SCH_1):PAGE70_I5@PURE_QUANTA.SOCKET4677_AZIF0045P001C01CS(CHIPS)':
 'VSS1336': CDS_PINID='VSS1336';
NODE_NAME     U1 EC9
 '@S9S_MB_2U_LIB.S9S_MB_2U(SCH_1):PAGE70_I5@PURE_QUANTA.SOCKET4677_AZIF0045P001C01CS(CHIPS)':
 'VSS1337': CDS_PINID='VSS1337';
NODE_NAME     U1 ED16
 '@S9S_MB_2U_LIB.S9S_MB_2U(SCH_1):PAGE70_I5@PURE_QUANTA.SOCKET4677_AZIF0045P001C01CS(CHIPS)':
 'VSS1338': CDS_PINID='VSS1338';
NODE_NAME     U1 ED24
 '@S9S_MB_2U_LIB.S9S_MB_2U(SCH_1):PAGE70_I5@PURE_QUANTA.SOCKET4677_AZIF0045P001C01CS(CHIPS)':
 'VSS1339': CDS_PINID='VSS1339';
NODE_NAME     U1 ED30
 '@S9S_MB_2U_LIB.S9S_MB_2U(SCH_1):PAGE70_I5@PURE_QUANTA.SOCKET4677_AZIF0045P001C01CS(CHIPS)':
 'VSS1341': CDS_PINID='VSS1341';
NODE_NAME     U1 ED36
 '@S9S_MB_2U_LIB.S9S_MB_2U(SCH_1):PAGE70_I5@PURE_QUANTA.SOCKET4677_AZIF0045P001C01CS(CHIPS)':
 'VSS1342': CDS_PINID='VSS1342';
NODE_NAME     U1 ED4
 '@S9S_MB_2U_LIB.S9S_MB_2U(SCH_1):PAGE70_I5@PURE_QUANTA.SOCKET4677_AZIF0045P001C01CS(CHIPS)':
 'VSS1344': CDS_PINID='VSS1344';
NODE_NAME     U1 ED49
 '@S9S_MB_2U_LIB.S9S_MB_2U(SCH_1):PAGE70_I5@PURE_QUANTA.SOCKET4677_AZIF0045P001C01CS(CHIPS)':
 'VSS1346': CDS_PINID='VSS1346';
NODE_NAME     U1 ED8
 '@S9S_MB_2U_LIB.S9S_MB_2U(SCH_1):PAGE70_I5@PURE_QUANTA.SOCKET4677_AZIF0045P001C01CS(CHIPS)':
 'VSS1348': CDS_PINID='VSS1348';
NODE_NAME     U1 EE78
 '@S9S_MB_2U_LIB.S9S_MB_2U(SCH_1):PAGE70_I5@PURE_QUANTA.SOCKET4677_AZIF0045P001C01CS(CHIPS)':
 'VSS1349': CDS_PINID='VSS1349';
NODE_NAME     U1 EE80
 '@S9S_MB_2U_LIB.S9S_MB_2U(SCH_1):PAGE70_I5@PURE_QUANTA.SOCKET4677_AZIF0045P001C01CS(CHIPS)':
 'VSS1350': CDS_PINID='VSS1350';
NODE_NAME     U1 EE88
 '@S9S_MB_2U_LIB.S9S_MB_2U(SCH_1):PAGE70_I5@PURE_QUANTA.SOCKET4677_AZIF0045P001C01CS(CHIPS)':
 'VSS1351': CDS_PINID='VSS1351';
NODE_NAME     U1 EF12
 '@S9S_MB_2U_LIB.S9S_MB_2U(SCH_1):PAGE70_I5@PURE_QUANTA.SOCKET4677_AZIF0045P001C01CS(CHIPS)':
 'VSS1352': CDS_PINID='VSS1352';
NODE_NAME     U1 EF16
 '@S9S_MB_2U_LIB.S9S_MB_2U(SCH_1):PAGE70_I5@PURE_QUANTA.SOCKET4677_AZIF0045P001C01CS(CHIPS)':
 'VSS1353': CDS_PINID='VSS1353';
NODE_NAME     U1 EF18
 '@S9S_MB_2U_LIB.S9S_MB_2U(SCH_1):PAGE70_I5@PURE_QUANTA.SOCKET4677_AZIF0045P001C01CS(CHIPS)':
 'VSS1354': CDS_PINID='VSS1354';
NODE_NAME     U1 EF2
 '@S9S_MB_2U_LIB.S9S_MB_2U(SCH_1):PAGE70_I5@PURE_QUANTA.SOCKET4677_AZIF0045P001C01CS(CHIPS)':
 'VSS1356': CDS_PINID='VSS1356';
NODE_NAME     U1 EF20
 '@S9S_MB_2U_LIB.S9S_MB_2U(SCH_1):PAGE70_I5@PURE_QUANTA.SOCKET4677_AZIF0045P001C01CS(CHIPS)':
 'VSS1358': CDS_PINID='VSS1358';
NODE_NAME     U1 EF22
 '@S9S_MB_2U_LIB.S9S_MB_2U(SCH_1):PAGE70_I5@PURE_QUANTA.SOCKET4677_AZIF0045P001C01CS(CHIPS)':
 'VSS1360': CDS_PINID='VSS1360';
NODE_NAME     U1 EF24
 '@S9S_MB_2U_LIB.S9S_MB_2U(SCH_1):PAGE70_I5@PURE_QUANTA.SOCKET4677_AZIF0045P001C01CS(CHIPS)':
 'VSS1361': CDS_PINID='VSS1361';
NODE_NAME     U1 EF26
 '@S9S_MB_2U_LIB.S9S_MB_2U(SCH_1):PAGE70_I5@PURE_QUANTA.SOCKET4677_AZIF0045P001C01CS(CHIPS)':
 'VSS1362': CDS_PINID='VSS1362';
NODE_NAME     U1 EF28
 '@S9S_MB_2U_LIB.S9S_MB_2U(SCH_1):PAGE70_I5@PURE_QUANTA.SOCKET4677_AZIF0045P001C01CS(CHIPS)':
 'VSS1363': CDS_PINID='VSS1363';
NODE_NAME     U1 EF30
 '@S9S_MB_2U_LIB.S9S_MB_2U(SCH_1):PAGE70_I5@PURE_QUANTA.SOCKET4677_AZIF0045P001C01CS(CHIPS)':
 'VSS1364': CDS_PINID='VSS1364';
NODE_NAME     U1 EF32
 '@S9S_MB_2U_LIB.S9S_MB_2U(SCH_1):PAGE70_I5@PURE_QUANTA.SOCKET4677_AZIF0045P001C01CS(CHIPS)':
 'VSS1365': CDS_PINID='VSS1365';
NODE_NAME     U1 EF34
 '@S9S_MB_2U_LIB.S9S_MB_2U(SCH_1):PAGE70_I5@PURE_QUANTA.SOCKET4677_AZIF0045P001C01CS(CHIPS)':
 'VSS1367': CDS_PINID='VSS1367';
NODE_NAME     U1 EF36
 '@S9S_MB_2U_LIB.S9S_MB_2U(SCH_1):PAGE70_I5@PURE_QUANTA.SOCKET4677_AZIF0045P001C01CS(CHIPS)':
 'VSS1370': CDS_PINID='VSS1370';
NODE_NAME     U1 EF38
 '@S9S_MB_2U_LIB.S9S_MB_2U(SCH_1):PAGE70_I5@PURE_QUANTA.SOCKET4677_AZIF0045P001C01CS(CHIPS)':
 'VSS1373': CDS_PINID='VSS1373';
NODE_NAME     U1 EF4
 '@S9S_MB_2U_LIB.S9S_MB_2U(SCH_1):PAGE70_I5@PURE_QUANTA.SOCKET4677_AZIF0045P001C01CS(CHIPS)':
 'VSS1374': CDS_PINID='VSS1374';
NODE_NAME     U1 EF40
 '@S9S_MB_2U_LIB.S9S_MB_2U(SCH_1):PAGE70_I5@PURE_QUANTA.SOCKET4677_AZIF0045P001C01CS(CHIPS)':
 'VSS1376': CDS_PINID='VSS1376';
NODE_NAME     U1 EF42
 '@S9S_MB_2U_LIB.S9S_MB_2U(SCH_1):PAGE70_I5@PURE_QUANTA.SOCKET4677_AZIF0045P001C01CS(CHIPS)':
 'VSS1382': CDS_PINID='VSS1382';
NODE_NAME     U1 EF44
 '@S9S_MB_2U_LIB.S9S_MB_2U(SCH_1):PAGE70_I5@PURE_QUANTA.SOCKET4677_AZIF0045P001C01CS(CHIPS)':
 'VSS1383': CDS_PINID='VSS1383';
NODE_NAME     U1 EF47
 '@S9S_MB_2U_LIB.S9S_MB_2U(SCH_1):PAGE70_I5@PURE_QUANTA.SOCKET4677_AZIF0045P001C01CS(CHIPS)':
 'VSS1384': CDS_PINID='VSS1384';
NODE_NAME     U1 EF49
 '@S9S_MB_2U_LIB.S9S_MB_2U(SCH_1):PAGE70_I5@PURE_QUANTA.SOCKET4677_AZIF0045P001C01CS(CHIPS)':
 'VSS1385': CDS_PINID='VSS1385';
NODE_NAME     U1 EF53
 '@S9S_MB_2U_LIB.S9S_MB_2U(SCH_1):PAGE70_I5@PURE_QUANTA.SOCKET4677_AZIF0045P001C01CS(CHIPS)':
 'VSS1386': CDS_PINID='VSS1386';
NODE_NAME     U1 EF55
 '@S9S_MB_2U_LIB.S9S_MB_2U(SCH_1):PAGE70_I5@PURE_QUANTA.SOCKET4677_AZIF0045P001C01CS(CHIPS)':
 'VSS1387': CDS_PINID='VSS1387';
NODE_NAME     U1 EF57
 '@S9S_MB_2U_LIB.S9S_MB_2U(SCH_1):PAGE70_I5@PURE_QUANTA.SOCKET4677_AZIF0045P001C01CS(CHIPS)':
 'VSS1388': CDS_PINID='VSS1388';
NODE_NAME     U1 EF59
 '@S9S_MB_2U_LIB.S9S_MB_2U(SCH_1):PAGE70_I5@PURE_QUANTA.SOCKET4677_AZIF0045P001C01CS(CHIPS)':
 'VSS1389': CDS_PINID='VSS1389';
NODE_NAME     U1 EF61
 '@S9S_MB_2U_LIB.S9S_MB_2U(SCH_1):PAGE70_I5@PURE_QUANTA.SOCKET4677_AZIF0045P001C01CS(CHIPS)':
 'VSS1390': CDS_PINID='VSS1390';
NODE_NAME     U1 EF63
 '@S9S_MB_2U_LIB.S9S_MB_2U(SCH_1):PAGE70_I5@PURE_QUANTA.SOCKET4677_AZIF0045P001C01CS(CHIPS)':
 'VSS1392': CDS_PINID='VSS1392';
NODE_NAME     U1 EF65
 '@S9S_MB_2U_LIB.S9S_MB_2U(SCH_1):PAGE70_I5@PURE_QUANTA.SOCKET4677_AZIF0045P001C01CS(CHIPS)':
 'VSS1393': CDS_PINID='VSS1393';
NODE_NAME     U1 EF67
 '@S9S_MB_2U_LIB.S9S_MB_2U(SCH_1):PAGE70_I5@PURE_QUANTA.SOCKET4677_AZIF0045P001C01CS(CHIPS)':
 'VSS1395': CDS_PINID='VSS1395';
NODE_NAME     U1 EF69
 '@S9S_MB_2U_LIB.S9S_MB_2U(SCH_1):PAGE70_I5@PURE_QUANTA.SOCKET4677_AZIF0045P001C01CS(CHIPS)':
 'VSS1399': CDS_PINID='VSS1399';
NODE_NAME     U1 EF71
 '@S9S_MB_2U_LIB.S9S_MB_2U(SCH_1):PAGE70_I5@PURE_QUANTA.SOCKET4677_AZIF0045P001C01CS(CHIPS)':
 'VSS1402': CDS_PINID='VSS1402';
NODE_NAME     U1 EF77
 '@S9S_MB_2U_LIB.S9S_MB_2U(SCH_1):PAGE70_I5@PURE_QUANTA.SOCKET4677_AZIF0045P001C01CS(CHIPS)':
 'VSS1403': CDS_PINID='VSS1403';
NODE_NAME     U1 EF8
 '@S9S_MB_2U_LIB.S9S_MB_2U(SCH_1):PAGE70_I5@PURE_QUANTA.SOCKET4677_AZIF0045P001C01CS(CHIPS)':
 'VSS1404': CDS_PINID='VSS1404';
NODE_NAME     U1 EF85
 '@S9S_MB_2U_LIB.S9S_MB_2U(SCH_1):PAGE70_I5@PURE_QUANTA.SOCKET4677_AZIF0045P001C01CS(CHIPS)':
 'VSS1406': CDS_PINID='VSS1406';
NODE_NAME     U1 EF87
 '@S9S_MB_2U_LIB.S9S_MB_2U(SCH_1):PAGE70_I5@PURE_QUANTA.SOCKET4677_AZIF0045P001C01CS(CHIPS)':
 'VSS1407': CDS_PINID='VSS1407';
NODE_NAME     U1 EG39
 '@S9S_MB_2U_LIB.S9S_MB_2U(SCH_1):PAGE70_I5@PURE_QUANTA.SOCKET4677_AZIF0045P001C01CS(CHIPS)':
 'VSS1408': CDS_PINID='VSS1408';
NODE_NAME     U1 EG82
 '@S9S_MB_2U_LIB.S9S_MB_2U(SCH_1):PAGE70_I5@PURE_QUANTA.SOCKET4677_AZIF0045P001C01CS(CHIPS)':
 'VSS1410': CDS_PINID='VSS1410';
NODE_NAME     U1 EG84
 '@S9S_MB_2U_LIB.S9S_MB_2U(SCH_1):PAGE70_I5@PURE_QUANTA.SOCKET4677_AZIF0045P001C01CS(CHIPS)':
 'VSS1411': CDS_PINID='VSS1411';
NODE_NAME     U1 EG86
 '@S9S_MB_2U_LIB.S9S_MB_2U(SCH_1):PAGE70_I5@PURE_QUANTA.SOCKET4677_AZIF0045P001C01CS(CHIPS)':
 'VSS1412': CDS_PINID='VSS1412';
NODE_NAME     U1 EG88
 '@S9S_MB_2U_LIB.S9S_MB_2U(SCH_1):PAGE70_I5@PURE_QUANTA.SOCKET4677_AZIF0045P001C01CS(CHIPS)':
 'VSS1413': CDS_PINID='VSS1413';
NODE_NAME     U1 EG9
 '@S9S_MB_2U_LIB.S9S_MB_2U(SCH_1):PAGE70_I5@PURE_QUANTA.SOCKET4677_AZIF0045P001C01CS(CHIPS)':
 'VSS1414': CDS_PINID='VSS1414';
NODE_NAME     U1 EG90
 '@S9S_MB_2U_LIB.S9S_MB_2U(SCH_1):PAGE70_I5@PURE_QUANTA.SOCKET4677_AZIF0045P001C01CS(CHIPS)':
 'VSS1415': CDS_PINID='VSS1415';
NODE_NAME     U1 EH16
 '@S9S_MB_2U_LIB.S9S_MB_2U(SCH_1):PAGE70_I5@PURE_QUANTA.SOCKET4677_AZIF0045P001C01CS(CHIPS)':
 'VSS1416': CDS_PINID='VSS1416';
NODE_NAME     U1 EH24
 '@S9S_MB_2U_LIB.S9S_MB_2U(SCH_1):PAGE70_I5@PURE_QUANTA.SOCKET4677_AZIF0045P001C01CS(CHIPS)':
 'VSS1417': CDS_PINID='VSS1417';
NODE_NAME     U1 EH30
 '@S9S_MB_2U_LIB.S9S_MB_2U(SCH_1):PAGE70_I5@PURE_QUANTA.SOCKET4677_AZIF0045P001C01CS(CHIPS)':
 'VSS1418': CDS_PINID='VSS1418';
NODE_NAME     U1 EH4
 '@S9S_MB_2U_LIB.S9S_MB_2U(SCH_1):PAGE70_I5@PURE_QUANTA.SOCKET4677_AZIF0045P001C01CS(CHIPS)':
 'VSS1420': CDS_PINID='VSS1420';
NODE_NAME     U1 DM51
 '@S9S_MB_2U_LIB.S9S_MB_2U(SCH_1):PAGE70_I8@PURE_QUANTA.SOCKET4677_AZIF0045P001C01CS(CHIPS)':
 'VSS934': CDS_PINID='VSS934';
NODE_NAME     U1 DM73
 '@S9S_MB_2U_LIB.S9S_MB_2U(SCH_1):PAGE70_I8@PURE_QUANTA.SOCKET4677_AZIF0045P001C01CS(CHIPS)':
 'VSS945': CDS_PINID='VSS945';
NODE_NAME     U1 DN17
 '@S9S_MB_2U_LIB.S9S_MB_2U(SCH_1):PAGE70_I8@PURE_QUANTA.SOCKET4677_AZIF0045P001C01CS(CHIPS)':
 'VSS955': CDS_PINID='VSS955';
NODE_NAME     U1 DN39
 '@S9S_MB_2U_LIB.S9S_MB_2U(SCH_1):PAGE70_I8@PURE_QUANTA.SOCKET4677_AZIF0045P001C01CS(CHIPS)':
 'VSS957': CDS_PINID='VSS957';
NODE_NAME     U1 DN52
 '@S9S_MB_2U_LIB.S9S_MB_2U(SCH_1):PAGE70_I8@PURE_QUANTA.SOCKET4677_AZIF0045P001C01CS(CHIPS)':
 'VSS959': CDS_PINID='VSS959';
NODE_NAME     U1 DP12
 '@S9S_MB_2U_LIB.S9S_MB_2U(SCH_1):PAGE70_I8@PURE_QUANTA.SOCKET4677_AZIF0045P001C01CS(CHIPS)':
 'VSS966': CDS_PINID='VSS966';
NODE_NAME     U1 DP18
 '@S9S_MB_2U_LIB.S9S_MB_2U(SCH_1):PAGE70_I8@PURE_QUANTA.SOCKET4677_AZIF0045P001C01CS(CHIPS)':
 'VSS968': CDS_PINID='VSS968';
NODE_NAME     U1 DP24
 '@S9S_MB_2U_LIB.S9S_MB_2U(SCH_1):PAGE70_I8@PURE_QUANTA.SOCKET4677_AZIF0045P001C01CS(CHIPS)':
 'VSS969': CDS_PINID='VSS969';
NODE_NAME     U1 DP42
 '@S9S_MB_2U_LIB.S9S_MB_2U(SCH_1):PAGE70_I8@PURE_QUANTA.SOCKET4677_AZIF0045P001C01CS(CHIPS)':
 'VSS973': CDS_PINID='VSS973';
NODE_NAME     U1 DP55
 '@S9S_MB_2U_LIB.S9S_MB_2U(SCH_1):PAGE70_I8@PURE_QUANTA.SOCKET4677_AZIF0045P001C01CS(CHIPS)':
 'VSS976': CDS_PINID='VSS976';
NODE_NAME     U1 DP61
 '@S9S_MB_2U_LIB.S9S_MB_2U(SCH_1):PAGE70_I8@PURE_QUANTA.SOCKET4677_AZIF0045P001C01CS(CHIPS)':
 'VSS979': CDS_PINID='VSS979';
NODE_NAME     U1 DP67
 '@S9S_MB_2U_LIB.S9S_MB_2U(SCH_1):PAGE70_I8@PURE_QUANTA.SOCKET4677_AZIF0045P001C01CS(CHIPS)':
 'VSS980': CDS_PINID='VSS980';
NODE_NAME     U1 DP91
 '@S9S_MB_2U_LIB.S9S_MB_2U(SCH_1):PAGE70_I8@PURE_QUANTA.SOCKET4677_AZIF0045P001C01CS(CHIPS)':
 'VSS985': CDS_PINID='VSS985';
NODE_NAME     U1 DR25
 '@S9S_MB_2U_LIB.S9S_MB_2U(SCH_1):PAGE70_I8@PURE_QUANTA.SOCKET4677_AZIF0045P001C01CS(CHIPS)':
 'VSS990': CDS_PINID='VSS990';
NODE_NAME     U1 DR35
 '@S9S_MB_2U_LIB.S9S_MB_2U(SCH_1):PAGE70_I8@PURE_QUANTA.SOCKET4677_AZIF0045P001C01CS(CHIPS)':
 'VSS993': CDS_PINID='VSS993';
NODE_NAME     U1 DR5
 '@S9S_MB_2U_LIB.S9S_MB_2U(SCH_1):PAGE70_I8@PURE_QUANTA.SOCKET4677_AZIF0045P001C01CS(CHIPS)':
 'VSS998': CDS_PINID='VSS998';
NODE_NAME     U1 DR54
 '@S9S_MB_2U_LIB.S9S_MB_2U(SCH_1):PAGE70_I8@PURE_QUANTA.SOCKET4677_AZIF0045P001C01CS(CHIPS)':
 'VSS1000': CDS_PINID='VSS1000';
NODE_NAME     U1 DR60
 '@S9S_MB_2U_LIB.S9S_MB_2U(SCH_1):PAGE70_I8@PURE_QUANTA.SOCKET4677_AZIF0045P001C01CS(CHIPS)':
 'VSS1002': CDS_PINID='VSS1002';
NODE_NAME     U1 DR62
 '@S9S_MB_2U_LIB.S9S_MB_2U(SCH_1):PAGE70_I8@PURE_QUANTA.SOCKET4677_AZIF0045P001C01CS(CHIPS)':
 'VSS1003': CDS_PINID='VSS1003';
NODE_NAME     U1 DR68
 '@S9S_MB_2U_LIB.S9S_MB_2U(SCH_1):PAGE70_I8@PURE_QUANTA.SOCKET4677_AZIF0045P001C01CS(CHIPS)':
 'VSS1005': CDS_PINID='VSS1005';
NODE_NAME     U1 DR72
 '@S9S_MB_2U_LIB.S9S_MB_2U(SCH_1):PAGE70_I8@PURE_QUANTA.SOCKET4677_AZIF0045P001C01CS(CHIPS)':
 'VSS1006': CDS_PINID='VSS1006';
NODE_NAME     U1 DT16
 '@S9S_MB_2U_LIB.S9S_MB_2U(SCH_1):PAGE70_I8@PURE_QUANTA.SOCKET4677_AZIF0045P001C01CS(CHIPS)':
 'VSS1013': CDS_PINID='VSS1013';
NODE_NAME     U1 DT20
 '@S9S_MB_2U_LIB.S9S_MB_2U(SCH_1):PAGE70_I8@PURE_QUANTA.SOCKET4677_AZIF0045P001C01CS(CHIPS)':
 'VSS1014': CDS_PINID='VSS1014';
NODE_NAME     U1 DT26
 '@S9S_MB_2U_LIB.S9S_MB_2U(SCH_1):PAGE70_I8@PURE_QUANTA.SOCKET4677_AZIF0045P001C01CS(CHIPS)':
 'VSS1016': CDS_PINID='VSS1016';
NODE_NAME     U1 DT4
 '@S9S_MB_2U_LIB.S9S_MB_2U(SCH_1):PAGE70_I8@PURE_QUANTA.SOCKET4677_AZIF0045P001C01CS(CHIPS)':
 'VSS1021': CDS_PINID='VSS1021';
NODE_NAME     U1 DT44
 '@S9S_MB_2U_LIB.S9S_MB_2U(SCH_1):PAGE70_I8@PURE_QUANTA.SOCKET4677_AZIF0045P001C01CS(CHIPS)':
 'VSS1023': CDS_PINID='VSS1023';
NODE_NAME     U1 DT51
 '@S9S_MB_2U_LIB.S9S_MB_2U(SCH_1):PAGE70_I8@PURE_QUANTA.SOCKET4677_AZIF0045P001C01CS(CHIPS)':
 'VSS1025': CDS_PINID='VSS1025';
NODE_NAME     U1 DT53
 '@S9S_MB_2U_LIB.S9S_MB_2U(SCH_1):PAGE70_I8@PURE_QUANTA.SOCKET4677_AZIF0045P001C01CS(CHIPS)':
 'VSS1026': CDS_PINID='VSS1026';
NODE_NAME     U1 DT59
 '@S9S_MB_2U_LIB.S9S_MB_2U(SCH_1):PAGE70_I8@PURE_QUANTA.SOCKET4677_AZIF0045P001C01CS(CHIPS)':
 'VSS1028': CDS_PINID='VSS1028';
NODE_NAME     U1 DT63
 '@S9S_MB_2U_LIB.S9S_MB_2U(SCH_1):PAGE70_I8@PURE_QUANTA.SOCKET4677_AZIF0045P001C01CS(CHIPS)':
 'VSS1029': CDS_PINID='VSS1029';
NODE_NAME     U1 DT83
 '@S9S_MB_2U_LIB.S9S_MB_2U(SCH_1):PAGE70_I8@PURE_QUANTA.SOCKET4677_AZIF0045P001C01CS(CHIPS)':
 'VSS1036': CDS_PINID='VSS1036';
NODE_NAME     U1 DU39
 '@S9S_MB_2U_LIB.S9S_MB_2U(SCH_1):PAGE70_I8@PURE_QUANTA.SOCKET4677_AZIF0045P001C01CS(CHIPS)':
 'VSS1047': CDS_PINID='VSS1047';
NODE_NAME     U1 DU45
 '@S9S_MB_2U_LIB.S9S_MB_2U(SCH_1):PAGE70_I8@PURE_QUANTA.SOCKET4677_AZIF0045P001C01CS(CHIPS)':
 'VSS1048': CDS_PINID='VSS1048';
NODE_NAME     U1 DU52
 '@S9S_MB_2U_LIB.S9S_MB_2U(SCH_1):PAGE70_I8@PURE_QUANTA.SOCKET4677_AZIF0045P001C01CS(CHIPS)':
 'VSS1050': CDS_PINID='VSS1050';
NODE_NAME     U1 DU58
 '@S9S_MB_2U_LIB.S9S_MB_2U(SCH_1):PAGE70_I8@PURE_QUANTA.SOCKET4677_AZIF0045P001C01CS(CHIPS)':
 'VSS1051': CDS_PINID='VSS1051';
NODE_NAME     U1 DU64
 '@S9S_MB_2U_LIB.S9S_MB_2U(SCH_1):PAGE70_I8@PURE_QUANTA.SOCKET4677_AZIF0045P001C01CS(CHIPS)':
 'VSS1052': CDS_PINID='VSS1052';
NODE_NAME     U1 DU70
 '@S9S_MB_2U_LIB.S9S_MB_2U(SCH_1):PAGE70_I8@PURE_QUANTA.SOCKET4677_AZIF0045P001C01CS(CHIPS)':
 'VSS1054': CDS_PINID='VSS1054';
NODE_NAME     U1 DV12
 '@S9S_MB_2U_LIB.S9S_MB_2U(SCH_1):PAGE70_I8@PURE_QUANTA.SOCKET4677_AZIF0045P001C01CS(CHIPS)':
 'VSS1059': CDS_PINID='VSS1059';
NODE_NAME     U1 DV16
 '@S9S_MB_2U_LIB.S9S_MB_2U(SCH_1):PAGE70_I8@PURE_QUANTA.SOCKET4677_AZIF0045P001C01CS(CHIPS)':
 'VSS1060': CDS_PINID='VSS1060';
NODE_NAME     U1 DV4
 '@S9S_MB_2U_LIB.S9S_MB_2U(SCH_1):PAGE70_I8@PURE_QUANTA.SOCKET4677_AZIF0045P001C01CS(CHIPS)':
 'VSS1063': CDS_PINID='VSS1063';
NODE_NAME     U1 DV42
 '@S9S_MB_2U_LIB.S9S_MB_2U(SCH_1):PAGE70_I8@PURE_QUANTA.SOCKET4677_AZIF0045P001C01CS(CHIPS)':
 'VSS1064': CDS_PINID='VSS1064';
NODE_NAME     U1 DW21
 '@S9S_MB_2U_LIB.S9S_MB_2U(SCH_1):PAGE70_I8@PURE_QUANTA.SOCKET4677_AZIF0045P001C01CS(CHIPS)':
 'VSS1077': CDS_PINID='VSS1077';
NODE_NAME     U1 DW60
 '@S9S_MB_2U_LIB.S9S_MB_2U(SCH_1):PAGE70_I8@PURE_QUANTA.SOCKET4677_AZIF0045P001C01CS(CHIPS)':
 'VSS1097': CDS_PINID='VSS1097';
NODE_NAME     U1 DM12
 '@S9S_MB_2U_LIB.S9S_MB_2U(SCH_1):PAGE70_I8@PURE_QUANTA.SOCKET4677_AZIF0045P001C01CS(CHIPS)':
 'VSS1100': CDS_PINID='VSS1100';
NODE_NAME     U1 DM16
 '@S9S_MB_2U_LIB.S9S_MB_2U(SCH_1):PAGE70_I8@PURE_QUANTA.SOCKET4677_AZIF0045P001C01CS(CHIPS)':
 'VSS1101': CDS_PINID='VSS1101';
NODE_NAME     U1 DM18
 '@S9S_MB_2U_LIB.S9S_MB_2U(SCH_1):PAGE70_I8@PURE_QUANTA.SOCKET4677_AZIF0045P001C01CS(CHIPS)':
 'VSS1102': CDS_PINID='VSS1102';
NODE_NAME     U1 DM20
 '@S9S_MB_2U_LIB.S9S_MB_2U(SCH_1):PAGE70_I8@PURE_QUANTA.SOCKET4677_AZIF0045P001C01CS(CHIPS)':
 'VSS1103': CDS_PINID='VSS1103';
NODE_NAME     U1 DM22
 '@S9S_MB_2U_LIB.S9S_MB_2U(SCH_1):PAGE70_I8@PURE_QUANTA.SOCKET4677_AZIF0045P001C01CS(CHIPS)':
 'VSS1104': CDS_PINID='VSS1104';
NODE_NAME     U1 DM24
 '@S9S_MB_2U_LIB.S9S_MB_2U(SCH_1):PAGE70_I8@PURE_QUANTA.SOCKET4677_AZIF0045P001C01CS(CHIPS)':
 'VSS1105': CDS_PINID='VSS1105';
NODE_NAME     U1 DM26
 '@S9S_MB_2U_LIB.S9S_MB_2U(SCH_1):PAGE70_I8@PURE_QUANTA.SOCKET4677_AZIF0045P001C01CS(CHIPS)':
 'VSS1106': CDS_PINID='VSS1106';
NODE_NAME     U1 DM28
 '@S9S_MB_2U_LIB.S9S_MB_2U(SCH_1):PAGE70_I8@PURE_QUANTA.SOCKET4677_AZIF0045P001C01CS(CHIPS)':
 'VSS1107': CDS_PINID='VSS1107';
NODE_NAME     U1 DM30
 '@S9S_MB_2U_LIB.S9S_MB_2U(SCH_1):PAGE70_I8@PURE_QUANTA.SOCKET4677_AZIF0045P001C01CS(CHIPS)':
 'VSS1108': CDS_PINID='VSS1108';
NODE_NAME     U1 DM32
 '@S9S_MB_2U_LIB.S9S_MB_2U(SCH_1):PAGE70_I8@PURE_QUANTA.SOCKET4677_AZIF0045P001C01CS(CHIPS)':
 'VSS1109': CDS_PINID='VSS1109';
NODE_NAME     U1 DM34
 '@S9S_MB_2U_LIB.S9S_MB_2U(SCH_1):PAGE70_I8@PURE_QUANTA.SOCKET4677_AZIF0045P001C01CS(CHIPS)':
 'VSS1110': CDS_PINID='VSS1110';
NODE_NAME     U1 DM36
 '@S9S_MB_2U_LIB.S9S_MB_2U(SCH_1):PAGE70_I8@PURE_QUANTA.SOCKET4677_AZIF0045P001C01CS(CHIPS)':
 'VSS1113': CDS_PINID='VSS1113';
NODE_NAME     U1 DM38
 '@S9S_MB_2U_LIB.S9S_MB_2U(SCH_1):PAGE70_I8@PURE_QUANTA.SOCKET4677_AZIF0045P001C01CS(CHIPS)':
 'VSS1114': CDS_PINID='VSS1114';
NODE_NAME     U1 DM4
 '@S9S_MB_2U_LIB.S9S_MB_2U(SCH_1):PAGE70_I8@PURE_QUANTA.SOCKET4677_AZIF0045P001C01CS(CHIPS)':
 'VSS1117': CDS_PINID='VSS1117';
NODE_NAME     U1 DM40
 '@S9S_MB_2U_LIB.S9S_MB_2U(SCH_1):PAGE70_I8@PURE_QUANTA.SOCKET4677_AZIF0045P001C01CS(CHIPS)':
 'VSS1118': CDS_PINID='VSS1118';
NODE_NAME     U1 DM42
 '@S9S_MB_2U_LIB.S9S_MB_2U(SCH_1):PAGE70_I8@PURE_QUANTA.SOCKET4677_AZIF0045P001C01CS(CHIPS)':
 'VSS1119': CDS_PINID='VSS1119';
NODE_NAME     U1 DM44
 '@S9S_MB_2U_LIB.S9S_MB_2U(SCH_1):PAGE70_I8@PURE_QUANTA.SOCKET4677_AZIF0045P001C01CS(CHIPS)':
 'VSS1120': CDS_PINID='VSS1120';
NODE_NAME     U1 DM47
 '@S9S_MB_2U_LIB.S9S_MB_2U(SCH_1):PAGE70_I8@PURE_QUANTA.SOCKET4677_AZIF0045P001C01CS(CHIPS)':
 'VSS1121': CDS_PINID='VSS1121';
NODE_NAME     U1 DM49
 '@S9S_MB_2U_LIB.S9S_MB_2U(SCH_1):PAGE70_I8@PURE_QUANTA.SOCKET4677_AZIF0045P001C01CS(CHIPS)':
 'VSS1122': CDS_PINID='VSS1122';
NODE_NAME     U1 DM53
 '@S9S_MB_2U_LIB.S9S_MB_2U(SCH_1):PAGE70_I8@PURE_QUANTA.SOCKET4677_AZIF0045P001C01CS(CHIPS)':
 'VSS1123': CDS_PINID='VSS1123';
NODE_NAME     U1 DM55
 '@S9S_MB_2U_LIB.S9S_MB_2U(SCH_1):PAGE70_I8@PURE_QUANTA.SOCKET4677_AZIF0045P001C01CS(CHIPS)':
 'VSS1124': CDS_PINID='VSS1124';
NODE_NAME     U1 DM57
 '@S9S_MB_2U_LIB.S9S_MB_2U(SCH_1):PAGE70_I8@PURE_QUANTA.SOCKET4677_AZIF0045P001C01CS(CHIPS)':
 'VSS1127': CDS_PINID='VSS1127';
NODE_NAME     U1 DM59
 '@S9S_MB_2U_LIB.S9S_MB_2U(SCH_1):PAGE70_I8@PURE_QUANTA.SOCKET4677_AZIF0045P001C01CS(CHIPS)':
 'VSS1128': CDS_PINID='VSS1128';
NODE_NAME     U1 DM61
 '@S9S_MB_2U_LIB.S9S_MB_2U(SCH_1):PAGE70_I8@PURE_QUANTA.SOCKET4677_AZIF0045P001C01CS(CHIPS)':
 'VSS1130': CDS_PINID='VSS1130';
NODE_NAME     U1 DM63
 '@S9S_MB_2U_LIB.S9S_MB_2U(SCH_1):PAGE70_I8@PURE_QUANTA.SOCKET4677_AZIF0045P001C01CS(CHIPS)':
 'VSS1132': CDS_PINID='VSS1132';
NODE_NAME     U1 DM65
 '@S9S_MB_2U_LIB.S9S_MB_2U(SCH_1):PAGE70_I8@PURE_QUANTA.SOCKET4677_AZIF0045P001C01CS(CHIPS)':
 'VSS1133': CDS_PINID='VSS1133';
NODE_NAME     U1 DM67
 '@S9S_MB_2U_LIB.S9S_MB_2U(SCH_1):PAGE70_I8@PURE_QUANTA.SOCKET4677_AZIF0045P001C01CS(CHIPS)':
 'VSS1134': CDS_PINID='VSS1134';
NODE_NAME     U1 DM69
 '@S9S_MB_2U_LIB.S9S_MB_2U(SCH_1):PAGE70_I8@PURE_QUANTA.SOCKET4677_AZIF0045P001C01CS(CHIPS)':
 'VSS1135': CDS_PINID='VSS1135';
NODE_NAME     U1 DM71
 '@S9S_MB_2U_LIB.S9S_MB_2U(SCH_1):PAGE70_I8@PURE_QUANTA.SOCKET4677_AZIF0045P001C01CS(CHIPS)':
 'VSS1136': CDS_PINID='VSS1136';
NODE_NAME     U1 DM75
 '@S9S_MB_2U_LIB.S9S_MB_2U(SCH_1):PAGE70_I8@PURE_QUANTA.SOCKET4677_AZIF0045P001C01CS(CHIPS)':
 'VSS1137': CDS_PINID='VSS1137';
NODE_NAME     U1 DM77
 '@S9S_MB_2U_LIB.S9S_MB_2U(SCH_1):PAGE70_I8@PURE_QUANTA.SOCKET4677_AZIF0045P001C01CS(CHIPS)':
 'VSS1138': CDS_PINID='VSS1138';
NODE_NAME     U1 DM79
 '@S9S_MB_2U_LIB.S9S_MB_2U(SCH_1):PAGE70_I8@PURE_QUANTA.SOCKET4677_AZIF0045P001C01CS(CHIPS)':
 'VSS1139': CDS_PINID='VSS1139';
NODE_NAME     U1 DM8
 '@S9S_MB_2U_LIB.S9S_MB_2U(SCH_1):PAGE70_I8@PURE_QUANTA.SOCKET4677_AZIF0045P001C01CS(CHIPS)':
 'VSS1140': CDS_PINID='VSS1140';
NODE_NAME     U1 DN78
 '@S9S_MB_2U_LIB.S9S_MB_2U(SCH_1):PAGE70_I8@PURE_QUANTA.SOCKET4677_AZIF0045P001C01CS(CHIPS)':
 'VSS1143': CDS_PINID='VSS1143';
NODE_NAME     U1 DN84
 '@S9S_MB_2U_LIB.S9S_MB_2U(SCH_1):PAGE70_I8@PURE_QUANTA.SOCKET4677_AZIF0045P001C01CS(CHIPS)':
 'VSS1147': CDS_PINID='VSS1147';
NODE_NAME     U1 DN88
 '@S9S_MB_2U_LIB.S9S_MB_2U(SCH_1):PAGE70_I8@PURE_QUANTA.SOCKET4677_AZIF0045P001C01CS(CHIPS)':
 'VSS1148': CDS_PINID='VSS1148';
NODE_NAME     U1 DP16
 '@S9S_MB_2U_LIB.S9S_MB_2U(SCH_1):PAGE70_I8@PURE_QUANTA.SOCKET4677_AZIF0045P001C01CS(CHIPS)':
 'VSS1149': CDS_PINID='VSS1149';
NODE_NAME     U1 DP30
 '@S9S_MB_2U_LIB.S9S_MB_2U(SCH_1):PAGE70_I8@PURE_QUANTA.SOCKET4677_AZIF0045P001C01CS(CHIPS)':
 'VSS1150': CDS_PINID='VSS1150';
NODE_NAME     U1 DP36
 '@S9S_MB_2U_LIB.S9S_MB_2U(SCH_1):PAGE70_I8@PURE_QUANTA.SOCKET4677_AZIF0045P001C01CS(CHIPS)':
 'VSS1151': CDS_PINID='VSS1151';
NODE_NAME     U1 DP4
 '@S9S_MB_2U_LIB.S9S_MB_2U(SCH_1):PAGE70_I8@PURE_QUANTA.SOCKET4677_AZIF0045P001C01CS(CHIPS)':
 'VSS1152': CDS_PINID='VSS1152';
NODE_NAME     U1 DP49
 '@S9S_MB_2U_LIB.S9S_MB_2U(SCH_1):PAGE70_I8@PURE_QUANTA.SOCKET4677_AZIF0045P001C01CS(CHIPS)':
 'VSS1153': CDS_PINID='VSS1153';
NODE_NAME     U1 DP73
 '@S9S_MB_2U_LIB.S9S_MB_2U(SCH_1):PAGE70_I8@PURE_QUANTA.SOCKET4677_AZIF0045P001C01CS(CHIPS)':
 'VSS1154': CDS_PINID='VSS1154';
NODE_NAME     U1 DP8
 '@S9S_MB_2U_LIB.S9S_MB_2U(SCH_1):PAGE70_I8@PURE_QUANTA.SOCKET4677_AZIF0045P001C01CS(CHIPS)':
 'VSS1157': CDS_PINID='VSS1157';
NODE_NAME     U1 DP81
 '@S9S_MB_2U_LIB.S9S_MB_2U(SCH_1):PAGE70_I8@PURE_QUANTA.SOCKET4677_AZIF0045P001C01CS(CHIPS)':
 'VSS1159': CDS_PINID='VSS1159';
NODE_NAME     U1 DP87
 '@S9S_MB_2U_LIB.S9S_MB_2U(SCH_1):PAGE70_I8@PURE_QUANTA.SOCKET4677_AZIF0045P001C01CS(CHIPS)':
 'VSS1160': CDS_PINID='VSS1160';
NODE_NAME     U1 DR1
 '@S9S_MB_2U_LIB.S9S_MB_2U(SCH_1):PAGE70_I8@PURE_QUANTA.SOCKET4677_AZIF0045P001C01CS(CHIPS)':
 'VSS1162': CDS_PINID='VSS1162';
NODE_NAME     U1 DR13
 '@S9S_MB_2U_LIB.S9S_MB_2U(SCH_1):PAGE70_I8@PURE_QUANTA.SOCKET4677_AZIF0045P001C01CS(CHIPS)':
 'VSS1164': CDS_PINID='VSS1164';
NODE_NAME     U1 DR19
 '@S9S_MB_2U_LIB.S9S_MB_2U(SCH_1):PAGE70_I8@PURE_QUANTA.SOCKET4677_AZIF0045P001C01CS(CHIPS)':
 'VSS1166': CDS_PINID='VSS1166';
NODE_NAME     U1 DR23
 '@S9S_MB_2U_LIB.S9S_MB_2U(SCH_1):PAGE70_I8@PURE_QUANTA.SOCKET4677_AZIF0045P001C01CS(CHIPS)':
 'VSS1169': CDS_PINID='VSS1169';
NODE_NAME     U1 DR29
 '@S9S_MB_2U_LIB.S9S_MB_2U(SCH_1):PAGE70_I8@PURE_QUANTA.SOCKET4677_AZIF0045P001C01CS(CHIPS)':
 'VSS1172': CDS_PINID='VSS1172';
NODE_NAME     U1 DR31
 '@S9S_MB_2U_LIB.S9S_MB_2U(SCH_1):PAGE70_I8@PURE_QUANTA.SOCKET4677_AZIF0045P001C01CS(CHIPS)':
 'VSS1173': CDS_PINID='VSS1173';
NODE_NAME     U1 DR37
 '@S9S_MB_2U_LIB.S9S_MB_2U(SCH_1):PAGE70_I8@PURE_QUANTA.SOCKET4677_AZIF0045P001C01CS(CHIPS)':
 'VSS1174': CDS_PINID='VSS1174';
NODE_NAME     U1 DR41
 '@S9S_MB_2U_LIB.S9S_MB_2U(SCH_1):PAGE70_I8@PURE_QUANTA.SOCKET4677_AZIF0045P001C01CS(CHIPS)':
 'VSS1175': CDS_PINID='VSS1175';
NODE_NAME     U1 DR43
 '@S9S_MB_2U_LIB.S9S_MB_2U(SCH_1):PAGE70_I8@PURE_QUANTA.SOCKET4677_AZIF0045P001C01CS(CHIPS)':
 'VSS1176': CDS_PINID='VSS1176';
NODE_NAME     U1 DR48
 '@S9S_MB_2U_LIB.S9S_MB_2U(SCH_1):PAGE70_I8@PURE_QUANTA.SOCKET4677_AZIF0045P001C01CS(CHIPS)':
 'VSS1177': CDS_PINID='VSS1177';
NODE_NAME     U1 DR50
 '@S9S_MB_2U_LIB.S9S_MB_2U(SCH_1):PAGE70_I8@PURE_QUANTA.SOCKET4677_AZIF0045P001C01CS(CHIPS)':
 'VSS1178': CDS_PINID='VSS1178';
NODE_NAME     U1 DR56
 '@S9S_MB_2U_LIB.S9S_MB_2U(SCH_1):PAGE70_I8@PURE_QUANTA.SOCKET4677_AZIF0045P001C01CS(CHIPS)':
 'VSS1179': CDS_PINID='VSS1179';
NODE_NAME     U1 DR66
 '@S9S_MB_2U_LIB.S9S_MB_2U(SCH_1):PAGE70_I8@PURE_QUANTA.SOCKET4677_AZIF0045P001C01CS(CHIPS)':
 'VSS1181': CDS_PINID='VSS1181';
NODE_NAME     U1 DR74
 '@S9S_MB_2U_LIB.S9S_MB_2U(SCH_1):PAGE70_I8@PURE_QUANTA.SOCKET4677_AZIF0045P001C01CS(CHIPS)':
 'VSS1182': CDS_PINID='VSS1182';
NODE_NAME     U1 DR78
 '@S9S_MB_2U_LIB.S9S_MB_2U(SCH_1):PAGE70_I8@PURE_QUANTA.SOCKET4677_AZIF0045P001C01CS(CHIPS)':
 'VSS1183': CDS_PINID='VSS1183';
NODE_NAME     U1 DR84
 '@S9S_MB_2U_LIB.S9S_MB_2U(SCH_1):PAGE70_I8@PURE_QUANTA.SOCKET4677_AZIF0045P001C01CS(CHIPS)':
 'VSS1184': CDS_PINID='VSS1184';
NODE_NAME     U1 DR88
 '@S9S_MB_2U_LIB.S9S_MB_2U(SCH_1):PAGE70_I8@PURE_QUANTA.SOCKET4677_AZIF0045P001C01CS(CHIPS)':
 'VSS1186': CDS_PINID='VSS1186';
NODE_NAME     U1 DR9
 '@S9S_MB_2U_LIB.S9S_MB_2U(SCH_1):PAGE70_I8@PURE_QUANTA.SOCKET4677_AZIF0045P001C01CS(CHIPS)':
 'VSS1187': CDS_PINID='VSS1187';
NODE_NAME     U1 DT12
 '@S9S_MB_2U_LIB.S9S_MB_2U(SCH_1):PAGE70_I8@PURE_QUANTA.SOCKET4677_AZIF0045P001C01CS(CHIPS)':
 'VSS1189': CDS_PINID='VSS1189';
NODE_NAME     U1 DT22
 '@S9S_MB_2U_LIB.S9S_MB_2U(SCH_1):PAGE70_I8@PURE_QUANTA.SOCKET4677_AZIF0045P001C01CS(CHIPS)':
 'VSS1190': CDS_PINID='VSS1190';
NODE_NAME     U1 DT28
 '@S9S_MB_2U_LIB.S9S_MB_2U(SCH_1):PAGE70_I8@PURE_QUANTA.SOCKET4677_AZIF0045P001C01CS(CHIPS)':
 'VSS1191': CDS_PINID='VSS1191';
NODE_NAME     U1 DT32
 '@S9S_MB_2U_LIB.S9S_MB_2U(SCH_1):PAGE70_I8@PURE_QUANTA.SOCKET4677_AZIF0045P001C01CS(CHIPS)':
 'VSS1192': CDS_PINID='VSS1192';
NODE_NAME     U1 DT34
 '@S9S_MB_2U_LIB.S9S_MB_2U(SCH_1):PAGE70_I8@PURE_QUANTA.SOCKET4677_AZIF0045P001C01CS(CHIPS)':
 'VSS1194': CDS_PINID='VSS1194';
NODE_NAME     U1 DT38
 '@S9S_MB_2U_LIB.S9S_MB_2U(SCH_1):PAGE70_I8@PURE_QUANTA.SOCKET4677_AZIF0045P001C01CS(CHIPS)':
 'VSS1196': CDS_PINID='VSS1196';
NODE_NAME     U1 DT40
 '@S9S_MB_2U_LIB.S9S_MB_2U(SCH_1):PAGE70_I8@PURE_QUANTA.SOCKET4677_AZIF0045P001C01CS(CHIPS)':
 'VSS1199': CDS_PINID='VSS1199';
NODE_NAME     U1 DT47
 '@S9S_MB_2U_LIB.S9S_MB_2U(SCH_1):PAGE70_I8@PURE_QUANTA.SOCKET4677_AZIF0045P001C01CS(CHIPS)':
 'VSS1201': CDS_PINID='VSS1201';
NODE_NAME     U1 DT57
 '@S9S_MB_2U_LIB.S9S_MB_2U(SCH_1):PAGE70_I8@PURE_QUANTA.SOCKET4677_AZIF0045P001C01CS(CHIPS)':
 'VSS1202': CDS_PINID='VSS1202';
NODE_NAME     U1 DT65
 '@S9S_MB_2U_LIB.S9S_MB_2U(SCH_1):PAGE70_I8@PURE_QUANTA.SOCKET4677_AZIF0045P001C01CS(CHIPS)':
 'VSS1203': CDS_PINID='VSS1203';
NODE_NAME     U1 DT69
 '@S9S_MB_2U_LIB.S9S_MB_2U(SCH_1):PAGE70_I8@PURE_QUANTA.SOCKET4677_AZIF0045P001C01CS(CHIPS)':
 'VSS1204': CDS_PINID='VSS1204';
NODE_NAME     U1 DT71
 '@S9S_MB_2U_LIB.S9S_MB_2U(SCH_1):PAGE70_I8@PURE_QUANTA.SOCKET4677_AZIF0045P001C01CS(CHIPS)':
 'VSS1205': CDS_PINID='VSS1205';
NODE_NAME     U1 DT75
 '@S9S_MB_2U_LIB.S9S_MB_2U(SCH_1):PAGE70_I8@PURE_QUANTA.SOCKET4677_AZIF0045P001C01CS(CHIPS)':
 'VSS1206': CDS_PINID='VSS1206';
NODE_NAME     U1 DT8
 '@S9S_MB_2U_LIB.S9S_MB_2U(SCH_1):PAGE70_I8@PURE_QUANTA.SOCKET4677_AZIF0045P001C01CS(CHIPS)':
 'VSS1207': CDS_PINID='VSS1207';
NODE_NAME     U1 DU21
 '@S9S_MB_2U_LIB.S9S_MB_2U(SCH_1):PAGE70_I8@PURE_QUANTA.SOCKET4677_AZIF0045P001C01CS(CHIPS)':
 'VSS1209': CDS_PINID='VSS1209';
NODE_NAME     U1 DU27
 '@S9S_MB_2U_LIB.S9S_MB_2U(SCH_1):PAGE70_I8@PURE_QUANTA.SOCKET4677_AZIF0045P001C01CS(CHIPS)':
 'VSS1211': CDS_PINID='VSS1211';
NODE_NAME     U1 DU33
 '@S9S_MB_2U_LIB.S9S_MB_2U(SCH_1):PAGE70_I8@PURE_QUANTA.SOCKET4677_AZIF0045P001C01CS(CHIPS)':
 'VSS1212': CDS_PINID='VSS1212';
NODE_NAME     U1 DU76
 '@S9S_MB_2U_LIB.S9S_MB_2U(SCH_1):PAGE70_I8@PURE_QUANTA.SOCKET4677_AZIF0045P001C01CS(CHIPS)':
 'VSS1213': CDS_PINID='VSS1213';
NODE_NAME     U1 DU78
 '@S9S_MB_2U_LIB.S9S_MB_2U(SCH_1):PAGE70_I8@PURE_QUANTA.SOCKET4677_AZIF0045P001C01CS(CHIPS)':
 'VSS1214': CDS_PINID='VSS1214';
NODE_NAME     U1 DU84
 '@S9S_MB_2U_LIB.S9S_MB_2U(SCH_1):PAGE70_I8@PURE_QUANTA.SOCKET4677_AZIF0045P001C01CS(CHIPS)':
 'VSS1215': CDS_PINID='VSS1215';
NODE_NAME     U1 DU88
 '@S9S_MB_2U_LIB.S9S_MB_2U(SCH_1):PAGE70_I8@PURE_QUANTA.SOCKET4677_AZIF0045P001C01CS(CHIPS)':
 'VSS1216': CDS_PINID='VSS1216';
NODE_NAME     U1 DV77
 '@S9S_MB_2U_LIB.S9S_MB_2U(SCH_1):PAGE70_I8@PURE_QUANTA.SOCKET4677_AZIF0045P001C01CS(CHIPS)':
 'VSS1218': CDS_PINID='VSS1218';
NODE_NAME     U1 DV79
 '@S9S_MB_2U_LIB.S9S_MB_2U(SCH_1):PAGE70_I8@PURE_QUANTA.SOCKET4677_AZIF0045P001C01CS(CHIPS)':
 'VSS1219': CDS_PINID='VSS1219';
NODE_NAME     U1 DV8
 '@S9S_MB_2U_LIB.S9S_MB_2U(SCH_1):PAGE70_I8@PURE_QUANTA.SOCKET4677_AZIF0045P001C01CS(CHIPS)':
 'VSS1221': CDS_PINID='VSS1221';
NODE_NAME     U1 DV81
 '@S9S_MB_2U_LIB.S9S_MB_2U(SCH_1):PAGE70_I8@PURE_QUANTA.SOCKET4677_AZIF0045P001C01CS(CHIPS)':
 'VSS1222': CDS_PINID='VSS1222';
NODE_NAME     U1 DV83
 '@S9S_MB_2U_LIB.S9S_MB_2U(SCH_1):PAGE70_I8@PURE_QUANTA.SOCKET4677_AZIF0045P001C01CS(CHIPS)':
 'VSS1226': CDS_PINID='VSS1226';
NODE_NAME     U1 DV87
 '@S9S_MB_2U_LIB.S9S_MB_2U(SCH_1):PAGE70_I8@PURE_QUANTA.SOCKET4677_AZIF0045P001C01CS(CHIPS)':
 'VSS1227': CDS_PINID='VSS1227';
NODE_NAME     U1 DV91
 '@S9S_MB_2U_LIB.S9S_MB_2U(SCH_1):PAGE70_I8@PURE_QUANTA.SOCKET4677_AZIF0045P001C01CS(CHIPS)':
 'VSS1228': CDS_PINID='VSS1228';
NODE_NAME     U1 DW1
 '@S9S_MB_2U_LIB.S9S_MB_2U(SCH_1):PAGE70_I8@PURE_QUANTA.SOCKET4677_AZIF0045P001C01CS(CHIPS)':
 'VSS1229': CDS_PINID='VSS1229';
NODE_NAME     U1 DW13
 '@S9S_MB_2U_LIB.S9S_MB_2U(SCH_1):PAGE70_I8@PURE_QUANTA.SOCKET4677_AZIF0045P001C01CS(CHIPS)':
 'VSS1230': CDS_PINID='VSS1230';
NODE_NAME     U1 DW17
 '@S9S_MB_2U_LIB.S9S_MB_2U(SCH_1):PAGE70_I8@PURE_QUANTA.SOCKET4677_AZIF0045P001C01CS(CHIPS)':
 'VSS1231': CDS_PINID='VSS1231';
NODE_NAME     U1 DW19
 '@S9S_MB_2U_LIB.S9S_MB_2U(SCH_1):PAGE70_I8@PURE_QUANTA.SOCKET4677_AZIF0045P001C01CS(CHIPS)':
 'VSS1233': CDS_PINID='VSS1233';
NODE_NAME     U1 DW23
 '@S9S_MB_2U_LIB.S9S_MB_2U(SCH_1):PAGE70_I8@PURE_QUANTA.SOCKET4677_AZIF0045P001C01CS(CHIPS)':
 'VSS1234': CDS_PINID='VSS1234';
NODE_NAME     U1 DW25
 '@S9S_MB_2U_LIB.S9S_MB_2U(SCH_1):PAGE70_I8@PURE_QUANTA.SOCKET4677_AZIF0045P001C01CS(CHIPS)':
 'VSS1236': CDS_PINID='VSS1236';
NODE_NAME     U1 DW27
 '@S9S_MB_2U_LIB.S9S_MB_2U(SCH_1):PAGE70_I8@PURE_QUANTA.SOCKET4677_AZIF0045P001C01CS(CHIPS)':
 'VSS1238': CDS_PINID='VSS1238';
NODE_NAME     U1 DW29
 '@S9S_MB_2U_LIB.S9S_MB_2U(SCH_1):PAGE70_I8@PURE_QUANTA.SOCKET4677_AZIF0045P001C01CS(CHIPS)':
 'VSS1239': CDS_PINID='VSS1239';
NODE_NAME     U1 DW31
 '@S9S_MB_2U_LIB.S9S_MB_2U(SCH_1):PAGE70_I8@PURE_QUANTA.SOCKET4677_AZIF0045P001C01CS(CHIPS)':
 'VSS1240': CDS_PINID='VSS1240';
NODE_NAME     U1 DW33
 '@S9S_MB_2U_LIB.S9S_MB_2U(SCH_1):PAGE70_I8@PURE_QUANTA.SOCKET4677_AZIF0045P001C01CS(CHIPS)':
 'VSS1241': CDS_PINID='VSS1241';
NODE_NAME     U1 DW35
 '@S9S_MB_2U_LIB.S9S_MB_2U(SCH_1):PAGE70_I8@PURE_QUANTA.SOCKET4677_AZIF0045P001C01CS(CHIPS)':
 'VSS1242': CDS_PINID='VSS1242';
NODE_NAME     U1 DW37
 '@S9S_MB_2U_LIB.S9S_MB_2U(SCH_1):PAGE70_I8@PURE_QUANTA.SOCKET4677_AZIF0045P001C01CS(CHIPS)':
 'VSS1243': CDS_PINID='VSS1243';
NODE_NAME     U1 DW39
 '@S9S_MB_2U_LIB.S9S_MB_2U(SCH_1):PAGE70_I8@PURE_QUANTA.SOCKET4677_AZIF0045P001C01CS(CHIPS)':
 'VSS1244': CDS_PINID='VSS1244';
NODE_NAME     U1 DW41
 '@S9S_MB_2U_LIB.S9S_MB_2U(SCH_1):PAGE70_I8@PURE_QUANTA.SOCKET4677_AZIF0045P001C01CS(CHIPS)':
 'VSS1245': CDS_PINID='VSS1245';
NODE_NAME     U1 DW43
 '@S9S_MB_2U_LIB.S9S_MB_2U(SCH_1):PAGE70_I8@PURE_QUANTA.SOCKET4677_AZIF0045P001C01CS(CHIPS)':
 'VSS1246': CDS_PINID='VSS1246';
NODE_NAME     U1 DW45
 '@S9S_MB_2U_LIB.S9S_MB_2U(SCH_1):PAGE70_I8@PURE_QUANTA.SOCKET4677_AZIF0045P001C01CS(CHIPS)':
 'VSS1247': CDS_PINID='VSS1247';
NODE_NAME     U1 DW48
 '@S9S_MB_2U_LIB.S9S_MB_2U(SCH_1):PAGE70_I8@PURE_QUANTA.SOCKET4677_AZIF0045P001C01CS(CHIPS)':
 'VSS1248': CDS_PINID='VSS1248';
NODE_NAME     U1 DW5
 '@S9S_MB_2U_LIB.S9S_MB_2U(SCH_1):PAGE70_I8@PURE_QUANTA.SOCKET4677_AZIF0045P001C01CS(CHIPS)':
 'VSS1249': CDS_PINID='VSS1249';
NODE_NAME     U1 DW50
 '@S9S_MB_2U_LIB.S9S_MB_2U(SCH_1):PAGE70_I8@PURE_QUANTA.SOCKET4677_AZIF0045P001C01CS(CHIPS)':
 'VSS1250': CDS_PINID='VSS1250';
NODE_NAME     U1 DW52
 '@S9S_MB_2U_LIB.S9S_MB_2U(SCH_1):PAGE70_I8@PURE_QUANTA.SOCKET4677_AZIF0045P001C01CS(CHIPS)':
 'VSS1251': CDS_PINID='VSS1251';
NODE_NAME     U1 DW54
 '@S9S_MB_2U_LIB.S9S_MB_2U(SCH_1):PAGE70_I8@PURE_QUANTA.SOCKET4677_AZIF0045P001C01CS(CHIPS)':
 'VSS1252': CDS_PINID='VSS1252';
NODE_NAME     U1 DW56
 '@S9S_MB_2U_LIB.S9S_MB_2U(SCH_1):PAGE70_I8@PURE_QUANTA.SOCKET4677_AZIF0045P001C01CS(CHIPS)':
 'VSS1253': CDS_PINID='VSS1253';
NODE_NAME     U1 DW58
 '@S9S_MB_2U_LIB.S9S_MB_2U(SCH_1):PAGE70_I8@PURE_QUANTA.SOCKET4677_AZIF0045P001C01CS(CHIPS)':
 'VSS1254': CDS_PINID='VSS1254';
NODE_NAME     U1 DW62
 '@S9S_MB_2U_LIB.S9S_MB_2U(SCH_1):PAGE70_I8@PURE_QUANTA.SOCKET4677_AZIF0045P001C01CS(CHIPS)':
 'VSS1255': CDS_PINID='VSS1255';
NODE_NAME     U1 DW64
 '@S9S_MB_2U_LIB.S9S_MB_2U(SCH_1):PAGE70_I8@PURE_QUANTA.SOCKET4677_AZIF0045P001C01CS(CHIPS)':
 'VSS1256': CDS_PINID='VSS1256';
NODE_NAME     U1 DW9
 '@S9S_MB_2U_LIB.S9S_MB_2U(SCH_1):PAGE70_I8@PURE_QUANTA.SOCKET4677_AZIF0045P001C01CS(CHIPS)':
 'VSS1268': CDS_PINID='VSS1268';
NODE_NAME     U1 DB91
 '@S9S_MB_2U_LIB.S9S_MB_2U(SCH_1):PAGE71_I2@PURE_QUANTA.SOCKET4677_AZIF0045P001C01CS(CHIPS)':
 'VSS723': CDS_PINID='VSS723';
NODE_NAME     U1 DC1
 '@S9S_MB_2U_LIB.S9S_MB_2U(SCH_1):PAGE71_I2@PURE_QUANTA.SOCKET4677_AZIF0045P001C01CS(CHIPS)':
 'VSS724': CDS_PINID='VSS724';
NODE_NAME     U1 DC13
 '@S9S_MB_2U_LIB.S9S_MB_2U(SCH_1):PAGE71_I2@PURE_QUANTA.SOCKET4677_AZIF0045P001C01CS(CHIPS)':
 'VSS725': CDS_PINID='VSS725';
NODE_NAME     U1 DC21
 '@S9S_MB_2U_LIB.S9S_MB_2U(SCH_1):PAGE71_I2@PURE_QUANTA.SOCKET4677_AZIF0045P001C01CS(CHIPS)':
 'VSS726': CDS_PINID='VSS726';
NODE_NAME     U1 DC52
 '@S9S_MB_2U_LIB.S9S_MB_2U(SCH_1):PAGE71_I2@PURE_QUANTA.SOCKET4677_AZIF0045P001C01CS(CHIPS)':
 'VSS735': CDS_PINID='VSS735';
NODE_NAME     U1 DC58
 '@S9S_MB_2U_LIB.S9S_MB_2U(SCH_1):PAGE71_I2@PURE_QUANTA.SOCKET4677_AZIF0045P001C01CS(CHIPS)':
 'VSS738': CDS_PINID='VSS738';
NODE_NAME     U1 DC64
 '@S9S_MB_2U_LIB.S9S_MB_2U(SCH_1):PAGE71_I2@PURE_QUANTA.SOCKET4677_AZIF0045P001C01CS(CHIPS)':
 'VSS739': CDS_PINID='VSS739';
NODE_NAME     U1 DD12
 '@S9S_MB_2U_LIB.S9S_MB_2U(SCH_1):PAGE71_I2@PURE_QUANTA.SOCKET4677_AZIF0045P001C01CS(CHIPS)':
 'VSS747': CDS_PINID='VSS747';
NODE_NAME     U1 DD16
 '@S9S_MB_2U_LIB.S9S_MB_2U(SCH_1):PAGE71_I2@PURE_QUANTA.SOCKET4677_AZIF0045P001C01CS(CHIPS)':
 'VSS748': CDS_PINID='VSS748';
NODE_NAME     U1 DD49
 '@S9S_MB_2U_LIB.S9S_MB_2U(SCH_1):PAGE71_I2@PURE_QUANTA.SOCKET4677_AZIF0045P001C01CS(CHIPS)':
 'VSS753': CDS_PINID='VSS753';
NODE_NAME     U1 DE39
 '@S9S_MB_2U_LIB.S9S_MB_2U(SCH_1):PAGE71_I2@PURE_QUANTA.SOCKET4677_AZIF0045P001C01CS(CHIPS)':
 'VSS776': CDS_PINID='VSS776';
NODE_NAME     U1 DE70
 '@S9S_MB_2U_LIB.S9S_MB_2U(SCH_1):PAGE71_I2@PURE_QUANTA.SOCKET4677_AZIF0045P001C01CS(CHIPS)':
 'VSS791': CDS_PINID='VSS791';
NODE_NAME     U1 DF12
 '@S9S_MB_2U_LIB.S9S_MB_2U(SCH_1):PAGE71_I2@PURE_QUANTA.SOCKET4677_AZIF0045P001C01CS(CHIPS)':
 'VSS798': CDS_PINID='VSS798';
NODE_NAME     U1 DF16
 '@S9S_MB_2U_LIB.S9S_MB_2U(SCH_1):PAGE71_I2@PURE_QUANTA.SOCKET4677_AZIF0045P001C01CS(CHIPS)':
 'VSS799': CDS_PINID='VSS799';
NODE_NAME     U1 DF49
 '@S9S_MB_2U_LIB.S9S_MB_2U(SCH_1):PAGE71_I2@PURE_QUANTA.SOCKET4677_AZIF0045P001C01CS(CHIPS)':
 'VSS802': CDS_PINID='VSS802';
NODE_NAME     U1 DF91
 '@S9S_MB_2U_LIB.S9S_MB_2U(SCH_1):PAGE71_I2@PURE_QUANTA.SOCKET4677_AZIF0045P001C01CS(CHIPS)':
 'VSS806': CDS_PINID='VSS806';
NODE_NAME     U1 DG1
 '@S9S_MB_2U_LIB.S9S_MB_2U(SCH_1):PAGE71_I2@PURE_QUANTA.SOCKET4677_AZIF0045P001C01CS(CHIPS)':
 'VSS807': CDS_PINID='VSS807';
NODE_NAME     U1 DG13
 '@S9S_MB_2U_LIB.S9S_MB_2U(SCH_1):PAGE71_I2@PURE_QUANTA.SOCKET4677_AZIF0045P001C01CS(CHIPS)':
 'VSS808': CDS_PINID='VSS808';
NODE_NAME     U1 DG21
 '@S9S_MB_2U_LIB.S9S_MB_2U(SCH_1):PAGE71_I2@PURE_QUANTA.SOCKET4677_AZIF0045P001C01CS(CHIPS)':
 'VSS809': CDS_PINID='VSS809';
NODE_NAME     U1 DG52
 '@S9S_MB_2U_LIB.S9S_MB_2U(SCH_1):PAGE71_I2@PURE_QUANTA.SOCKET4677_AZIF0045P001C01CS(CHIPS)':
 'VSS817': CDS_PINID='VSS817';
NODE_NAME     U1 DG58
 '@S9S_MB_2U_LIB.S9S_MB_2U(SCH_1):PAGE71_I2@PURE_QUANTA.SOCKET4677_AZIF0045P001C01CS(CHIPS)':
 'VSS820': CDS_PINID='VSS820';
NODE_NAME     U1 DG64
 '@S9S_MB_2U_LIB.S9S_MB_2U(SCH_1):PAGE71_I2@PURE_QUANTA.SOCKET4677_AZIF0045P001C01CS(CHIPS)':
 'VSS821': CDS_PINID='VSS821';
NODE_NAME     U1 DH16
 '@S9S_MB_2U_LIB.S9S_MB_2U(SCH_1):PAGE71_I2@PURE_QUANTA.SOCKET4677_AZIF0045P001C01CS(CHIPS)':
 'VSS829': CDS_PINID='VSS829';
NODE_NAME     U1 DH20
 '@S9S_MB_2U_LIB.S9S_MB_2U(SCH_1):PAGE71_I2@PURE_QUANTA.SOCKET4677_AZIF0045P001C01CS(CHIPS)':
 'VSS830': CDS_PINID='VSS830';
NODE_NAME     U1 DH26
 '@S9S_MB_2U_LIB.S9S_MB_2U(SCH_1):PAGE71_I2@PURE_QUANTA.SOCKET4677_AZIF0045P001C01CS(CHIPS)':
 'VSS832': CDS_PINID='VSS832';
NODE_NAME     U1 DH34
 '@S9S_MB_2U_LIB.S9S_MB_2U(SCH_1):PAGE71_I2@PURE_QUANTA.SOCKET4677_AZIF0045P001C01CS(CHIPS)':
 'VSS835': CDS_PINID='VSS835';
NODE_NAME     U1 DH44
 '@S9S_MB_2U_LIB.S9S_MB_2U(SCH_1):PAGE71_I2@PURE_QUANTA.SOCKET4677_AZIF0045P001C01CS(CHIPS)':
 'VSS839': CDS_PINID='VSS839';
NODE_NAME     U1 DH51
 '@S9S_MB_2U_LIB.S9S_MB_2U(SCH_1):PAGE71_I2@PURE_QUANTA.SOCKET4677_AZIF0045P001C01CS(CHIPS)':
 'VSS841': CDS_PINID='VSS841';
NODE_NAME     U1 DH53
 '@S9S_MB_2U_LIB.S9S_MB_2U(SCH_1):PAGE71_I2@PURE_QUANTA.SOCKET4677_AZIF0045P001C01CS(CHIPS)':
 'VSS842': CDS_PINID='VSS842';
NODE_NAME     U1 DH59
 '@S9S_MB_2U_LIB.S9S_MB_2U(SCH_1):PAGE71_I2@PURE_QUANTA.SOCKET4677_AZIF0045P001C01CS(CHIPS)':
 'VSS844': CDS_PINID='VSS844';
NODE_NAME     U1 DH63
 '@S9S_MB_2U_LIB.S9S_MB_2U(SCH_1):PAGE71_I2@PURE_QUANTA.SOCKET4677_AZIF0045P001C01CS(CHIPS)':
 'VSS845': CDS_PINID='VSS845';
NODE_NAME     U1 DH69
 '@S9S_MB_2U_LIB.S9S_MB_2U(SCH_1):PAGE71_I2@PURE_QUANTA.SOCKET4677_AZIF0045P001C01CS(CHIPS)':
 'VSS847': CDS_PINID='VSS847';
NODE_NAME     U1 DH75
 '@S9S_MB_2U_LIB.S9S_MB_2U(SCH_1):PAGE71_I2@PURE_QUANTA.SOCKET4677_AZIF0045P001C01CS(CHIPS)':
 'VSS849': CDS_PINID='VSS849';
NODE_NAME     U1 DJ25
 '@S9S_MB_2U_LIB.S9S_MB_2U(SCH_1):PAGE71_I2@PURE_QUANTA.SOCKET4677_AZIF0045P001C01CS(CHIPS)':
 'VSS857': CDS_PINID='VSS857';
NODE_NAME     U1 DJ35
 '@S9S_MB_2U_LIB.S9S_MB_2U(SCH_1):PAGE71_I2@PURE_QUANTA.SOCKET4677_AZIF0045P001C01CS(CHIPS)':
 'VSS861': CDS_PINID='VSS861';
NODE_NAME     U1 DJ54
 '@S9S_MB_2U_LIB.S9S_MB_2U(SCH_1):PAGE71_I2@PURE_QUANTA.SOCKET4677_AZIF0045P001C01CS(CHIPS)':
 'VSS867': CDS_PINID='VSS867';
NODE_NAME     U1 DJ62
 '@S9S_MB_2U_LIB.S9S_MB_2U(SCH_1):PAGE71_I2@PURE_QUANTA.SOCKET4677_AZIF0045P001C01CS(CHIPS)':
 'VSS870': CDS_PINID='VSS870';
NODE_NAME     U1 DJ68
 '@S9S_MB_2U_LIB.S9S_MB_2U(SCH_1):PAGE71_I2@PURE_QUANTA.SOCKET4677_AZIF0045P001C01CS(CHIPS)':
 'VSS872': CDS_PINID='VSS872';
NODE_NAME     U1 DK12
 '@S9S_MB_2U_LIB.S9S_MB_2U(SCH_1):PAGE71_I2@PURE_QUANTA.SOCKET4677_AZIF0045P001C01CS(CHIPS)':
 'VSS880': CDS_PINID='VSS880';
NODE_NAME     U1 DK18
 '@S9S_MB_2U_LIB.S9S_MB_2U(SCH_1):PAGE71_I2@PURE_QUANTA.SOCKET4677_AZIF0045P001C01CS(CHIPS)':
 'VSS882': CDS_PINID='VSS882';
NODE_NAME     U1 DK24
 '@S9S_MB_2U_LIB.S9S_MB_2U(SCH_1):PAGE71_I2@PURE_QUANTA.SOCKET4677_AZIF0045P001C01CS(CHIPS)':
 'VSS883': CDS_PINID='VSS883';
NODE_NAME     U1 DK42
 '@S9S_MB_2U_LIB.S9S_MB_2U(SCH_1):PAGE71_I2@PURE_QUANTA.SOCKET4677_AZIF0045P001C01CS(CHIPS)':
 'VSS887': CDS_PINID='VSS887';
NODE_NAME     U1 DK55
 '@S9S_MB_2U_LIB.S9S_MB_2U(SCH_1):PAGE71_I2@PURE_QUANTA.SOCKET4677_AZIF0045P001C01CS(CHIPS)':
 'VSS890': CDS_PINID='VSS890';
NODE_NAME     U1 DK61
 '@S9S_MB_2U_LIB.S9S_MB_2U(SCH_1):PAGE71_I2@PURE_QUANTA.SOCKET4677_AZIF0045P001C01CS(CHIPS)':
 'VSS893': CDS_PINID='VSS893';
NODE_NAME     U1 DK67
 '@S9S_MB_2U_LIB.S9S_MB_2U(SCH_1):PAGE71_I2@PURE_QUANTA.SOCKET4677_AZIF0045P001C01CS(CHIPS)':
 'VSS894': CDS_PINID='VSS894';
NODE_NAME     U1 DL1
 '@S9S_MB_2U_LIB.S9S_MB_2U(SCH_1):PAGE71_I2@PURE_QUANTA.SOCKET4677_AZIF0045P001C01CS(CHIPS)':
 'VSS903': CDS_PINID='VSS903';
NODE_NAME     U1 DL13
 '@S9S_MB_2U_LIB.S9S_MB_2U(SCH_1):PAGE71_I2@PURE_QUANTA.SOCKET4677_AZIF0045P001C01CS(CHIPS)':
 'VSS904': CDS_PINID='VSS904';
NODE_NAME     U1 DL17
 '@S9S_MB_2U_LIB.S9S_MB_2U(SCH_1):PAGE71_I2@PURE_QUANTA.SOCKET4677_AZIF0045P001C01CS(CHIPS)':
 'VSS905': CDS_PINID='VSS905';
NODE_NAME     U1 DL5
 '@S9S_MB_2U_LIB.S9S_MB_2U(SCH_1):PAGE71_I2@PURE_QUANTA.SOCKET4677_AZIF0045P001C01CS(CHIPS)':
 'VSS908': CDS_PINID='VSS908';
NODE_NAME     U1 DL52
 '@S9S_MB_2U_LIB.S9S_MB_2U(SCH_1):PAGE71_I2@PURE_QUANTA.SOCKET4677_AZIF0045P001C01CS(CHIPS)':
 'VSS909': CDS_PINID='VSS909';
NODE_NAME     U1 DC27
 '@S9S_MB_2U_LIB.S9S_MB_2U(SCH_1):PAGE71_I2@PURE_QUANTA.SOCKET4677_AZIF0045P001C01CS(CHIPS)':
 'VSS949': CDS_PINID='VSS949';
NODE_NAME     U1 DC33
 '@S9S_MB_2U_LIB.S9S_MB_2U(SCH_1):PAGE71_I2@PURE_QUANTA.SOCKET4677_AZIF0045P001C01CS(CHIPS)':
 'VSS950': CDS_PINID='VSS950';
NODE_NAME     U1 DC39
 '@S9S_MB_2U_LIB.S9S_MB_2U(SCH_1):PAGE71_I2@PURE_QUANTA.SOCKET4677_AZIF0045P001C01CS(CHIPS)':
 'VSS951': CDS_PINID='VSS951';
NODE_NAME     U1 DC45
 '@S9S_MB_2U_LIB.S9S_MB_2U(SCH_1):PAGE71_I2@PURE_QUANTA.SOCKET4677_AZIF0045P001C01CS(CHIPS)':
 'VSS952': CDS_PINID='VSS952';
NODE_NAME     U1 DC5
 '@S9S_MB_2U_LIB.S9S_MB_2U(SCH_1):PAGE71_I2@PURE_QUANTA.SOCKET4677_AZIF0045P001C01CS(CHIPS)':
 'VSS953': CDS_PINID='VSS953';
NODE_NAME     U1 DC70
 '@S9S_MB_2U_LIB.S9S_MB_2U(SCH_1):PAGE71_I2@PURE_QUANTA.SOCKET4677_AZIF0045P001C01CS(CHIPS)':
 'VSS954': CDS_PINID='VSS954';
NODE_NAME     U1 DC76
 '@S9S_MB_2U_LIB.S9S_MB_2U(SCH_1):PAGE71_I2@PURE_QUANTA.SOCKET4677_AZIF0045P001C01CS(CHIPS)':
 'VSS956': CDS_PINID='VSS956';
NODE_NAME     U1 DC78
 '@S9S_MB_2U_LIB.S9S_MB_2U(SCH_1):PAGE71_I2@PURE_QUANTA.SOCKET4677_AZIF0045P001C01CS(CHIPS)':
 'VSS958': CDS_PINID='VSS958';
NODE_NAME     U1 DC80
 '@S9S_MB_2U_LIB.S9S_MB_2U(SCH_1):PAGE71_I2@PURE_QUANTA.SOCKET4677_AZIF0045P001C01CS(CHIPS)':
 'VSS960': CDS_PINID='VSS960';
NODE_NAME     U1 DC84
 '@S9S_MB_2U_LIB.S9S_MB_2U(SCH_1):PAGE71_I2@PURE_QUANTA.SOCKET4677_AZIF0045P001C01CS(CHIPS)':
 'VSS961': CDS_PINID='VSS961';
NODE_NAME     U1 DC88
 '@S9S_MB_2U_LIB.S9S_MB_2U(SCH_1):PAGE71_I2@PURE_QUANTA.SOCKET4677_AZIF0045P001C01CS(CHIPS)':
 'VSS962': CDS_PINID='VSS962';
NODE_NAME     U1 DC9
 '@S9S_MB_2U_LIB.S9S_MB_2U(SCH_1):PAGE71_I2@PURE_QUANTA.SOCKET4677_AZIF0045P001C01CS(CHIPS)':
 'VSS963': CDS_PINID='VSS963';
NODE_NAME     U1 DD4
 '@S9S_MB_2U_LIB.S9S_MB_2U(SCH_1):PAGE71_I2@PURE_QUANTA.SOCKET4677_AZIF0045P001C01CS(CHIPS)':
 'VSS964': CDS_PINID='VSS964';
NODE_NAME     U1 DD79
 '@S9S_MB_2U_LIB.S9S_MB_2U(SCH_1):PAGE71_I2@PURE_QUANTA.SOCKET4677_AZIF0045P001C01CS(CHIPS)':
 'VSS965': CDS_PINID='VSS965';
NODE_NAME     U1 DD8
 '@S9S_MB_2U_LIB.S9S_MB_2U(SCH_1):PAGE71_I2@PURE_QUANTA.SOCKET4677_AZIF0045P001C01CS(CHIPS)':
 'VSS967': CDS_PINID='VSS967';
NODE_NAME     U1 DE17
 '@S9S_MB_2U_LIB.S9S_MB_2U(SCH_1):PAGE71_I2@PURE_QUANTA.SOCKET4677_AZIF0045P001C01CS(CHIPS)':
 'VSS970': CDS_PINID='VSS970';
NODE_NAME     U1 DE19
 '@S9S_MB_2U_LIB.S9S_MB_2U(SCH_1):PAGE71_I2@PURE_QUANTA.SOCKET4677_AZIF0045P001C01CS(CHIPS)':
 'VSS971': CDS_PINID='VSS971';
NODE_NAME     U1 DE21
 '@S9S_MB_2U_LIB.S9S_MB_2U(SCH_1):PAGE71_I2@PURE_QUANTA.SOCKET4677_AZIF0045P001C01CS(CHIPS)':
 'VSS972': CDS_PINID='VSS972';
NODE_NAME     U1 DE23
 '@S9S_MB_2U_LIB.S9S_MB_2U(SCH_1):PAGE71_I2@PURE_QUANTA.SOCKET4677_AZIF0045P001C01CS(CHIPS)':
 'VSS974': CDS_PINID='VSS974';
NODE_NAME     U1 DE25
 '@S9S_MB_2U_LIB.S9S_MB_2U(SCH_1):PAGE71_I2@PURE_QUANTA.SOCKET4677_AZIF0045P001C01CS(CHIPS)':
 'VSS975': CDS_PINID='VSS975';
NODE_NAME     U1 DE27
 '@S9S_MB_2U_LIB.S9S_MB_2U(SCH_1):PAGE71_I2@PURE_QUANTA.SOCKET4677_AZIF0045P001C01CS(CHIPS)':
 'VSS977': CDS_PINID='VSS977';
NODE_NAME     U1 DE29
 '@S9S_MB_2U_LIB.S9S_MB_2U(SCH_1):PAGE71_I2@PURE_QUANTA.SOCKET4677_AZIF0045P001C01CS(CHIPS)':
 'VSS978': CDS_PINID='VSS978';
NODE_NAME     U1 DE31
 '@S9S_MB_2U_LIB.S9S_MB_2U(SCH_1):PAGE71_I2@PURE_QUANTA.SOCKET4677_AZIF0045P001C01CS(CHIPS)':
 'VSS981': CDS_PINID='VSS981';
NODE_NAME     U1 DE33
 '@S9S_MB_2U_LIB.S9S_MB_2U(SCH_1):PAGE71_I2@PURE_QUANTA.SOCKET4677_AZIF0045P001C01CS(CHIPS)':
 'VSS982': CDS_PINID='VSS982';
NODE_NAME     U1 DE35
 '@S9S_MB_2U_LIB.S9S_MB_2U(SCH_1):PAGE71_I2@PURE_QUANTA.SOCKET4677_AZIF0045P001C01CS(CHIPS)':
 'VSS983': CDS_PINID='VSS983';
NODE_NAME     U1 DE37
 '@S9S_MB_2U_LIB.S9S_MB_2U(SCH_1):PAGE71_I2@PURE_QUANTA.SOCKET4677_AZIF0045P001C01CS(CHIPS)':
 'VSS984': CDS_PINID='VSS984';
NODE_NAME     U1 DE41
 '@S9S_MB_2U_LIB.S9S_MB_2U(SCH_1):PAGE71_I2@PURE_QUANTA.SOCKET4677_AZIF0045P001C01CS(CHIPS)':
 'VSS986': CDS_PINID='VSS986';
NODE_NAME     U1 DE43
 '@S9S_MB_2U_LIB.S9S_MB_2U(SCH_1):PAGE71_I2@PURE_QUANTA.SOCKET4677_AZIF0045P001C01CS(CHIPS)':
 'VSS987': CDS_PINID='VSS987';
NODE_NAME     U1 DE45
 '@S9S_MB_2U_LIB.S9S_MB_2U(SCH_1):PAGE71_I2@PURE_QUANTA.SOCKET4677_AZIF0045P001C01CS(CHIPS)':
 'VSS988': CDS_PINID='VSS988';
NODE_NAME     U1 DE48
 '@S9S_MB_2U_LIB.S9S_MB_2U(SCH_1):PAGE71_I2@PURE_QUANTA.SOCKET4677_AZIF0045P001C01CS(CHIPS)':
 'VSS989': CDS_PINID='VSS989';
NODE_NAME     U1 DE50
 '@S9S_MB_2U_LIB.S9S_MB_2U(SCH_1):PAGE71_I2@PURE_QUANTA.SOCKET4677_AZIF0045P001C01CS(CHIPS)':
 'VSS991': CDS_PINID='VSS991';
NODE_NAME     U1 DE52
 '@S9S_MB_2U_LIB.S9S_MB_2U(SCH_1):PAGE71_I2@PURE_QUANTA.SOCKET4677_AZIF0045P001C01CS(CHIPS)':
 'VSS992': CDS_PINID='VSS992';
NODE_NAME     U1 DE54
 '@S9S_MB_2U_LIB.S9S_MB_2U(SCH_1):PAGE71_I2@PURE_QUANTA.SOCKET4677_AZIF0045P001C01CS(CHIPS)':
 'VSS994': CDS_PINID='VSS994';
NODE_NAME     U1 DE56
 '@S9S_MB_2U_LIB.S9S_MB_2U(SCH_1):PAGE71_I2@PURE_QUANTA.SOCKET4677_AZIF0045P001C01CS(CHIPS)':
 'VSS995': CDS_PINID='VSS995';
NODE_NAME     U1 DE58
 '@S9S_MB_2U_LIB.S9S_MB_2U(SCH_1):PAGE71_I2@PURE_QUANTA.SOCKET4677_AZIF0045P001C01CS(CHIPS)':
 'VSS996': CDS_PINID='VSS996';
NODE_NAME     U1 DE60
 '@S9S_MB_2U_LIB.S9S_MB_2U(SCH_1):PAGE71_I2@PURE_QUANTA.SOCKET4677_AZIF0045P001C01CS(CHIPS)':
 'VSS997': CDS_PINID='VSS997';
NODE_NAME     U1 DE62
 '@S9S_MB_2U_LIB.S9S_MB_2U(SCH_1):PAGE71_I2@PURE_QUANTA.SOCKET4677_AZIF0045P001C01CS(CHIPS)':
 'VSS999': CDS_PINID='VSS999';
NODE_NAME     U1 DE64
 '@S9S_MB_2U_LIB.S9S_MB_2U(SCH_1):PAGE71_I2@PURE_QUANTA.SOCKET4677_AZIF0045P001C01CS(CHIPS)':
 'VSS1001': CDS_PINID='VSS1001';
NODE_NAME     U1 DE66
 '@S9S_MB_2U_LIB.S9S_MB_2U(SCH_1):PAGE71_I2@PURE_QUANTA.SOCKET4677_AZIF0045P001C01CS(CHIPS)':
 'VSS1004': CDS_PINID='VSS1004';
NODE_NAME     U1 DE68
 '@S9S_MB_2U_LIB.S9S_MB_2U(SCH_1):PAGE71_I2@PURE_QUANTA.SOCKET4677_AZIF0045P001C01CS(CHIPS)':
 'VSS1007': CDS_PINID='VSS1007';
NODE_NAME     U1 DE72
 '@S9S_MB_2U_LIB.S9S_MB_2U(SCH_1):PAGE71_I2@PURE_QUANTA.SOCKET4677_AZIF0045P001C01CS(CHIPS)':
 'VSS1008': CDS_PINID='VSS1008';
NODE_NAME     U1 DE74
 '@S9S_MB_2U_LIB.S9S_MB_2U(SCH_1):PAGE71_I2@PURE_QUANTA.SOCKET4677_AZIF0045P001C01CS(CHIPS)':
 'VSS1009': CDS_PINID='VSS1009';
NODE_NAME     U1 DE76
 '@S9S_MB_2U_LIB.S9S_MB_2U(SCH_1):PAGE71_I2@PURE_QUANTA.SOCKET4677_AZIF0045P001C01CS(CHIPS)':
 'VSS1010': CDS_PINID='VSS1010';
NODE_NAME     U1 DE82
 '@S9S_MB_2U_LIB.S9S_MB_2U(SCH_1):PAGE71_I2@PURE_QUANTA.SOCKET4677_AZIF0045P001C01CS(CHIPS)':
 'VSS1011': CDS_PINID='VSS1011';
NODE_NAME     U1 DE84
 '@S9S_MB_2U_LIB.S9S_MB_2U(SCH_1):PAGE71_I2@PURE_QUANTA.SOCKET4677_AZIF0045P001C01CS(CHIPS)':
 'VSS1012': CDS_PINID='VSS1012';
NODE_NAME     U1 DE88
 '@S9S_MB_2U_LIB.S9S_MB_2U(SCH_1):PAGE71_I2@PURE_QUANTA.SOCKET4677_AZIF0045P001C01CS(CHIPS)':
 'VSS1015': CDS_PINID='VSS1015';
NODE_NAME     U1 DF4
 '@S9S_MB_2U_LIB.S9S_MB_2U(SCH_1):PAGE71_I2@PURE_QUANTA.SOCKET4677_AZIF0045P001C01CS(CHIPS)':
 'VSS1017': CDS_PINID='VSS1017';
NODE_NAME     U1 DF79
 '@S9S_MB_2U_LIB.S9S_MB_2U(SCH_1):PAGE71_I2@PURE_QUANTA.SOCKET4677_AZIF0045P001C01CS(CHIPS)':
 'VSS1018': CDS_PINID='VSS1018';
NODE_NAME     U1 DF8
 '@S9S_MB_2U_LIB.S9S_MB_2U(SCH_1):PAGE71_I2@PURE_QUANTA.SOCKET4677_AZIF0045P001C01CS(CHIPS)':
 'VSS1019': CDS_PINID='VSS1019';
NODE_NAME     U1 DF87
 '@S9S_MB_2U_LIB.S9S_MB_2U(SCH_1):PAGE71_I2@PURE_QUANTA.SOCKET4677_AZIF0045P001C01CS(CHIPS)':
 'VSS1020': CDS_PINID='VSS1020';
NODE_NAME     U1 DG27
 '@S9S_MB_2U_LIB.S9S_MB_2U(SCH_1):PAGE71_I2@PURE_QUANTA.SOCKET4677_AZIF0045P001C01CS(CHIPS)':
 'VSS1022': CDS_PINID='VSS1022';
NODE_NAME     U1 DG33
 '@S9S_MB_2U_LIB.S9S_MB_2U(SCH_1):PAGE71_I2@PURE_QUANTA.SOCKET4677_AZIF0045P001C01CS(CHIPS)':
 'VSS1024': CDS_PINID='VSS1024';
NODE_NAME     U1 DG39
 '@S9S_MB_2U_LIB.S9S_MB_2U(SCH_1):PAGE71_I2@PURE_QUANTA.SOCKET4677_AZIF0045P001C01CS(CHIPS)':
 'VSS1027': CDS_PINID='VSS1027';
NODE_NAME     U1 DG45
 '@S9S_MB_2U_LIB.S9S_MB_2U(SCH_1):PAGE71_I2@PURE_QUANTA.SOCKET4677_AZIF0045P001C01CS(CHIPS)':
 'VSS1030': CDS_PINID='VSS1030';
NODE_NAME     U1 DG5
 '@S9S_MB_2U_LIB.S9S_MB_2U(SCH_1):PAGE71_I2@PURE_QUANTA.SOCKET4677_AZIF0045P001C01CS(CHIPS)':
 'VSS1031': CDS_PINID='VSS1031';
NODE_NAME     U1 DG70
 '@S9S_MB_2U_LIB.S9S_MB_2U(SCH_1):PAGE71_I2@PURE_QUANTA.SOCKET4677_AZIF0045P001C01CS(CHIPS)':
 'VSS1032': CDS_PINID='VSS1032';
NODE_NAME     U1 DG76
 '@S9S_MB_2U_LIB.S9S_MB_2U(SCH_1):PAGE71_I2@PURE_QUANTA.SOCKET4677_AZIF0045P001C01CS(CHIPS)':
 'VSS1033': CDS_PINID='VSS1033';
NODE_NAME     U1 DG80
 '@S9S_MB_2U_LIB.S9S_MB_2U(SCH_1):PAGE71_I2@PURE_QUANTA.SOCKET4677_AZIF0045P001C01CS(CHIPS)':
 'VSS1034': CDS_PINID='VSS1034';
NODE_NAME     U1 DG84
 '@S9S_MB_2U_LIB.S9S_MB_2U(SCH_1):PAGE71_I2@PURE_QUANTA.SOCKET4677_AZIF0045P001C01CS(CHIPS)':
 'VSS1035': CDS_PINID='VSS1035';
NODE_NAME     U1 DG88
 '@S9S_MB_2U_LIB.S9S_MB_2U(SCH_1):PAGE71_I2@PURE_QUANTA.SOCKET4677_AZIF0045P001C01CS(CHIPS)':
 'VSS1037': CDS_PINID='VSS1037';
NODE_NAME     U1 DG9
 '@S9S_MB_2U_LIB.S9S_MB_2U(SCH_1):PAGE71_I2@PURE_QUANTA.SOCKET4677_AZIF0045P001C01CS(CHIPS)':
 'VSS1038': CDS_PINID='VSS1038';
NODE_NAME     U1 DH12
 '@S9S_MB_2U_LIB.S9S_MB_2U(SCH_1):PAGE71_I2@PURE_QUANTA.SOCKET4677_AZIF0045P001C01CS(CHIPS)':
 'VSS1039': CDS_PINID='VSS1039';
NODE_NAME     U1 DH22
 '@S9S_MB_2U_LIB.S9S_MB_2U(SCH_1):PAGE71_I2@PURE_QUANTA.SOCKET4677_AZIF0045P001C01CS(CHIPS)':
 'VSS1040': CDS_PINID='VSS1040';
NODE_NAME     U1 DH28
 '@S9S_MB_2U_LIB.S9S_MB_2U(SCH_1):PAGE71_I2@PURE_QUANTA.SOCKET4677_AZIF0045P001C01CS(CHIPS)':
 'VSS1041': CDS_PINID='VSS1041';
NODE_NAME     U1 DH32
 '@S9S_MB_2U_LIB.S9S_MB_2U(SCH_1):PAGE71_I2@PURE_QUANTA.SOCKET4677_AZIF0045P001C01CS(CHIPS)':
 'VSS1042': CDS_PINID='VSS1042';
NODE_NAME     U1 DH38
 '@S9S_MB_2U_LIB.S9S_MB_2U(SCH_1):PAGE71_I2@PURE_QUANTA.SOCKET4677_AZIF0045P001C01CS(CHIPS)':
 'VSS1043': CDS_PINID='VSS1043';
NODE_NAME     U1 DH4
 '@S9S_MB_2U_LIB.S9S_MB_2U(SCH_1):PAGE71_I2@PURE_QUANTA.SOCKET4677_AZIF0045P001C01CS(CHIPS)':
 'VSS1044': CDS_PINID='VSS1044';
NODE_NAME     U1 DH40
 '@S9S_MB_2U_LIB.S9S_MB_2U(SCH_1):PAGE71_I2@PURE_QUANTA.SOCKET4677_AZIF0045P001C01CS(CHIPS)':
 'VSS1045': CDS_PINID='VSS1045';
NODE_NAME     U1 DH47
 '@S9S_MB_2U_LIB.S9S_MB_2U(SCH_1):PAGE71_I2@PURE_QUANTA.SOCKET4677_AZIF0045P001C01CS(CHIPS)':
 'VSS1046': CDS_PINID='VSS1046';
NODE_NAME     U1 DH57
 '@S9S_MB_2U_LIB.S9S_MB_2U(SCH_1):PAGE71_I2@PURE_QUANTA.SOCKET4677_AZIF0045P001C01CS(CHIPS)':
 'VSS1049': CDS_PINID='VSS1049';
NODE_NAME     U1 DH65
 '@S9S_MB_2U_LIB.S9S_MB_2U(SCH_1):PAGE71_I2@PURE_QUANTA.SOCKET4677_AZIF0045P001C01CS(CHIPS)':
 'VSS1053': CDS_PINID='VSS1053';
NODE_NAME     U1 DH71
 '@S9S_MB_2U_LIB.S9S_MB_2U(SCH_1):PAGE71_I2@PURE_QUANTA.SOCKET4677_AZIF0045P001C01CS(CHIPS)':
 'VSS1055': CDS_PINID='VSS1055';
NODE_NAME     U1 DH77
 '@S9S_MB_2U_LIB.S9S_MB_2U(SCH_1):PAGE71_I2@PURE_QUANTA.SOCKET4677_AZIF0045P001C01CS(CHIPS)':
 'VSS1056': CDS_PINID='VSS1056';
NODE_NAME     U1 DH8
 '@S9S_MB_2U_LIB.S9S_MB_2U(SCH_1):PAGE71_I2@PURE_QUANTA.SOCKET4677_AZIF0045P001C01CS(CHIPS)':
 'VSS1057': CDS_PINID='VSS1057';
NODE_NAME     U1 DH85
 '@S9S_MB_2U_LIB.S9S_MB_2U(SCH_1):PAGE71_I2@PURE_QUANTA.SOCKET4677_AZIF0045P001C01CS(CHIPS)':
 'VSS1058': CDS_PINID='VSS1058';
NODE_NAME     U1 DJ19
 '@S9S_MB_2U_LIB.S9S_MB_2U(SCH_1):PAGE71_I2@PURE_QUANTA.SOCKET4677_AZIF0045P001C01CS(CHIPS)':
 'VSS1061': CDS_PINID='VSS1061';
NODE_NAME     U1 DJ23
 '@S9S_MB_2U_LIB.S9S_MB_2U(SCH_1):PAGE71_I2@PURE_QUANTA.SOCKET4677_AZIF0045P001C01CS(CHIPS)':
 'VSS1062': CDS_PINID='VSS1062';
NODE_NAME     U1 DJ29
 '@S9S_MB_2U_LIB.S9S_MB_2U(SCH_1):PAGE71_I2@PURE_QUANTA.SOCKET4677_AZIF0045P001C01CS(CHIPS)':
 'VSS1065': CDS_PINID='VSS1065';
NODE_NAME     U1 DJ31
 '@S9S_MB_2U_LIB.S9S_MB_2U(SCH_1):PAGE71_I2@PURE_QUANTA.SOCKET4677_AZIF0045P001C01CS(CHIPS)':
 'VSS1066': CDS_PINID='VSS1066';
NODE_NAME     U1 DJ37
 '@S9S_MB_2U_LIB.S9S_MB_2U(SCH_1):PAGE71_I2@PURE_QUANTA.SOCKET4677_AZIF0045P001C01CS(CHIPS)':
 'VSS1067': CDS_PINID='VSS1067';
NODE_NAME     U1 DJ41
 '@S9S_MB_2U_LIB.S9S_MB_2U(SCH_1):PAGE71_I2@PURE_QUANTA.SOCKET4677_AZIF0045P001C01CS(CHIPS)':
 'VSS1068': CDS_PINID='VSS1068';
NODE_NAME     U1 DJ43
 '@S9S_MB_2U_LIB.S9S_MB_2U(SCH_1):PAGE71_I2@PURE_QUANTA.SOCKET4677_AZIF0045P001C01CS(CHIPS)':
 'VSS1069': CDS_PINID='VSS1069';
NODE_NAME     U1 DJ48
 '@S9S_MB_2U_LIB.S9S_MB_2U(SCH_1):PAGE71_I2@PURE_QUANTA.SOCKET4677_AZIF0045P001C01CS(CHIPS)':
 'VSS1070': CDS_PINID='VSS1070';
NODE_NAME     U1 DJ50
 '@S9S_MB_2U_LIB.S9S_MB_2U(SCH_1):PAGE71_I2@PURE_QUANTA.SOCKET4677_AZIF0045P001C01CS(CHIPS)':
 'VSS1071': CDS_PINID='VSS1071';
NODE_NAME     U1 DJ56
 '@S9S_MB_2U_LIB.S9S_MB_2U(SCH_1):PAGE71_I2@PURE_QUANTA.SOCKET4677_AZIF0045P001C01CS(CHIPS)':
 'VSS1072': CDS_PINID='VSS1072';
NODE_NAME     U1 DJ60
 '@S9S_MB_2U_LIB.S9S_MB_2U(SCH_1):PAGE71_I2@PURE_QUANTA.SOCKET4677_AZIF0045P001C01CS(CHIPS)':
 'VSS1073': CDS_PINID='VSS1073';
NODE_NAME     U1 DJ66
 '@S9S_MB_2U_LIB.S9S_MB_2U(SCH_1):PAGE71_I2@PURE_QUANTA.SOCKET4677_AZIF0045P001C01CS(CHIPS)':
 'VSS1074': CDS_PINID='VSS1074';
NODE_NAME     U1 DJ72
 '@S9S_MB_2U_LIB.S9S_MB_2U(SCH_1):PAGE71_I2@PURE_QUANTA.SOCKET4677_AZIF0045P001C01CS(CHIPS)':
 'VSS1075': CDS_PINID='VSS1075';
NODE_NAME     U1 DJ74
 '@S9S_MB_2U_LIB.S9S_MB_2U(SCH_1):PAGE71_I2@PURE_QUANTA.SOCKET4677_AZIF0045P001C01CS(CHIPS)':
 'VSS1076': CDS_PINID='VSS1076';
NODE_NAME     U1 DJ80
 '@S9S_MB_2U_LIB.S9S_MB_2U(SCH_1):PAGE71_I2@PURE_QUANTA.SOCKET4677_AZIF0045P001C01CS(CHIPS)':
 'VSS1078': CDS_PINID='VSS1078';
NODE_NAME     U1 DJ82
 '@S9S_MB_2U_LIB.S9S_MB_2U(SCH_1):PAGE71_I2@PURE_QUANTA.SOCKET4677_AZIF0045P001C01CS(CHIPS)':
 'VSS1079': CDS_PINID='VSS1079';
NODE_NAME     U1 DJ84
 '@S9S_MB_2U_LIB.S9S_MB_2U(SCH_1):PAGE71_I2@PURE_QUANTA.SOCKET4677_AZIF0045P001C01CS(CHIPS)':
 'VSS1080': CDS_PINID='VSS1080';
NODE_NAME     U1 DJ88
 '@S9S_MB_2U_LIB.S9S_MB_2U(SCH_1):PAGE71_I2@PURE_QUANTA.SOCKET4677_AZIF0045P001C01CS(CHIPS)':
 'VSS1081': CDS_PINID='VSS1081';
NODE_NAME     U1 DK16
 '@S9S_MB_2U_LIB.S9S_MB_2U(SCH_1):PAGE71_I2@PURE_QUANTA.SOCKET4677_AZIF0045P001C01CS(CHIPS)':
 'VSS1082': CDS_PINID='VSS1082';
NODE_NAME     U1 DK30
 '@S9S_MB_2U_LIB.S9S_MB_2U(SCH_1):PAGE71_I2@PURE_QUANTA.SOCKET4677_AZIF0045P001C01CS(CHIPS)':
 'VSS1083': CDS_PINID='VSS1083';
NODE_NAME     U1 DK36
 '@S9S_MB_2U_LIB.S9S_MB_2U(SCH_1):PAGE71_I2@PURE_QUANTA.SOCKET4677_AZIF0045P001C01CS(CHIPS)':
 'VSS1084': CDS_PINID='VSS1084';
NODE_NAME     U1 DK4
 '@S9S_MB_2U_LIB.S9S_MB_2U(SCH_1):PAGE71_I2@PURE_QUANTA.SOCKET4677_AZIF0045P001C01CS(CHIPS)':
 'VSS1085': CDS_PINID='VSS1085';
NODE_NAME     U1 DK49
 '@S9S_MB_2U_LIB.S9S_MB_2U(SCH_1):PAGE71_I2@PURE_QUANTA.SOCKET4677_AZIF0045P001C01CS(CHIPS)':
 'VSS1086': CDS_PINID='VSS1086';
NODE_NAME     U1 DK73
 '@S9S_MB_2U_LIB.S9S_MB_2U(SCH_1):PAGE71_I2@PURE_QUANTA.SOCKET4677_AZIF0045P001C01CS(CHIPS)':
 'VSS1087': CDS_PINID='VSS1087';
NODE_NAME     U1 DK77
 '@S9S_MB_2U_LIB.S9S_MB_2U(SCH_1):PAGE71_I2@PURE_QUANTA.SOCKET4677_AZIF0045P001C01CS(CHIPS)':
 'VSS1088': CDS_PINID='VSS1088';
NODE_NAME     U1 DK79
 '@S9S_MB_2U_LIB.S9S_MB_2U(SCH_1):PAGE71_I2@PURE_QUANTA.SOCKET4677_AZIF0045P001C01CS(CHIPS)':
 'VSS1089': CDS_PINID='VSS1089';
NODE_NAME     U1 DK8
 '@S9S_MB_2U_LIB.S9S_MB_2U(SCH_1):PAGE71_I2@PURE_QUANTA.SOCKET4677_AZIF0045P001C01CS(CHIPS)':
 'VSS1090': CDS_PINID='VSS1090';
NODE_NAME     U1 DK81
 '@S9S_MB_2U_LIB.S9S_MB_2U(SCH_1):PAGE71_I2@PURE_QUANTA.SOCKET4677_AZIF0045P001C01CS(CHIPS)':
 'VSS1091': CDS_PINID='VSS1091';
NODE_NAME     U1 DK83
 '@S9S_MB_2U_LIB.S9S_MB_2U(SCH_1):PAGE71_I2@PURE_QUANTA.SOCKET4677_AZIF0045P001C01CS(CHIPS)':
 'VSS1092': CDS_PINID='VSS1092';
NODE_NAME     U1 DK87
 '@S9S_MB_2U_LIB.S9S_MB_2U(SCH_1):PAGE71_I2@PURE_QUANTA.SOCKET4677_AZIF0045P001C01CS(CHIPS)':
 'VSS1093': CDS_PINID='VSS1093';
NODE_NAME     U1 DK91
 '@S9S_MB_2U_LIB.S9S_MB_2U(SCH_1):PAGE71_I2@PURE_QUANTA.SOCKET4677_AZIF0045P001C01CS(CHIPS)':
 'VSS1094': CDS_PINID='VSS1094';
NODE_NAME     U1 DL39
 '@S9S_MB_2U_LIB.S9S_MB_2U(SCH_1):PAGE71_I2@PURE_QUANTA.SOCKET4677_AZIF0045P001C01CS(CHIPS)':
 'VSS1095': CDS_PINID='VSS1095';
NODE_NAME     U1 DL84
 '@S9S_MB_2U_LIB.S9S_MB_2U(SCH_1):PAGE71_I2@PURE_QUANTA.SOCKET4677_AZIF0045P001C01CS(CHIPS)':
 'VSS1096': CDS_PINID='VSS1096';
NODE_NAME     U1 DL88
 '@S9S_MB_2U_LIB.S9S_MB_2U(SCH_1):PAGE71_I2@PURE_QUANTA.SOCKET4677_AZIF0045P001C01CS(CHIPS)':
 'VSS1098': CDS_PINID='VSS1098';
NODE_NAME     U1 DL9
 '@S9S_MB_2U_LIB.S9S_MB_2U(SCH_1):PAGE71_I2@PURE_QUANTA.SOCKET4677_AZIF0045P001C01CS(CHIPS)':
 'VSS1099': CDS_PINID='VSS1099';
NODE_NAME     U1 CM16
 '@S9S_MB_2U_LIB.S9S_MB_2U(SCH_1):PAGE71_I5@PURE_QUANTA.SOCKET4677_AZIF0045P001C01CS(CHIPS)':
 'VSS436': CDS_PINID='VSS436';
NODE_NAME     U1 CM22
 '@S9S_MB_2U_LIB.S9S_MB_2U(SCH_1):PAGE71_I5@PURE_QUANTA.SOCKET4677_AZIF0045P001C01CS(CHIPS)':
 'VSS438': CDS_PINID='VSS438';
NODE_NAME     U1 CN76
 '@S9S_MB_2U_LIB.S9S_MB_2U(SCH_1):PAGE71_I5@PURE_QUANTA.SOCKET4677_AZIF0045P001C01CS(CHIPS)':
 'VSS471': CDS_PINID='VSS471';
NODE_NAME     U1 CP16
 '@S9S_MB_2U_LIB.S9S_MB_2U(SCH_1):PAGE71_I5@PURE_QUANTA.SOCKET4677_AZIF0045P001C01CS(CHIPS)':
 'VSS478': CDS_PINID='VSS478';
NODE_NAME     U1 CP79
 '@S9S_MB_2U_LIB.S9S_MB_2U(SCH_1):PAGE71_I5@PURE_QUANTA.SOCKET4677_AZIF0045P001C01CS(CHIPS)':
 'VSS493': CDS_PINID='VSS493';
NODE_NAME     U1 CR78
 '@S9S_MB_2U_LIB.S9S_MB_2U(SCH_1):PAGE71_I5@PURE_QUANTA.SOCKET4677_AZIF0045P001C01CS(CHIPS)':
 'VSS514': CDS_PINID='VSS514';
NODE_NAME     U1 CT16
 '@S9S_MB_2U_LIB.S9S_MB_2U(SCH_1):PAGE71_I5@PURE_QUANTA.SOCKET4677_AZIF0045P001C01CS(CHIPS)':
 'VSS521': CDS_PINID='VSS521';
NODE_NAME     U1 CT4
 '@S9S_MB_2U_LIB.S9S_MB_2U(SCH_1):PAGE71_I5@PURE_QUANTA.SOCKET4677_AZIF0045P001C01CS(CHIPS)':
 'VSS526': CDS_PINID='VSS526';
NODE_NAME     U1 CT8
 '@S9S_MB_2U_LIB.S9S_MB_2U(SCH_1):PAGE71_I5@PURE_QUANTA.SOCKET4677_AZIF0045P001C01CS(CHIPS)':
 'VSS534': CDS_PINID='VSS534';
NODE_NAME     U1 CT89
 '@S9S_MB_2U_LIB.S9S_MB_2U(SCH_1):PAGE71_I5@PURE_QUANTA.SOCKET4677_AZIF0045P001C01CS(CHIPS)':
 'VSS537': CDS_PINID='VSS537';
NODE_NAME     U1 CU25
 '@S9S_MB_2U_LIB.S9S_MB_2U(SCH_1):PAGE71_I5@PURE_QUANTA.SOCKET4677_AZIF0045P001C01CS(CHIPS)':
 'VSS544': CDS_PINID='VSS544';
NODE_NAME     U1 CU72
 '@S9S_MB_2U_LIB.S9S_MB_2U(SCH_1):PAGE71_I5@PURE_QUANTA.SOCKET4677_AZIF0045P001C01CS(CHIPS)':
 'VSS553': CDS_PINID='VSS553';
NODE_NAME     U1 CU78
 '@S9S_MB_2U_LIB.S9S_MB_2U(SCH_1):PAGE71_I5@PURE_QUANTA.SOCKET4677_AZIF0045P001C01CS(CHIPS)':
 'VSS554': CDS_PINID='VSS554';
NODE_NAME     U1 CV16
 '@S9S_MB_2U_LIB.S9S_MB_2U(SCH_1):PAGE71_I5@PURE_QUANTA.SOCKET4677_AZIF0045P001C01CS(CHIPS)':
 'VSS558': CDS_PINID='VSS558';
NODE_NAME     U1 CV26
 '@S9S_MB_2U_LIB.S9S_MB_2U(SCH_1):PAGE71_I5@PURE_QUANTA.SOCKET4677_AZIF0045P001C01CS(CHIPS)':
 'VSS562': CDS_PINID='VSS562';
NODE_NAME     U1 CV79
 '@S9S_MB_2U_LIB.S9S_MB_2U(SCH_1):PAGE71_I5@PURE_QUANTA.SOCKET4677_AZIF0045P001C01CS(CHIPS)':
 'VSS571': CDS_PINID='VSS571';
NODE_NAME     U1 CW33
 '@S9S_MB_2U_LIB.S9S_MB_2U(SCH_1):PAGE71_I5@PURE_QUANTA.SOCKET4677_AZIF0045P001C01CS(CHIPS)':
 'VSS583': CDS_PINID='VSS583';
NODE_NAME     U1 CW70
 '@S9S_MB_2U_LIB.S9S_MB_2U(SCH_1):PAGE71_I5@PURE_QUANTA.SOCKET4677_AZIF0045P001C01CS(CHIPS)':
 'VSS595': CDS_PINID='VSS595';
NODE_NAME     U1 CY4
 '@S9S_MB_2U_LIB.S9S_MB_2U(SCH_1):PAGE71_I5@PURE_QUANTA.SOCKET4677_AZIF0045P001C01CS(CHIPS)':
 'VSS611': CDS_PINID='VSS611';
NODE_NAME     U1 DA43
 '@S9S_MB_2U_LIB.S9S_MB_2U(SCH_1):PAGE71_I5@PURE_QUANTA.SOCKET4677_AZIF0045P001C01CS(CHIPS)':
 'VSS679': CDS_PINID='VSS679';
NODE_NAME     U1 DA68
 '@S9S_MB_2U_LIB.S9S_MB_2U(SCH_1):PAGE71_I5@PURE_QUANTA.SOCKET4677_AZIF0045P001C01CS(CHIPS)':
 'VSS690': CDS_PINID='VSS690';
NODE_NAME     U1 DB16
 '@S9S_MB_2U_LIB.S9S_MB_2U(SCH_1):PAGE71_I5@PURE_QUANTA.SOCKET4677_AZIF0045P001C01CS(CHIPS)':
 'VSS699': CDS_PINID='VSS699';
NODE_NAME     U1 DB20
 '@S9S_MB_2U_LIB.S9S_MB_2U(SCH_1):PAGE71_I5@PURE_QUANTA.SOCKET4677_AZIF0045P001C01CS(CHIPS)':
 'VSS700': CDS_PINID='VSS700';
NODE_NAME     U1 DB26
 '@S9S_MB_2U_LIB.S9S_MB_2U(SCH_1):PAGE71_I5@PURE_QUANTA.SOCKET4677_AZIF0045P001C01CS(CHIPS)':
 'VSS702': CDS_PINID='VSS702';
NODE_NAME     U1 DB34
 '@S9S_MB_2U_LIB.S9S_MB_2U(SCH_1):PAGE71_I5@PURE_QUANTA.SOCKET4677_AZIF0045P001C01CS(CHIPS)':
 'VSS705': CDS_PINID='VSS705';
NODE_NAME     U1 DB44
 '@S9S_MB_2U_LIB.S9S_MB_2U(SCH_1):PAGE71_I5@PURE_QUANTA.SOCKET4677_AZIF0045P001C01CS(CHIPS)':
 'VSS709': CDS_PINID='VSS709';
NODE_NAME     U1 DB51
 '@S9S_MB_2U_LIB.S9S_MB_2U(SCH_1):PAGE71_I5@PURE_QUANTA.SOCKET4677_AZIF0045P001C01CS(CHIPS)':
 'VSS711': CDS_PINID='VSS711';
NODE_NAME     U1 DB53
 '@S9S_MB_2U_LIB.S9S_MB_2U(SCH_1):PAGE71_I5@PURE_QUANTA.SOCKET4677_AZIF0045P001C01CS(CHIPS)':
 'VSS712': CDS_PINID='VSS712';
NODE_NAME     U1 DB59
 '@S9S_MB_2U_LIB.S9S_MB_2U(SCH_1):PAGE71_I5@PURE_QUANTA.SOCKET4677_AZIF0045P001C01CS(CHIPS)':
 'VSS714': CDS_PINID='VSS714';
NODE_NAME     U1 DB63
 '@S9S_MB_2U_LIB.S9S_MB_2U(SCH_1):PAGE71_I5@PURE_QUANTA.SOCKET4677_AZIF0045P001C01CS(CHIPS)':
 'VSS715': CDS_PINID='VSS715';
NODE_NAME     U1 DB69
 '@S9S_MB_2U_LIB.S9S_MB_2U(SCH_1):PAGE71_I5@PURE_QUANTA.SOCKET4677_AZIF0045P001C01CS(CHIPS)':
 'VSS717': CDS_PINID='VSS717';
NODE_NAME     U1 DB75
 '@S9S_MB_2U_LIB.S9S_MB_2U(SCH_1):PAGE71_I5@PURE_QUANTA.SOCKET4677_AZIF0045P001C01CS(CHIPS)':
 'VSS719': CDS_PINID='VSS719';
NODE_NAME     U1 CK63
 '@S9S_MB_2U_LIB.S9S_MB_2U(SCH_1):PAGE71_I5@PURE_QUANTA.SOCKET4677_AZIF0045P001C01CS(CHIPS)':
 'VSS744': CDS_PINID='VSS744';
NODE_NAME     U1 CK69
 '@S9S_MB_2U_LIB.S9S_MB_2U(SCH_1):PAGE71_I5@PURE_QUANTA.SOCKET4677_AZIF0045P001C01CS(CHIPS)':
 'VSS745': CDS_PINID='VSS745';
NODE_NAME     U1 CK81
 '@S9S_MB_2U_LIB.S9S_MB_2U(SCH_1):PAGE71_I5@PURE_QUANTA.SOCKET4677_AZIF0045P001C01CS(CHIPS)':
 'VSS749': CDS_PINID='VSS749';
NODE_NAME     U1 CL1
 '@S9S_MB_2U_LIB.S9S_MB_2U(SCH_1):PAGE71_I5@PURE_QUANTA.SOCKET4677_AZIF0045P001C01CS(CHIPS)':
 'VSS750': CDS_PINID='VSS750';
NODE_NAME     U1 CL13
 '@S9S_MB_2U_LIB.S9S_MB_2U(SCH_1):PAGE71_I5@PURE_QUANTA.SOCKET4677_AZIF0045P001C01CS(CHIPS)':
 'VSS751': CDS_PINID='VSS751';
NODE_NAME     U1 CL17
 '@S9S_MB_2U_LIB.S9S_MB_2U(SCH_1):PAGE71_I5@PURE_QUANTA.SOCKET4677_AZIF0045P001C01CS(CHIPS)':
 'VSS752': CDS_PINID='VSS752';
NODE_NAME     U1 CL5
 '@S9S_MB_2U_LIB.S9S_MB_2U(SCH_1):PAGE71_I5@PURE_QUANTA.SOCKET4677_AZIF0045P001C01CS(CHIPS)':
 'VSS754': CDS_PINID='VSS754';
NODE_NAME     U1 CL62
 '@S9S_MB_2U_LIB.S9S_MB_2U(SCH_1):PAGE71_I5@PURE_QUANTA.SOCKET4677_AZIF0045P001C01CS(CHIPS)':
 'VSS755': CDS_PINID='VSS755';
NODE_NAME     U1 CL74
 '@S9S_MB_2U_LIB.S9S_MB_2U(SCH_1):PAGE71_I5@PURE_QUANTA.SOCKET4677_AZIF0045P001C01CS(CHIPS)':
 'VSS756': CDS_PINID='VSS756';
NODE_NAME     U1 CL78
 '@S9S_MB_2U_LIB.S9S_MB_2U(SCH_1):PAGE71_I5@PURE_QUANTA.SOCKET4677_AZIF0045P001C01CS(CHIPS)':
 'VSS757': CDS_PINID='VSS757';
NODE_NAME     U1 CL80
 '@S9S_MB_2U_LIB.S9S_MB_2U(SCH_1):PAGE71_I5@PURE_QUANTA.SOCKET4677_AZIF0045P001C01CS(CHIPS)':
 'VSS758': CDS_PINID='VSS758';
NODE_NAME     U1 CL82
 '@S9S_MB_2U_LIB.S9S_MB_2U(SCH_1):PAGE71_I5@PURE_QUANTA.SOCKET4677_AZIF0045P001C01CS(CHIPS)':
 'VSS759': CDS_PINID='VSS759';
NODE_NAME     U1 CL9
 '@S9S_MB_2U_LIB.S9S_MB_2U(SCH_1):PAGE71_I5@PURE_QUANTA.SOCKET4677_AZIF0045P001C01CS(CHIPS)':
 'VSS760': CDS_PINID='VSS760';
NODE_NAME     U1 CM12
 '@S9S_MB_2U_LIB.S9S_MB_2U(SCH_1):PAGE71_I5@PURE_QUANTA.SOCKET4677_AZIF0045P001C01CS(CHIPS)':
 'VSS761': CDS_PINID='VSS761';
NODE_NAME     U1 CM20
 '@S9S_MB_2U_LIB.S9S_MB_2U(SCH_1):PAGE71_I5@PURE_QUANTA.SOCKET4677_AZIF0045P001C01CS(CHIPS)':
 'VSS762': CDS_PINID='VSS762';
NODE_NAME     U1 CM24
 '@S9S_MB_2U_LIB.S9S_MB_2U(SCH_1):PAGE71_I5@PURE_QUANTA.SOCKET4677_AZIF0045P001C01CS(CHIPS)':
 'VSS763': CDS_PINID='VSS763';
NODE_NAME     U1 CM4
 '@S9S_MB_2U_LIB.S9S_MB_2U(SCH_1):PAGE71_I5@PURE_QUANTA.SOCKET4677_AZIF0045P001C01CS(CHIPS)':
 'VSS764': CDS_PINID='VSS764';
NODE_NAME     U1 CM61
 '@S9S_MB_2U_LIB.S9S_MB_2U(SCH_1):PAGE71_I5@PURE_QUANTA.SOCKET4677_AZIF0045P001C01CS(CHIPS)':
 'VSS765': CDS_PINID='VSS765';
NODE_NAME     U1 CM65
 '@S9S_MB_2U_LIB.S9S_MB_2U(SCH_1):PAGE71_I5@PURE_QUANTA.SOCKET4677_AZIF0045P001C01CS(CHIPS)':
 'VSS766': CDS_PINID='VSS766';
NODE_NAME     U1 CM67
 '@S9S_MB_2U_LIB.S9S_MB_2U(SCH_1):PAGE71_I5@PURE_QUANTA.SOCKET4677_AZIF0045P001C01CS(CHIPS)':
 'VSS767': CDS_PINID='VSS767';
NODE_NAME     U1 CM79
 '@S9S_MB_2U_LIB.S9S_MB_2U(SCH_1):PAGE71_I5@PURE_QUANTA.SOCKET4677_AZIF0045P001C01CS(CHIPS)':
 'VSS768': CDS_PINID='VSS768';
NODE_NAME     U1 CM8
 '@S9S_MB_2U_LIB.S9S_MB_2U(SCH_1):PAGE71_I5@PURE_QUANTA.SOCKET4677_AZIF0045P001C01CS(CHIPS)':
 'VSS769': CDS_PINID='VSS769';
NODE_NAME     U1 CM81
 '@S9S_MB_2U_LIB.S9S_MB_2U(SCH_1):PAGE71_I5@PURE_QUANTA.SOCKET4677_AZIF0045P001C01CS(CHIPS)':
 'VSS770': CDS_PINID='VSS770';
NODE_NAME     U1 CM83
 '@S9S_MB_2U_LIB.S9S_MB_2U(SCH_1):PAGE71_I5@PURE_QUANTA.SOCKET4677_AZIF0045P001C01CS(CHIPS)':
 'VSS771': CDS_PINID='VSS771';
NODE_NAME     U1 CM85
 '@S9S_MB_2U_LIB.S9S_MB_2U(SCH_1):PAGE71_I5@PURE_QUANTA.SOCKET4677_AZIF0045P001C01CS(CHIPS)':
 'VSS772': CDS_PINID='VSS772';
NODE_NAME     U1 CN68
 '@S9S_MB_2U_LIB.S9S_MB_2U(SCH_1):PAGE71_I5@PURE_QUANTA.SOCKET4677_AZIF0045P001C01CS(CHIPS)':
 'VSS773': CDS_PINID='VSS773';
NODE_NAME     U1 CN70
 '@S9S_MB_2U_LIB.S9S_MB_2U(SCH_1):PAGE71_I5@PURE_QUANTA.SOCKET4677_AZIF0045P001C01CS(CHIPS)':
 'VSS774': CDS_PINID='VSS774';
NODE_NAME     U1 CN72
 '@S9S_MB_2U_LIB.S9S_MB_2U(SCH_1):PAGE71_I5@PURE_QUANTA.SOCKET4677_AZIF0045P001C01CS(CHIPS)':
 'VSS775': CDS_PINID='VSS775';
NODE_NAME     U1 CN74
 '@S9S_MB_2U_LIB.S9S_MB_2U(SCH_1):PAGE71_I5@PURE_QUANTA.SOCKET4677_AZIF0045P001C01CS(CHIPS)':
 'VSS777': CDS_PINID='VSS777';
NODE_NAME     U1 CN84
 '@S9S_MB_2U_LIB.S9S_MB_2U(SCH_1):PAGE71_I5@PURE_QUANTA.SOCKET4677_AZIF0045P001C01CS(CHIPS)':
 'VSS778': CDS_PINID='VSS778';
NODE_NAME     U1 CN86
 '@S9S_MB_2U_LIB.S9S_MB_2U(SCH_1):PAGE71_I5@PURE_QUANTA.SOCKET4677_AZIF0045P001C01CS(CHIPS)':
 'VSS779': CDS_PINID='VSS779';
NODE_NAME     U1 CP12
 '@S9S_MB_2U_LIB.S9S_MB_2U(SCH_1):PAGE71_I5@PURE_QUANTA.SOCKET4677_AZIF0045P001C01CS(CHIPS)':
 'VSS780': CDS_PINID='VSS780';
NODE_NAME     U1 CP18
 '@S9S_MB_2U_LIB.S9S_MB_2U(SCH_1):PAGE71_I5@PURE_QUANTA.SOCKET4677_AZIF0045P001C01CS(CHIPS)':
 'VSS781': CDS_PINID='VSS781';
NODE_NAME     U1 CP4
 '@S9S_MB_2U_LIB.S9S_MB_2U(SCH_1):PAGE71_I5@PURE_QUANTA.SOCKET4677_AZIF0045P001C01CS(CHIPS)':
 'VSS782': CDS_PINID='VSS782';
NODE_NAME     U1 CP75
 '@S9S_MB_2U_LIB.S9S_MB_2U(SCH_1):PAGE71_I5@PURE_QUANTA.SOCKET4677_AZIF0045P001C01CS(CHIPS)':
 'VSS783': CDS_PINID='VSS783';
NODE_NAME     U1 CP77
 '@S9S_MB_2U_LIB.S9S_MB_2U(SCH_1):PAGE71_I5@PURE_QUANTA.SOCKET4677_AZIF0045P001C01CS(CHIPS)':
 'VSS784': CDS_PINID='VSS784';
NODE_NAME     U1 CP8
 '@S9S_MB_2U_LIB.S9S_MB_2U(SCH_1):PAGE71_I5@PURE_QUANTA.SOCKET4677_AZIF0045P001C01CS(CHIPS)':
 'VSS785': CDS_PINID='VSS785';
NODE_NAME     U1 CP83
 '@S9S_MB_2U_LIB.S9S_MB_2U(SCH_1):PAGE71_I5@PURE_QUANTA.SOCKET4677_AZIF0045P001C01CS(CHIPS)':
 'VSS786': CDS_PINID='VSS786';
NODE_NAME     U1 CP87
 '@S9S_MB_2U_LIB.S9S_MB_2U(SCH_1):PAGE71_I5@PURE_QUANTA.SOCKET4677_AZIF0045P001C01CS(CHIPS)':
 'VSS787': CDS_PINID='VSS787';
NODE_NAME     U1 CP91
 '@S9S_MB_2U_LIB.S9S_MB_2U(SCH_1):PAGE71_I5@PURE_QUANTA.SOCKET4677_AZIF0045P001C01CS(CHIPS)':
 'VSS788': CDS_PINID='VSS788';
NODE_NAME     U1 CR1
 '@S9S_MB_2U_LIB.S9S_MB_2U(SCH_1):PAGE71_I5@PURE_QUANTA.SOCKET4677_AZIF0045P001C01CS(CHIPS)':
 'VSS789': CDS_PINID='VSS789';
NODE_NAME     U1 CR11
 '@S9S_MB_2U_LIB.S9S_MB_2U(SCH_1):PAGE71_I5@PURE_QUANTA.SOCKET4677_AZIF0045P001C01CS(CHIPS)':
 'VSS790': CDS_PINID='VSS790';
NODE_NAME     U1 CR13
 '@S9S_MB_2U_LIB.S9S_MB_2U(SCH_1):PAGE71_I5@PURE_QUANTA.SOCKET4677_AZIF0045P001C01CS(CHIPS)':
 'VSS792': CDS_PINID='VSS792';
NODE_NAME     U1 CR17
 '@S9S_MB_2U_LIB.S9S_MB_2U(SCH_1):PAGE71_I5@PURE_QUANTA.SOCKET4677_AZIF0045P001C01CS(CHIPS)':
 'VSS793': CDS_PINID='VSS793';
NODE_NAME     U1 CR5
 '@S9S_MB_2U_LIB.S9S_MB_2U(SCH_1):PAGE71_I5@PURE_QUANTA.SOCKET4677_AZIF0045P001C01CS(CHIPS)':
 'VSS794': CDS_PINID='VSS794';
NODE_NAME     U1 CR62
 '@S9S_MB_2U_LIB.S9S_MB_2U(SCH_1):PAGE71_I5@PURE_QUANTA.SOCKET4677_AZIF0045P001C01CS(CHIPS)':
 'VSS795': CDS_PINID='VSS795';
NODE_NAME     U1 CR64
 '@S9S_MB_2U_LIB.S9S_MB_2U(SCH_1):PAGE71_I5@PURE_QUANTA.SOCKET4677_AZIF0045P001C01CS(CHIPS)':
 'VSS796': CDS_PINID='VSS796';
NODE_NAME     U1 CR84
 '@S9S_MB_2U_LIB.S9S_MB_2U(SCH_1):PAGE71_I5@PURE_QUANTA.SOCKET4677_AZIF0045P001C01CS(CHIPS)':
 'VSS797': CDS_PINID='VSS797';
NODE_NAME     U1 CR88
 '@S9S_MB_2U_LIB.S9S_MB_2U(SCH_1):PAGE71_I5@PURE_QUANTA.SOCKET4677_AZIF0045P001C01CS(CHIPS)':
 'VSS800': CDS_PINID='VSS800';
NODE_NAME     U1 CR9
 '@S9S_MB_2U_LIB.S9S_MB_2U(SCH_1):PAGE71_I5@PURE_QUANTA.SOCKET4677_AZIF0045P001C01CS(CHIPS)':
 'VSS801': CDS_PINID='VSS801';
NODE_NAME     U1 CR90
 '@S9S_MB_2U_LIB.S9S_MB_2U(SCH_1):PAGE71_I5@PURE_QUANTA.SOCKET4677_AZIF0045P001C01CS(CHIPS)':
 'VSS803': CDS_PINID='VSS803';
NODE_NAME     U1 CT10
 '@S9S_MB_2U_LIB.S9S_MB_2U(SCH_1):PAGE71_I5@PURE_QUANTA.SOCKET4677_AZIF0045P001C01CS(CHIPS)':
 'VSS804': CDS_PINID='VSS804';
NODE_NAME     U1 CT12
 '@S9S_MB_2U_LIB.S9S_MB_2U(SCH_1):PAGE71_I5@PURE_QUANTA.SOCKET4677_AZIF0045P001C01CS(CHIPS)':
 'VSS805': CDS_PINID='VSS805';
NODE_NAME     U1 CT69
 '@S9S_MB_2U_LIB.S9S_MB_2U(SCH_1):PAGE71_I5@PURE_QUANTA.SOCKET4677_AZIF0045P001C01CS(CHIPS)':
 'VSS810': CDS_PINID='VSS810';
NODE_NAME     U1 CT73
 '@S9S_MB_2U_LIB.S9S_MB_2U(SCH_1):PAGE71_I5@PURE_QUANTA.SOCKET4677_AZIF0045P001C01CS(CHIPS)':
 'VSS811': CDS_PINID='VSS811';
NODE_NAME     U1 CT81
 '@S9S_MB_2U_LIB.S9S_MB_2U(SCH_1):PAGE71_I5@PURE_QUANTA.SOCKET4677_AZIF0045P001C01CS(CHIPS)':
 'VSS812': CDS_PINID='VSS812';
NODE_NAME     U1 CU19
 '@S9S_MB_2U_LIB.S9S_MB_2U(SCH_1):PAGE71_I5@PURE_QUANTA.SOCKET4677_AZIF0045P001C01CS(CHIPS)':
 'VSS813': CDS_PINID='VSS813';
NODE_NAME     U1 CU21
 '@S9S_MB_2U_LIB.S9S_MB_2U(SCH_1):PAGE71_I5@PURE_QUANTA.SOCKET4677_AZIF0045P001C01CS(CHIPS)':
 'VSS814': CDS_PINID='VSS814';
NODE_NAME     U1 CU23
 '@S9S_MB_2U_LIB.S9S_MB_2U(SCH_1):PAGE71_I5@PURE_QUANTA.SOCKET4677_AZIF0045P001C01CS(CHIPS)':
 'VSS815': CDS_PINID='VSS815';
NODE_NAME     U1 CU60
 '@S9S_MB_2U_LIB.S9S_MB_2U(SCH_1):PAGE71_I5@PURE_QUANTA.SOCKET4677_AZIF0045P001C01CS(CHIPS)':
 'VSS816': CDS_PINID='VSS816';
NODE_NAME     U1 CU66
 '@S9S_MB_2U_LIB.S9S_MB_2U(SCH_1):PAGE71_I5@PURE_QUANTA.SOCKET4677_AZIF0045P001C01CS(CHIPS)':
 'VSS818': CDS_PINID='VSS818';
NODE_NAME     U1 CU68
 '@S9S_MB_2U_LIB.S9S_MB_2U(SCH_1):PAGE71_I5@PURE_QUANTA.SOCKET4677_AZIF0045P001C01CS(CHIPS)':
 'VSS819': CDS_PINID='VSS819';
NODE_NAME     U1 CU84
 '@S9S_MB_2U_LIB.S9S_MB_2U(SCH_1):PAGE71_I5@PURE_QUANTA.SOCKET4677_AZIF0045P001C01CS(CHIPS)':
 'VSS822': CDS_PINID='VSS822';
NODE_NAME     U1 CU88
 '@S9S_MB_2U_LIB.S9S_MB_2U(SCH_1):PAGE71_I5@PURE_QUANTA.SOCKET4677_AZIF0045P001C01CS(CHIPS)':
 'VSS823': CDS_PINID='VSS823';
NODE_NAME     U1 CV12
 '@S9S_MB_2U_LIB.S9S_MB_2U(SCH_1):PAGE71_I5@PURE_QUANTA.SOCKET4677_AZIF0045P001C01CS(CHIPS)':
 'VSS824': CDS_PINID='VSS824';
NODE_NAME     U1 CV4
 '@S9S_MB_2U_LIB.S9S_MB_2U(SCH_1):PAGE71_I5@PURE_QUANTA.SOCKET4677_AZIF0045P001C01CS(CHIPS)':
 'VSS825': CDS_PINID='VSS825';
NODE_NAME     U1 CV75
 '@S9S_MB_2U_LIB.S9S_MB_2U(SCH_1):PAGE71_I5@PURE_QUANTA.SOCKET4677_AZIF0045P001C01CS(CHIPS)':
 'VSS826': CDS_PINID='VSS826';
NODE_NAME     U1 CV8
 '@S9S_MB_2U_LIB.S9S_MB_2U(SCH_1):PAGE71_I5@PURE_QUANTA.SOCKET4677_AZIF0045P001C01CS(CHIPS)':
 'VSS827': CDS_PINID='VSS827';
NODE_NAME     U1 CV83
 '@S9S_MB_2U_LIB.S9S_MB_2U(SCH_1):PAGE71_I5@PURE_QUANTA.SOCKET4677_AZIF0045P001C01CS(CHIPS)':
 'VSS828': CDS_PINID='VSS828';
NODE_NAME     U1 CV87
 '@S9S_MB_2U_LIB.S9S_MB_2U(SCH_1):PAGE71_I5@PURE_QUANTA.SOCKET4677_AZIF0045P001C01CS(CHIPS)':
 'VSS831': CDS_PINID='VSS831';
NODE_NAME     U1 CV91
 '@S9S_MB_2U_LIB.S9S_MB_2U(SCH_1):PAGE71_I5@PURE_QUANTA.SOCKET4677_AZIF0045P001C01CS(CHIPS)':
 'VSS833': CDS_PINID='VSS833';
NODE_NAME     U1 CW1
 '@S9S_MB_2U_LIB.S9S_MB_2U(SCH_1):PAGE71_I5@PURE_QUANTA.SOCKET4677_AZIF0045P001C01CS(CHIPS)':
 'VSS834': CDS_PINID='VSS834';
NODE_NAME     U1 CW13
 '@S9S_MB_2U_LIB.S9S_MB_2U(SCH_1):PAGE71_I5@PURE_QUANTA.SOCKET4677_AZIF0045P001C01CS(CHIPS)':
 'VSS836': CDS_PINID='VSS836';
NODE_NAME     U1 CW17
 '@S9S_MB_2U_LIB.S9S_MB_2U(SCH_1):PAGE71_I5@PURE_QUANTA.SOCKET4677_AZIF0045P001C01CS(CHIPS)':
 'VSS837': CDS_PINID='VSS837';
NODE_NAME     U1 CW5
 '@S9S_MB_2U_LIB.S9S_MB_2U(SCH_1):PAGE71_I5@PURE_QUANTA.SOCKET4677_AZIF0045P001C01CS(CHIPS)':
 'VSS838': CDS_PINID='VSS838';
NODE_NAME     U1 CW72
 '@S9S_MB_2U_LIB.S9S_MB_2U(SCH_1):PAGE71_I5@PURE_QUANTA.SOCKET4677_AZIF0045P001C01CS(CHIPS)':
 'VSS840': CDS_PINID='VSS840';
NODE_NAME     U1 CW78
 '@S9S_MB_2U_LIB.S9S_MB_2U(SCH_1):PAGE71_I5@PURE_QUANTA.SOCKET4677_AZIF0045P001C01CS(CHIPS)':
 'VSS843': CDS_PINID='VSS843';
NODE_NAME     U1 CW84
 '@S9S_MB_2U_LIB.S9S_MB_2U(SCH_1):PAGE71_I5@PURE_QUANTA.SOCKET4677_AZIF0045P001C01CS(CHIPS)':
 'VSS846': CDS_PINID='VSS846';
NODE_NAME     U1 CW88
 '@S9S_MB_2U_LIB.S9S_MB_2U(SCH_1):PAGE71_I5@PURE_QUANTA.SOCKET4677_AZIF0045P001C01CS(CHIPS)':
 'VSS848': CDS_PINID='VSS848';
NODE_NAME     U1 CW9
 '@S9S_MB_2U_LIB.S9S_MB_2U(SCH_1):PAGE71_I5@PURE_QUANTA.SOCKET4677_AZIF0045P001C01CS(CHIPS)':
 'VSS850': CDS_PINID='VSS850';
NODE_NAME     U1 CY12
 '@S9S_MB_2U_LIB.S9S_MB_2U(SCH_1):PAGE71_I5@PURE_QUANTA.SOCKET4677_AZIF0045P001C01CS(CHIPS)':
 'VSS851': CDS_PINID='VSS851';
NODE_NAME     U1 CY16
 '@S9S_MB_2U_LIB.S9S_MB_2U(SCH_1):PAGE71_I5@PURE_QUANTA.SOCKET4677_AZIF0045P001C01CS(CHIPS)':
 'VSS852': CDS_PINID='VSS852';
NODE_NAME     U1 CY18
 '@S9S_MB_2U_LIB.S9S_MB_2U(SCH_1):PAGE71_I5@PURE_QUANTA.SOCKET4677_AZIF0045P001C01CS(CHIPS)':
 'VSS853': CDS_PINID='VSS853';
NODE_NAME     U1 CY26
 '@S9S_MB_2U_LIB.S9S_MB_2U(SCH_1):PAGE71_I5@PURE_QUANTA.SOCKET4677_AZIF0045P001C01CS(CHIPS)':
 'VSS854': CDS_PINID='VSS854';
NODE_NAME     U1 CY30
 '@S9S_MB_2U_LIB.S9S_MB_2U(SCH_1):PAGE71_I5@PURE_QUANTA.SOCKET4677_AZIF0045P001C01CS(CHIPS)':
 'VSS855': CDS_PINID='VSS855';
NODE_NAME     U1 CY63
 '@S9S_MB_2U_LIB.S9S_MB_2U(SCH_1):PAGE71_I5@PURE_QUANTA.SOCKET4677_AZIF0045P001C01CS(CHIPS)':
 'VSS856': CDS_PINID='VSS856';
NODE_NAME     U1 CY73
 '@S9S_MB_2U_LIB.S9S_MB_2U(SCH_1):PAGE71_I5@PURE_QUANTA.SOCKET4677_AZIF0045P001C01CS(CHIPS)':
 'VSS858': CDS_PINID='VSS858';
NODE_NAME     U1 CY77
 '@S9S_MB_2U_LIB.S9S_MB_2U(SCH_1):PAGE71_I5@PURE_QUANTA.SOCKET4677_AZIF0045P001C01CS(CHIPS)':
 'VSS859': CDS_PINID='VSS859';
NODE_NAME     U1 CY8
 '@S9S_MB_2U_LIB.S9S_MB_2U(SCH_1):PAGE71_I5@PURE_QUANTA.SOCKET4677_AZIF0045P001C01CS(CHIPS)':
 'VSS860': CDS_PINID='VSS860';
NODE_NAME     U1 CY81
 '@S9S_MB_2U_LIB.S9S_MB_2U(SCH_1):PAGE71_I5@PURE_QUANTA.SOCKET4677_AZIF0045P001C01CS(CHIPS)':
 'VSS862': CDS_PINID='VSS862';
NODE_NAME     U1 CY83
 '@S9S_MB_2U_LIB.S9S_MB_2U(SCH_1):PAGE71_I5@PURE_QUANTA.SOCKET4677_AZIF0045P001C01CS(CHIPS)':
 'VSS863': CDS_PINID='VSS863';
NODE_NAME     U1 DA19
 '@S9S_MB_2U_LIB.S9S_MB_2U(SCH_1):PAGE71_I5@PURE_QUANTA.SOCKET4677_AZIF0045P001C01CS(CHIPS)':
 'VSS910': CDS_PINID='VSS910';
NODE_NAME     U1 DA23
 '@S9S_MB_2U_LIB.S9S_MB_2U(SCH_1):PAGE71_I5@PURE_QUANTA.SOCKET4677_AZIF0045P001C01CS(CHIPS)':
 'VSS911': CDS_PINID='VSS911';
NODE_NAME     U1 DA25
 '@S9S_MB_2U_LIB.S9S_MB_2U(SCH_1):PAGE71_I5@PURE_QUANTA.SOCKET4677_AZIF0045P001C01CS(CHIPS)':
 'VSS912': CDS_PINID='VSS912';
NODE_NAME     U1 DA29
 '@S9S_MB_2U_LIB.S9S_MB_2U(SCH_1):PAGE71_I5@PURE_QUANTA.SOCKET4677_AZIF0045P001C01CS(CHIPS)':
 'VSS913': CDS_PINID='VSS913';
NODE_NAME     U1 DA31
 '@S9S_MB_2U_LIB.S9S_MB_2U(SCH_1):PAGE71_I5@PURE_QUANTA.SOCKET4677_AZIF0045P001C01CS(CHIPS)':
 'VSS914': CDS_PINID='VSS914';
NODE_NAME     U1 DA33
 '@S9S_MB_2U_LIB.S9S_MB_2U(SCH_1):PAGE71_I5@PURE_QUANTA.SOCKET4677_AZIF0045P001C01CS(CHIPS)':
 'VSS915': CDS_PINID='VSS915';
NODE_NAME     U1 DA35
 '@S9S_MB_2U_LIB.S9S_MB_2U(SCH_1):PAGE71_I5@PURE_QUANTA.SOCKET4677_AZIF0045P001C01CS(CHIPS)':
 'VSS916': CDS_PINID='VSS916';
NODE_NAME     U1 DA37
 '@S9S_MB_2U_LIB.S9S_MB_2U(SCH_1):PAGE71_I5@PURE_QUANTA.SOCKET4677_AZIF0045P001C01CS(CHIPS)':
 'VSS917': CDS_PINID='VSS917';
NODE_NAME     U1 DA41
 '@S9S_MB_2U_LIB.S9S_MB_2U(SCH_1):PAGE71_I5@PURE_QUANTA.SOCKET4677_AZIF0045P001C01CS(CHIPS)':
 'VSS918': CDS_PINID='VSS918';
NODE_NAME     U1 DA48
 '@S9S_MB_2U_LIB.S9S_MB_2U(SCH_1):PAGE71_I5@PURE_QUANTA.SOCKET4677_AZIF0045P001C01CS(CHIPS)':
 'VSS919': CDS_PINID='VSS919';
NODE_NAME     U1 DA50
 '@S9S_MB_2U_LIB.S9S_MB_2U(SCH_1):PAGE71_I5@PURE_QUANTA.SOCKET4677_AZIF0045P001C01CS(CHIPS)':
 'VSS920': CDS_PINID='VSS920';
NODE_NAME     U1 DA54
 '@S9S_MB_2U_LIB.S9S_MB_2U(SCH_1):PAGE71_I5@PURE_QUANTA.SOCKET4677_AZIF0045P001C01CS(CHIPS)':
 'VSS921': CDS_PINID='VSS921';
NODE_NAME     U1 DA56
 '@S9S_MB_2U_LIB.S9S_MB_2U(SCH_1):PAGE71_I5@PURE_QUANTA.SOCKET4677_AZIF0045P001C01CS(CHIPS)':
 'VSS922': CDS_PINID='VSS922';
NODE_NAME     U1 DA58
 '@S9S_MB_2U_LIB.S9S_MB_2U(SCH_1):PAGE71_I5@PURE_QUANTA.SOCKET4677_AZIF0045P001C01CS(CHIPS)':
 'VSS923': CDS_PINID='VSS923';
NODE_NAME     U1 DA60
 '@S9S_MB_2U_LIB.S9S_MB_2U(SCH_1):PAGE71_I5@PURE_QUANTA.SOCKET4677_AZIF0045P001C01CS(CHIPS)':
 'VSS924': CDS_PINID='VSS924';
NODE_NAME     U1 DA62
 '@S9S_MB_2U_LIB.S9S_MB_2U(SCH_1):PAGE71_I5@PURE_QUANTA.SOCKET4677_AZIF0045P001C01CS(CHIPS)':
 'VSS925': CDS_PINID='VSS925';
NODE_NAME     U1 DA66
 '@S9S_MB_2U_LIB.S9S_MB_2U(SCH_1):PAGE71_I5@PURE_QUANTA.SOCKET4677_AZIF0045P001C01CS(CHIPS)':
 'VSS926': CDS_PINID='VSS926';
NODE_NAME     U1 DA72
 '@S9S_MB_2U_LIB.S9S_MB_2U(SCH_1):PAGE71_I5@PURE_QUANTA.SOCKET4677_AZIF0045P001C01CS(CHIPS)':
 'VSS927': CDS_PINID='VSS927';
NODE_NAME     U1 DA74
 '@S9S_MB_2U_LIB.S9S_MB_2U(SCH_1):PAGE71_I5@PURE_QUANTA.SOCKET4677_AZIF0045P001C01CS(CHIPS)':
 'VSS928': CDS_PINID='VSS928';
NODE_NAME     U1 DA80
 '@S9S_MB_2U_LIB.S9S_MB_2U(SCH_1):PAGE71_I5@PURE_QUANTA.SOCKET4677_AZIF0045P001C01CS(CHIPS)':
 'VSS929': CDS_PINID='VSS929';
NODE_NAME     U1 DA82
 '@S9S_MB_2U_LIB.S9S_MB_2U(SCH_1):PAGE71_I5@PURE_QUANTA.SOCKET4677_AZIF0045P001C01CS(CHIPS)':
 'VSS930': CDS_PINID='VSS930';
NODE_NAME     U1 DA84
 '@S9S_MB_2U_LIB.S9S_MB_2U(SCH_1):PAGE71_I5@PURE_QUANTA.SOCKET4677_AZIF0045P001C01CS(CHIPS)':
 'VSS931': CDS_PINID='VSS931';
NODE_NAME     U1 DA88
 '@S9S_MB_2U_LIB.S9S_MB_2U(SCH_1):PAGE71_I5@PURE_QUANTA.SOCKET4677_AZIF0045P001C01CS(CHIPS)':
 'VSS932': CDS_PINID='VSS932';
NODE_NAME     U1 DB12
 '@S9S_MB_2U_LIB.S9S_MB_2U(SCH_1):PAGE71_I5@PURE_QUANTA.SOCKET4677_AZIF0045P001C01CS(CHIPS)':
 'VSS933': CDS_PINID='VSS933';
NODE_NAME     U1 DB22
 '@S9S_MB_2U_LIB.S9S_MB_2U(SCH_1):PAGE71_I5@PURE_QUANTA.SOCKET4677_AZIF0045P001C01CS(CHIPS)':
 'VSS935': CDS_PINID='VSS935';
NODE_NAME     U1 DB28
 '@S9S_MB_2U_LIB.S9S_MB_2U(SCH_1):PAGE71_I5@PURE_QUANTA.SOCKET4677_AZIF0045P001C01CS(CHIPS)':
 'VSS936': CDS_PINID='VSS936';
NODE_NAME     U1 DB32
 '@S9S_MB_2U_LIB.S9S_MB_2U(SCH_1):PAGE71_I5@PURE_QUANTA.SOCKET4677_AZIF0045P001C01CS(CHIPS)':
 'VSS937': CDS_PINID='VSS937';
NODE_NAME     U1 DB38
 '@S9S_MB_2U_LIB.S9S_MB_2U(SCH_1):PAGE71_I5@PURE_QUANTA.SOCKET4677_AZIF0045P001C01CS(CHIPS)':
 'VSS938': CDS_PINID='VSS938';
NODE_NAME     U1 DB4
 '@S9S_MB_2U_LIB.S9S_MB_2U(SCH_1):PAGE71_I5@PURE_QUANTA.SOCKET4677_AZIF0045P001C01CS(CHIPS)':
 'VSS939': CDS_PINID='VSS939';
NODE_NAME     U1 DB40
 '@S9S_MB_2U_LIB.S9S_MB_2U(SCH_1):PAGE71_I5@PURE_QUANTA.SOCKET4677_AZIF0045P001C01CS(CHIPS)':
 'VSS940': CDS_PINID='VSS940';
NODE_NAME     U1 DB47
 '@S9S_MB_2U_LIB.S9S_MB_2U(SCH_1):PAGE71_I5@PURE_QUANTA.SOCKET4677_AZIF0045P001C01CS(CHIPS)':
 'VSS941': CDS_PINID='VSS941';
NODE_NAME     U1 DB57
 '@S9S_MB_2U_LIB.S9S_MB_2U(SCH_1):PAGE71_I5@PURE_QUANTA.SOCKET4677_AZIF0045P001C01CS(CHIPS)':
 'VSS942': CDS_PINID='VSS942';
NODE_NAME     U1 DB65
 '@S9S_MB_2U_LIB.S9S_MB_2U(SCH_1):PAGE71_I5@PURE_QUANTA.SOCKET4677_AZIF0045P001C01CS(CHIPS)':
 'VSS943': CDS_PINID='VSS943';
NODE_NAME     U1 DB71
 '@S9S_MB_2U_LIB.S9S_MB_2U(SCH_1):PAGE71_I5@PURE_QUANTA.SOCKET4677_AZIF0045P001C01CS(CHIPS)':
 'VSS944': CDS_PINID='VSS944';
NODE_NAME     U1 DB77
 '@S9S_MB_2U_LIB.S9S_MB_2U(SCH_1):PAGE71_I5@PURE_QUANTA.SOCKET4677_AZIF0045P001C01CS(CHIPS)':
 'VSS946': CDS_PINID='VSS946';
NODE_NAME     U1 DB8
 '@S9S_MB_2U_LIB.S9S_MB_2U(SCH_1):PAGE71_I5@PURE_QUANTA.SOCKET4677_AZIF0045P001C01CS(CHIPS)':
 'VSS947': CDS_PINID='VSS947';
NODE_NAME     U1 DB87
 '@S9S_MB_2U_LIB.S9S_MB_2U(SCH_1):PAGE71_I5@PURE_QUANTA.SOCKET4677_AZIF0045P001C01CS(CHIPS)':
 'VSS948': CDS_PINID='VSS948';
NODE_NAME     U1 CJ76
 '@S9S_MB_2U_LIB.S9S_MB_2U(SCH_1):PAGE71_I8@PURE_QUANTA.SOCKET4677_AZIF0045P001C01CS(CHIPS)':
 'VSS383': CDS_PINID='VSS383';
NODE_NAME     U1 CK4
 '@S9S_MB_2U_LIB.S9S_MB_2U(SCH_1):PAGE71_I8@PURE_QUANTA.SOCKET4677_AZIF0045P001C01CS(CHIPS)':
 'VSS396': CDS_PINID='VSS396';
NODE_NAME     U1 BR35
 '@S9S_MB_2U_LIB.S9S_MB_2U(SCH_1):PAGE71_I8@PURE_QUANTA.SOCKET4677_AZIF0045P001C01CS(CHIPS)':
 'VSS542': CDS_PINID='VSS542';
NODE_NAME     U1 BR37
 '@S9S_MB_2U_LIB.S9S_MB_2U(SCH_1):PAGE71_I8@PURE_QUANTA.SOCKET4677_AZIF0045P001C01CS(CHIPS)':
 'VSS543': CDS_PINID='VSS543';
NODE_NAME     U1 BR39
 '@S9S_MB_2U_LIB.S9S_MB_2U(SCH_1):PAGE71_I8@PURE_QUANTA.SOCKET4677_AZIF0045P001C01CS(CHIPS)':
 'VSS545': CDS_PINID='VSS545';
NODE_NAME     U1 BR41
 '@S9S_MB_2U_LIB.S9S_MB_2U(SCH_1):PAGE71_I8@PURE_QUANTA.SOCKET4677_AZIF0045P001C01CS(CHIPS)':
 'VSS546': CDS_PINID='VSS546';
NODE_NAME     U1 BR43
 '@S9S_MB_2U_LIB.S9S_MB_2U(SCH_1):PAGE71_I8@PURE_QUANTA.SOCKET4677_AZIF0045P001C01CS(CHIPS)':
 'VSS547': CDS_PINID='VSS547';
NODE_NAME     U1 BR45
 '@S9S_MB_2U_LIB.S9S_MB_2U(SCH_1):PAGE71_I8@PURE_QUANTA.SOCKET4677_AZIF0045P001C01CS(CHIPS)':
 'VSS548': CDS_PINID='VSS548';
NODE_NAME     U1 BR48
 '@S9S_MB_2U_LIB.S9S_MB_2U(SCH_1):PAGE71_I8@PURE_QUANTA.SOCKET4677_AZIF0045P001C01CS(CHIPS)':
 'VSS549': CDS_PINID='VSS549';
NODE_NAME     U1 BR50
 '@S9S_MB_2U_LIB.S9S_MB_2U(SCH_1):PAGE71_I8@PURE_QUANTA.SOCKET4677_AZIF0045P001C01CS(CHIPS)':
 'VSS550': CDS_PINID='VSS550';
NODE_NAME     U1 BR52
 '@S9S_MB_2U_LIB.S9S_MB_2U(SCH_1):PAGE71_I8@PURE_QUANTA.SOCKET4677_AZIF0045P001C01CS(CHIPS)':
 'VSS551': CDS_PINID='VSS551';
NODE_NAME     U1 BR54
 '@S9S_MB_2U_LIB.S9S_MB_2U(SCH_1):PAGE71_I8@PURE_QUANTA.SOCKET4677_AZIF0045P001C01CS(CHIPS)':
 'VSS552': CDS_PINID='VSS552';
NODE_NAME     U1 BR56
 '@S9S_MB_2U_LIB.S9S_MB_2U(SCH_1):PAGE71_I8@PURE_QUANTA.SOCKET4677_AZIF0045P001C01CS(CHIPS)':
 'VSS555': CDS_PINID='VSS555';
NODE_NAME     U1 BR58
 '@S9S_MB_2U_LIB.S9S_MB_2U(SCH_1):PAGE71_I8@PURE_QUANTA.SOCKET4677_AZIF0045P001C01CS(CHIPS)':
 'VSS556': CDS_PINID='VSS556';
NODE_NAME     U1 BR64
 '@S9S_MB_2U_LIB.S9S_MB_2U(SCH_1):PAGE71_I8@PURE_QUANTA.SOCKET4677_AZIF0045P001C01CS(CHIPS)':
 'VSS557': CDS_PINID='VSS557';
NODE_NAME     U1 BR66
 '@S9S_MB_2U_LIB.S9S_MB_2U(SCH_1):PAGE71_I8@PURE_QUANTA.SOCKET4677_AZIF0045P001C01CS(CHIPS)':
 'VSS559': CDS_PINID='VSS559';
NODE_NAME     U1 BR68
 '@S9S_MB_2U_LIB.S9S_MB_2U(SCH_1):PAGE71_I8@PURE_QUANTA.SOCKET4677_AZIF0045P001C01CS(CHIPS)':
 'VSS560': CDS_PINID='VSS560';
NODE_NAME     U1 BR70
 '@S9S_MB_2U_LIB.S9S_MB_2U(SCH_1):PAGE71_I8@PURE_QUANTA.SOCKET4677_AZIF0045P001C01CS(CHIPS)':
 'VSS561': CDS_PINID='VSS561';
NODE_NAME     U1 BR72
 '@S9S_MB_2U_LIB.S9S_MB_2U(SCH_1):PAGE71_I8@PURE_QUANTA.SOCKET4677_AZIF0045P001C01CS(CHIPS)':
 'VSS563': CDS_PINID='VSS563';
NODE_NAME     U1 BR74
 '@S9S_MB_2U_LIB.S9S_MB_2U(SCH_1):PAGE71_I8@PURE_QUANTA.SOCKET4677_AZIF0045P001C01CS(CHIPS)':
 'VSS564': CDS_PINID='VSS564';
NODE_NAME     U1 BR76
 '@S9S_MB_2U_LIB.S9S_MB_2U(SCH_1):PAGE71_I8@PURE_QUANTA.SOCKET4677_AZIF0045P001C01CS(CHIPS)':
 'VSS565': CDS_PINID='VSS565';
NODE_NAME     U1 BR80
 '@S9S_MB_2U_LIB.S9S_MB_2U(SCH_1):PAGE71_I8@PURE_QUANTA.SOCKET4677_AZIF0045P001C01CS(CHIPS)':
 'VSS566': CDS_PINID='VSS566';
NODE_NAME     U1 BR82
 '@S9S_MB_2U_LIB.S9S_MB_2U(SCH_1):PAGE71_I8@PURE_QUANTA.SOCKET4677_AZIF0045P001C01CS(CHIPS)':
 'VSS567': CDS_PINID='VSS567';
NODE_NAME     U1 BR84
 '@S9S_MB_2U_LIB.S9S_MB_2U(SCH_1):PAGE71_I8@PURE_QUANTA.SOCKET4677_AZIF0045P001C01CS(CHIPS)':
 'VSS568': CDS_PINID='VSS568';
NODE_NAME     U1 BR86
 '@S9S_MB_2U_LIB.S9S_MB_2U(SCH_1):PAGE71_I8@PURE_QUANTA.SOCKET4677_AZIF0045P001C01CS(CHIPS)':
 'VSS569': CDS_PINID='VSS569';
NODE_NAME     U1 BR88
 '@S9S_MB_2U_LIB.S9S_MB_2U(SCH_1):PAGE71_I8@PURE_QUANTA.SOCKET4677_AZIF0045P001C01CS(CHIPS)':
 'VSS570': CDS_PINID='VSS570';
NODE_NAME     U1 BR90
 '@S9S_MB_2U_LIB.S9S_MB_2U(SCH_1):PAGE71_I8@PURE_QUANTA.SOCKET4677_AZIF0045P001C01CS(CHIPS)':
 'VSS573': CDS_PINID='VSS573';
NODE_NAME     U1 BT12
 '@S9S_MB_2U_LIB.S9S_MB_2U(SCH_1):PAGE71_I8@PURE_QUANTA.SOCKET4677_AZIF0045P001C01CS(CHIPS)':
 'VSS574': CDS_PINID='VSS574';
NODE_NAME     U1 BT16
 '@S9S_MB_2U_LIB.S9S_MB_2U(SCH_1):PAGE71_I8@PURE_QUANTA.SOCKET4677_AZIF0045P001C01CS(CHIPS)':
 'VSS575': CDS_PINID='VSS575';
NODE_NAME     U1 BT20
 '@S9S_MB_2U_LIB.S9S_MB_2U(SCH_1):PAGE71_I8@PURE_QUANTA.SOCKET4677_AZIF0045P001C01CS(CHIPS)':
 'VSS576': CDS_PINID='VSS576';
NODE_NAME     U1 BT4
 '@S9S_MB_2U_LIB.S9S_MB_2U(SCH_1):PAGE71_I8@PURE_QUANTA.SOCKET4677_AZIF0045P001C01CS(CHIPS)':
 'VSS577': CDS_PINID='VSS577';
NODE_NAME     U1 BT8
 '@S9S_MB_2U_LIB.S9S_MB_2U(SCH_1):PAGE71_I8@PURE_QUANTA.SOCKET4677_AZIF0045P001C01CS(CHIPS)':
 'VSS578': CDS_PINID='VSS578';
NODE_NAME     U1 BU15
 '@S9S_MB_2U_LIB.S9S_MB_2U(SCH_1):PAGE71_I8@PURE_QUANTA.SOCKET4677_AZIF0045P001C01CS(CHIPS)':
 'VSS579': CDS_PINID='VSS579';
NODE_NAME     U1 BU19
 '@S9S_MB_2U_LIB.S9S_MB_2U(SCH_1):PAGE71_I8@PURE_QUANTA.SOCKET4677_AZIF0045P001C01CS(CHIPS)':
 'VSS580': CDS_PINID='VSS580';
NODE_NAME     U1 BU21
 '@S9S_MB_2U_LIB.S9S_MB_2U(SCH_1):PAGE71_I8@PURE_QUANTA.SOCKET4677_AZIF0045P001C01CS(CHIPS)':
 'VSS581': CDS_PINID='VSS581';
NODE_NAME     U1 BU23
 '@S9S_MB_2U_LIB.S9S_MB_2U(SCH_1):PAGE71_I8@PURE_QUANTA.SOCKET4677_AZIF0045P001C01CS(CHIPS)':
 'VSS582': CDS_PINID='VSS582';
NODE_NAME     U1 BU25
 '@S9S_MB_2U_LIB.S9S_MB_2U(SCH_1):PAGE71_I8@PURE_QUANTA.SOCKET4677_AZIF0045P001C01CS(CHIPS)':
 'VSS584': CDS_PINID='VSS584';
NODE_NAME     U1 BU31
 '@S9S_MB_2U_LIB.S9S_MB_2U(SCH_1):PAGE71_I8@PURE_QUANTA.SOCKET4677_AZIF0045P001C01CS(CHIPS)':
 'VSS585': CDS_PINID='VSS585';
NODE_NAME     U1 BU7
 '@S9S_MB_2U_LIB.S9S_MB_2U(SCH_1):PAGE71_I8@PURE_QUANTA.SOCKET4677_AZIF0045P001C01CS(CHIPS)':
 'VSS586': CDS_PINID='VSS586';
NODE_NAME     U1 BV12
 '@S9S_MB_2U_LIB.S9S_MB_2U(SCH_1):PAGE71_I8@PURE_QUANTA.SOCKET4677_AZIF0045P001C01CS(CHIPS)':
 'VSS587': CDS_PINID='VSS587';
NODE_NAME     U1 BV16
 '@S9S_MB_2U_LIB.S9S_MB_2U(SCH_1):PAGE71_I8@PURE_QUANTA.SOCKET4677_AZIF0045P001C01CS(CHIPS)':
 'VSS588': CDS_PINID='VSS588';
NODE_NAME     U1 BV18
 '@S9S_MB_2U_LIB.S9S_MB_2U(SCH_1):PAGE71_I8@PURE_QUANTA.SOCKET4677_AZIF0045P001C01CS(CHIPS)':
 'VSS589': CDS_PINID='VSS589';
NODE_NAME     U1 BV2
 '@S9S_MB_2U_LIB.S9S_MB_2U(SCH_1):PAGE71_I8@PURE_QUANTA.SOCKET4677_AZIF0045P001C01CS(CHIPS)':
 'VSS590': CDS_PINID='VSS590';
NODE_NAME     U1 BV20
 '@S9S_MB_2U_LIB.S9S_MB_2U(SCH_1):PAGE71_I8@PURE_QUANTA.SOCKET4677_AZIF0045P001C01CS(CHIPS)':
 'VSS591': CDS_PINID='VSS591';
NODE_NAME     U1 BV4
 '@S9S_MB_2U_LIB.S9S_MB_2U(SCH_1):PAGE71_I8@PURE_QUANTA.SOCKET4677_AZIF0045P001C01CS(CHIPS)':
 'VSS592': CDS_PINID='VSS592';
NODE_NAME     U1 BV6
 '@S9S_MB_2U_LIB.S9S_MB_2U(SCH_1):PAGE71_I8@PURE_QUANTA.SOCKET4677_AZIF0045P001C01CS(CHIPS)':
 'VSS593': CDS_PINID='VSS593';
NODE_NAME     U1 BV8
 '@S9S_MB_2U_LIB.S9S_MB_2U(SCH_1):PAGE71_I8@PURE_QUANTA.SOCKET4677_AZIF0045P001C01CS(CHIPS)':
 'VSS594': CDS_PINID='VSS594';
NODE_NAME     U1 BW13
 '@S9S_MB_2U_LIB.S9S_MB_2U(SCH_1):PAGE71_I8@PURE_QUANTA.SOCKET4677_AZIF0045P001C01CS(CHIPS)':
 'VSS596': CDS_PINID='VSS596';
NODE_NAME     U1 BW17
 '@S9S_MB_2U_LIB.S9S_MB_2U(SCH_1):PAGE71_I8@PURE_QUANTA.SOCKET4677_AZIF0045P001C01CS(CHIPS)':
 'VSS597': CDS_PINID='VSS597';
NODE_NAME     U1 BW27
 '@S9S_MB_2U_LIB.S9S_MB_2U(SCH_1):PAGE71_I8@PURE_QUANTA.SOCKET4677_AZIF0045P001C01CS(CHIPS)':
 'VSS598': CDS_PINID='VSS598';
NODE_NAME     U1 BW29
 '@S9S_MB_2U_LIB.S9S_MB_2U(SCH_1):PAGE71_I8@PURE_QUANTA.SOCKET4677_AZIF0045P001C01CS(CHIPS)':
 'VSS599': CDS_PINID='VSS599';
NODE_NAME     U1 BW3
 '@S9S_MB_2U_LIB.S9S_MB_2U(SCH_1):PAGE71_I8@PURE_QUANTA.SOCKET4677_AZIF0045P001C01CS(CHIPS)':
 'VSS600': CDS_PINID='VSS600';
NODE_NAME     U1 BW31
 '@S9S_MB_2U_LIB.S9S_MB_2U(SCH_1):PAGE71_I8@PURE_QUANTA.SOCKET4677_AZIF0045P001C01CS(CHIPS)':
 'VSS601': CDS_PINID='VSS601';
NODE_NAME     U1 BW5
 '@S9S_MB_2U_LIB.S9S_MB_2U(SCH_1):PAGE71_I8@PURE_QUANTA.SOCKET4677_AZIF0045P001C01CS(CHIPS)':
 'VSS602': CDS_PINID='VSS602';
NODE_NAME     U1 BW9
 '@S9S_MB_2U_LIB.S9S_MB_2U(SCH_1):PAGE71_I8@PURE_QUANTA.SOCKET4677_AZIF0045P001C01CS(CHIPS)':
 'VSS603': CDS_PINID='VSS603';
NODE_NAME     U1 BY12
 '@S9S_MB_2U_LIB.S9S_MB_2U(SCH_1):PAGE71_I8@PURE_QUANTA.SOCKET4677_AZIF0045P001C01CS(CHIPS)':
 'VSS604': CDS_PINID='VSS604';
NODE_NAME     U1 BY16
 '@S9S_MB_2U_LIB.S9S_MB_2U(SCH_1):PAGE71_I8@PURE_QUANTA.SOCKET4677_AZIF0045P001C01CS(CHIPS)':
 'VSS605': CDS_PINID='VSS605';
NODE_NAME     U1 BY20
 '@S9S_MB_2U_LIB.S9S_MB_2U(SCH_1):PAGE71_I8@PURE_QUANTA.SOCKET4677_AZIF0045P001C01CS(CHIPS)':
 'VSS606': CDS_PINID='VSS606';
NODE_NAME     U1 BY4
 '@S9S_MB_2U_LIB.S9S_MB_2U(SCH_1):PAGE71_I8@PURE_QUANTA.SOCKET4677_AZIF0045P001C01CS(CHIPS)':
 'VSS607': CDS_PINID='VSS607';
NODE_NAME     U1 BY8
 '@S9S_MB_2U_LIB.S9S_MB_2U(SCH_1):PAGE71_I8@PURE_QUANTA.SOCKET4677_AZIF0045P001C01CS(CHIPS)':
 'VSS608': CDS_PINID='VSS608';
NODE_NAME     U1 CA3
 '@S9S_MB_2U_LIB.S9S_MB_2U(SCH_1):PAGE71_I8@PURE_QUANTA.SOCKET4677_AZIF0045P001C01CS(CHIPS)':
 'VSS620': CDS_PINID='VSS620';
NODE_NAME     U1 CA31
 '@S9S_MB_2U_LIB.S9S_MB_2U(SCH_1):PAGE71_I8@PURE_QUANTA.SOCKET4677_AZIF0045P001C01CS(CHIPS)':
 'VSS621': CDS_PINID='VSS621';
NODE_NAME     U1 CB12
 '@S9S_MB_2U_LIB.S9S_MB_2U(SCH_1):PAGE71_I8@PURE_QUANTA.SOCKET4677_AZIF0045P001C01CS(CHIPS)':
 'VSS622': CDS_PINID='VSS622';
NODE_NAME     U1 CB16
 '@S9S_MB_2U_LIB.S9S_MB_2U(SCH_1):PAGE71_I8@PURE_QUANTA.SOCKET4677_AZIF0045P001C01CS(CHIPS)':
 'VSS623': CDS_PINID='VSS623';
NODE_NAME     U1 CB20
 '@S9S_MB_2U_LIB.S9S_MB_2U(SCH_1):PAGE71_I8@PURE_QUANTA.SOCKET4677_AZIF0045P001C01CS(CHIPS)':
 'VSS624': CDS_PINID='VSS624';
NODE_NAME     U1 CB22
 '@S9S_MB_2U_LIB.S9S_MB_2U(SCH_1):PAGE71_I8@PURE_QUANTA.SOCKET4677_AZIF0045P001C01CS(CHIPS)':
 'VSS625': CDS_PINID='VSS625';
NODE_NAME     U1 CB24
 '@S9S_MB_2U_LIB.S9S_MB_2U(SCH_1):PAGE71_I8@PURE_QUANTA.SOCKET4677_AZIF0045P001C01CS(CHIPS)':
 'VSS626': CDS_PINID='VSS626';
NODE_NAME     U1 CB26
 '@S9S_MB_2U_LIB.S9S_MB_2U(SCH_1):PAGE71_I8@PURE_QUANTA.SOCKET4677_AZIF0045P001C01CS(CHIPS)':
 'VSS627': CDS_PINID='VSS627';
NODE_NAME     U1 CB28
 '@S9S_MB_2U_LIB.S9S_MB_2U(SCH_1):PAGE71_I8@PURE_QUANTA.SOCKET4677_AZIF0045P001C01CS(CHIPS)':
 'VSS628': CDS_PINID='VSS628';
NODE_NAME     U1 CB32
 '@S9S_MB_2U_LIB.S9S_MB_2U(SCH_1):PAGE71_I8@PURE_QUANTA.SOCKET4677_AZIF0045P001C01CS(CHIPS)':
 'VSS629': CDS_PINID='VSS629';
NODE_NAME     U1 CB34
 '@S9S_MB_2U_LIB.S9S_MB_2U(SCH_1):PAGE71_I8@PURE_QUANTA.SOCKET4677_AZIF0045P001C01CS(CHIPS)':
 'VSS630': CDS_PINID='VSS630';
NODE_NAME     U1 CB36
 '@S9S_MB_2U_LIB.S9S_MB_2U(SCH_1):PAGE71_I8@PURE_QUANTA.SOCKET4677_AZIF0045P001C01CS(CHIPS)':
 'VSS631': CDS_PINID='VSS631';
NODE_NAME     U1 CB38
 '@S9S_MB_2U_LIB.S9S_MB_2U(SCH_1):PAGE71_I8@PURE_QUANTA.SOCKET4677_AZIF0045P001C01CS(CHIPS)':
 'VSS632': CDS_PINID='VSS632';
NODE_NAME     U1 CB4
 '@S9S_MB_2U_LIB.S9S_MB_2U(SCH_1):PAGE71_I8@PURE_QUANTA.SOCKET4677_AZIF0045P001C01CS(CHIPS)':
 'VSS633': CDS_PINID='VSS633';
NODE_NAME     U1 CB40
 '@S9S_MB_2U_LIB.S9S_MB_2U(SCH_1):PAGE71_I8@PURE_QUANTA.SOCKET4677_AZIF0045P001C01CS(CHIPS)':
 'VSS634': CDS_PINID='VSS634';
NODE_NAME     U1 CB42
 '@S9S_MB_2U_LIB.S9S_MB_2U(SCH_1):PAGE71_I8@PURE_QUANTA.SOCKET4677_AZIF0045P001C01CS(CHIPS)':
 'VSS635': CDS_PINID='VSS635';
NODE_NAME     U1 CB44
 '@S9S_MB_2U_LIB.S9S_MB_2U(SCH_1):PAGE71_I8@PURE_QUANTA.SOCKET4677_AZIF0045P001C01CS(CHIPS)':
 'VSS636': CDS_PINID='VSS636';
NODE_NAME     U1 CB47
 '@S9S_MB_2U_LIB.S9S_MB_2U(SCH_1):PAGE71_I8@PURE_QUANTA.SOCKET4677_AZIF0045P001C01CS(CHIPS)':
 'VSS637': CDS_PINID='VSS637';
NODE_NAME     U1 CB49
 '@S9S_MB_2U_LIB.S9S_MB_2U(SCH_1):PAGE71_I8@PURE_QUANTA.SOCKET4677_AZIF0045P001C01CS(CHIPS)':
 'VSS638': CDS_PINID='VSS638';
NODE_NAME     U1 CB51
 '@S9S_MB_2U_LIB.S9S_MB_2U(SCH_1):PAGE71_I8@PURE_QUANTA.SOCKET4677_AZIF0045P001C01CS(CHIPS)':
 'VSS639': CDS_PINID='VSS639';
NODE_NAME     U1 CB53
 '@S9S_MB_2U_LIB.S9S_MB_2U(SCH_1):PAGE71_I8@PURE_QUANTA.SOCKET4677_AZIF0045P001C01CS(CHIPS)':
 'VSS640': CDS_PINID='VSS640';
NODE_NAME     U1 CB55
 '@S9S_MB_2U_LIB.S9S_MB_2U(SCH_1):PAGE71_I8@PURE_QUANTA.SOCKET4677_AZIF0045P001C01CS(CHIPS)':
 'VSS641': CDS_PINID='VSS641';
NODE_NAME     U1 CB57
 '@S9S_MB_2U_LIB.S9S_MB_2U(SCH_1):PAGE71_I8@PURE_QUANTA.SOCKET4677_AZIF0045P001C01CS(CHIPS)':
 'VSS642': CDS_PINID='VSS642';
NODE_NAME     U1 CB59
 '@S9S_MB_2U_LIB.S9S_MB_2U(SCH_1):PAGE71_I8@PURE_QUANTA.SOCKET4677_AZIF0045P001C01CS(CHIPS)':
 'VSS643': CDS_PINID='VSS643';
NODE_NAME     U1 CB63
 '@S9S_MB_2U_LIB.S9S_MB_2U(SCH_1):PAGE71_I8@PURE_QUANTA.SOCKET4677_AZIF0045P001C01CS(CHIPS)':
 'VSS644': CDS_PINID='VSS644';
NODE_NAME     U1 CB65
 '@S9S_MB_2U_LIB.S9S_MB_2U(SCH_1):PAGE71_I8@PURE_QUANTA.SOCKET4677_AZIF0045P001C01CS(CHIPS)':
 'VSS645': CDS_PINID='VSS645';
NODE_NAME     U1 CB67
 '@S9S_MB_2U_LIB.S9S_MB_2U(SCH_1):PAGE71_I8@PURE_QUANTA.SOCKET4677_AZIF0045P001C01CS(CHIPS)':
 'VSS646': CDS_PINID='VSS646';
NODE_NAME     U1 CB69
 '@S9S_MB_2U_LIB.S9S_MB_2U(SCH_1):PAGE71_I8@PURE_QUANTA.SOCKET4677_AZIF0045P001C01CS(CHIPS)':
 'VSS647': CDS_PINID='VSS647';
NODE_NAME     U1 CB71
 '@S9S_MB_2U_LIB.S9S_MB_2U(SCH_1):PAGE71_I8@PURE_QUANTA.SOCKET4677_AZIF0045P001C01CS(CHIPS)':
 'VSS648': CDS_PINID='VSS648';
NODE_NAME     U1 CB73
 '@S9S_MB_2U_LIB.S9S_MB_2U(SCH_1):PAGE71_I8@PURE_QUANTA.SOCKET4677_AZIF0045P001C01CS(CHIPS)':
 'VSS649': CDS_PINID='VSS649';
NODE_NAME     U1 CB79
 '@S9S_MB_2U_LIB.S9S_MB_2U(SCH_1):PAGE71_I8@PURE_QUANTA.SOCKET4677_AZIF0045P001C01CS(CHIPS)':
 'VSS650': CDS_PINID='VSS650';
NODE_NAME     U1 CB8
 '@S9S_MB_2U_LIB.S9S_MB_2U(SCH_1):PAGE71_I8@PURE_QUANTA.SOCKET4677_AZIF0045P001C01CS(CHIPS)':
 'VSS651': CDS_PINID='VSS651';
NODE_NAME     U1 CB81
 '@S9S_MB_2U_LIB.S9S_MB_2U(SCH_1):PAGE71_I8@PURE_QUANTA.SOCKET4677_AZIF0045P001C01CS(CHIPS)':
 'VSS652': CDS_PINID='VSS652';
NODE_NAME     U1 CB83
 '@S9S_MB_2U_LIB.S9S_MB_2U(SCH_1):PAGE71_I8@PURE_QUANTA.SOCKET4677_AZIF0045P001C01CS(CHIPS)':
 'VSS653': CDS_PINID='VSS653';
NODE_NAME     U1 CB85
 '@S9S_MB_2U_LIB.S9S_MB_2U(SCH_1):PAGE71_I8@PURE_QUANTA.SOCKET4677_AZIF0045P001C01CS(CHIPS)':
 'VSS654': CDS_PINID='VSS654';
NODE_NAME     U1 CB87
 '@S9S_MB_2U_LIB.S9S_MB_2U(SCH_1):PAGE71_I8@PURE_QUANTA.SOCKET4677_AZIF0045P001C01CS(CHIPS)':
 'VSS655': CDS_PINID='VSS655';
NODE_NAME     U1 CB89
 '@S9S_MB_2U_LIB.S9S_MB_2U(SCH_1):PAGE71_I8@PURE_QUANTA.SOCKET4677_AZIF0045P001C01CS(CHIPS)':
 'VSS656': CDS_PINID='VSS656';
NODE_NAME     U1 CC13
 '@S9S_MB_2U_LIB.S9S_MB_2U(SCH_1):PAGE71_I8@PURE_QUANTA.SOCKET4677_AZIF0045P001C01CS(CHIPS)':
 'VSS660': CDS_PINID='VSS660';
NODE_NAME     U1 CC17
 '@S9S_MB_2U_LIB.S9S_MB_2U(SCH_1):PAGE71_I8@PURE_QUANTA.SOCKET4677_AZIF0045P001C01CS(CHIPS)':
 'VSS661': CDS_PINID='VSS661';
NODE_NAME     U1 CC31
 '@S9S_MB_2U_LIB.S9S_MB_2U(SCH_1):PAGE71_I8@PURE_QUANTA.SOCKET4677_AZIF0045P001C01CS(CHIPS)':
 'VSS664': CDS_PINID='VSS664';
NODE_NAME     U1 CC5
 '@S9S_MB_2U_LIB.S9S_MB_2U(SCH_1):PAGE71_I8@PURE_QUANTA.SOCKET4677_AZIF0045P001C01CS(CHIPS)':
 'VSS665': CDS_PINID='VSS665';
NODE_NAME     U1 CC62
 '@S9S_MB_2U_LIB.S9S_MB_2U(SCH_1):PAGE71_I8@PURE_QUANTA.SOCKET4677_AZIF0045P001C01CS(CHIPS)':
 'VSS666': CDS_PINID='VSS666';
NODE_NAME     U1 CC70
 '@S9S_MB_2U_LIB.S9S_MB_2U(SCH_1):PAGE71_I8@PURE_QUANTA.SOCKET4677_AZIF0045P001C01CS(CHIPS)':
 'VSS667': CDS_PINID='VSS667';
NODE_NAME     U1 CC72
 '@S9S_MB_2U_LIB.S9S_MB_2U(SCH_1):PAGE71_I8@PURE_QUANTA.SOCKET4677_AZIF0045P001C01CS(CHIPS)':
 'VSS668': CDS_PINID='VSS668';
NODE_NAME     U1 CC74
 '@S9S_MB_2U_LIB.S9S_MB_2U(SCH_1):PAGE71_I8@PURE_QUANTA.SOCKET4677_AZIF0045P001C01CS(CHIPS)':
 'VSS669': CDS_PINID='VSS669';
NODE_NAME     U1 CC9
 '@S9S_MB_2U_LIB.S9S_MB_2U(SCH_1):PAGE71_I8@PURE_QUANTA.SOCKET4677_AZIF0045P001C01CS(CHIPS)':
 'VSS670': CDS_PINID='VSS670';
NODE_NAME     U1 CD12
 '@S9S_MB_2U_LIB.S9S_MB_2U(SCH_1):PAGE71_I8@PURE_QUANTA.SOCKET4677_AZIF0045P001C01CS(CHIPS)':
 'VSS671': CDS_PINID='VSS671';
NODE_NAME     U1 CD16
 '@S9S_MB_2U_LIB.S9S_MB_2U(SCH_1):PAGE71_I8@PURE_QUANTA.SOCKET4677_AZIF0045P001C01CS(CHIPS)':
 'VSS672': CDS_PINID='VSS672';
NODE_NAME     U1 CD20
 '@S9S_MB_2U_LIB.S9S_MB_2U(SCH_1):PAGE71_I8@PURE_QUANTA.SOCKET4677_AZIF0045P001C01CS(CHIPS)':
 'VSS673': CDS_PINID='VSS673';
NODE_NAME     U1 CD4
 '@S9S_MB_2U_LIB.S9S_MB_2U(SCH_1):PAGE71_I8@PURE_QUANTA.SOCKET4677_AZIF0045P001C01CS(CHIPS)':
 'VSS674': CDS_PINID='VSS674';
NODE_NAME     U1 CD61
 '@S9S_MB_2U_LIB.S9S_MB_2U(SCH_1):PAGE71_I8@PURE_QUANTA.SOCKET4677_AZIF0045P001C01CS(CHIPS)':
 'VSS675': CDS_PINID='VSS675';
NODE_NAME     U1 CD75
 '@S9S_MB_2U_LIB.S9S_MB_2U(SCH_1):PAGE71_I8@PURE_QUANTA.SOCKET4677_AZIF0045P001C01CS(CHIPS)':
 'VSS676': CDS_PINID='VSS676';
NODE_NAME     U1 CD77
 '@S9S_MB_2U_LIB.S9S_MB_2U(SCH_1):PAGE71_I8@PURE_QUANTA.SOCKET4677_AZIF0045P001C01CS(CHIPS)':
 'VSS677': CDS_PINID='VSS677';
NODE_NAME     U1 CD8
 '@S9S_MB_2U_LIB.S9S_MB_2U(SCH_1):PAGE71_I8@PURE_QUANTA.SOCKET4677_AZIF0045P001C01CS(CHIPS)':
 'VSS678': CDS_PINID='VSS678';
NODE_NAME     U1 CE3
 '@S9S_MB_2U_LIB.S9S_MB_2U(SCH_1):PAGE71_I8@PURE_QUANTA.SOCKET4677_AZIF0045P001C01CS(CHIPS)':
 'VSS680': CDS_PINID='VSS680';
NODE_NAME     U1 CE60
 '@S9S_MB_2U_LIB.S9S_MB_2U(SCH_1):PAGE71_I8@PURE_QUANTA.SOCKET4677_AZIF0045P001C01CS(CHIPS)':
 'VSS681': CDS_PINID='VSS681';
NODE_NAME     U1 CE66
 '@S9S_MB_2U_LIB.S9S_MB_2U(SCH_1):PAGE71_I8@PURE_QUANTA.SOCKET4677_AZIF0045P001C01CS(CHIPS)':
 'VSS682': CDS_PINID='VSS682';
NODE_NAME     U1 CE72
 '@S9S_MB_2U_LIB.S9S_MB_2U(SCH_1):PAGE71_I8@PURE_QUANTA.SOCKET4677_AZIF0045P001C01CS(CHIPS)':
 'VSS683': CDS_PINID='VSS683';
NODE_NAME     U1 CE76
 '@S9S_MB_2U_LIB.S9S_MB_2U(SCH_1):PAGE71_I8@PURE_QUANTA.SOCKET4677_AZIF0045P001C01CS(CHIPS)':
 'VSS684': CDS_PINID='VSS684';
NODE_NAME     U1 CE78
 '@S9S_MB_2U_LIB.S9S_MB_2U(SCH_1):PAGE71_I8@PURE_QUANTA.SOCKET4677_AZIF0045P001C01CS(CHIPS)':
 'VSS685': CDS_PINID='VSS685';
NODE_NAME     U1 CF12
 '@S9S_MB_2U_LIB.S9S_MB_2U(SCH_1):PAGE71_I8@PURE_QUANTA.SOCKET4677_AZIF0045P001C01CS(CHIPS)':
 'VSS686': CDS_PINID='VSS686';
NODE_NAME     U1 CF16
 '@S9S_MB_2U_LIB.S9S_MB_2U(SCH_1):PAGE71_I8@PURE_QUANTA.SOCKET4677_AZIF0045P001C01CS(CHIPS)':
 'VSS687': CDS_PINID='VSS687';
NODE_NAME     U1 CF20
 '@S9S_MB_2U_LIB.S9S_MB_2U(SCH_1):PAGE71_I8@PURE_QUANTA.SOCKET4677_AZIF0045P001C01CS(CHIPS)':
 'VSS688': CDS_PINID='VSS688';
NODE_NAME     U1 CF4
 '@S9S_MB_2U_LIB.S9S_MB_2U(SCH_1):PAGE71_I8@PURE_QUANTA.SOCKET4677_AZIF0045P001C01CS(CHIPS)':
 'VSS689': CDS_PINID='VSS689';
NODE_NAME     U1 CF69
 '@S9S_MB_2U_LIB.S9S_MB_2U(SCH_1):PAGE71_I8@PURE_QUANTA.SOCKET4677_AZIF0045P001C01CS(CHIPS)':
 'VSS691': CDS_PINID='VSS691';
NODE_NAME     U1 CF71
 '@S9S_MB_2U_LIB.S9S_MB_2U(SCH_1):PAGE71_I8@PURE_QUANTA.SOCKET4677_AZIF0045P001C01CS(CHIPS)':
 'VSS692': CDS_PINID='VSS692';
NODE_NAME     U1 CF8
 '@S9S_MB_2U_LIB.S9S_MB_2U(SCH_1):PAGE71_I8@PURE_QUANTA.SOCKET4677_AZIF0045P001C01CS(CHIPS)':
 'VSS693': CDS_PINID='VSS693';
NODE_NAME     U1 CG1
 '@S9S_MB_2U_LIB.S9S_MB_2U(SCH_1):PAGE71_I8@PURE_QUANTA.SOCKET4677_AZIF0045P001C01CS(CHIPS)':
 'VSS694': CDS_PINID='VSS694';
NODE_NAME     U1 CG13
 '@S9S_MB_2U_LIB.S9S_MB_2U(SCH_1):PAGE71_I8@PURE_QUANTA.SOCKET4677_AZIF0045P001C01CS(CHIPS)':
 'VSS695': CDS_PINID='VSS695';
NODE_NAME     U1 CG17
 '@S9S_MB_2U_LIB.S9S_MB_2U(SCH_1):PAGE71_I8@PURE_QUANTA.SOCKET4677_AZIF0045P001C01CS(CHIPS)':
 'VSS696': CDS_PINID='VSS696';
NODE_NAME     U1 CG21
 '@S9S_MB_2U_LIB.S9S_MB_2U(SCH_1):PAGE71_I8@PURE_QUANTA.SOCKET4677_AZIF0045P001C01CS(CHIPS)':
 'VSS697': CDS_PINID='VSS697';
NODE_NAME     U1 CG23
 '@S9S_MB_2U_LIB.S9S_MB_2U(SCH_1):PAGE71_I8@PURE_QUANTA.SOCKET4677_AZIF0045P001C01CS(CHIPS)':
 'VSS698': CDS_PINID='VSS698';
NODE_NAME     U1 CG25
 '@S9S_MB_2U_LIB.S9S_MB_2U(SCH_1):PAGE71_I8@PURE_QUANTA.SOCKET4677_AZIF0045P001C01CS(CHIPS)':
 'VSS701': CDS_PINID='VSS701';
NODE_NAME     U1 CG5
 '@S9S_MB_2U_LIB.S9S_MB_2U(SCH_1):PAGE71_I8@PURE_QUANTA.SOCKET4677_AZIF0045P001C01CS(CHIPS)':
 'VSS703': CDS_PINID='VSS703';
NODE_NAME     U1 CG62
 '@S9S_MB_2U_LIB.S9S_MB_2U(SCH_1):PAGE71_I8@PURE_QUANTA.SOCKET4677_AZIF0045P001C01CS(CHIPS)':
 'VSS704': CDS_PINID='VSS704';
NODE_NAME     U1 CG64
 '@S9S_MB_2U_LIB.S9S_MB_2U(SCH_1):PAGE71_I8@PURE_QUANTA.SOCKET4677_AZIF0045P001C01CS(CHIPS)':
 'VSS706': CDS_PINID='VSS706';
NODE_NAME     U1 CG70
 '@S9S_MB_2U_LIB.S9S_MB_2U(SCH_1):PAGE71_I8@PURE_QUANTA.SOCKET4677_AZIF0045P001C01CS(CHIPS)':
 'VSS707': CDS_PINID='VSS707';
NODE_NAME     U1 CG72
 '@S9S_MB_2U_LIB.S9S_MB_2U(SCH_1):PAGE71_I8@PURE_QUANTA.SOCKET4677_AZIF0045P001C01CS(CHIPS)':
 'VSS708': CDS_PINID='VSS708';
NODE_NAME     U1 CG74
 '@S9S_MB_2U_LIB.S9S_MB_2U(SCH_1):PAGE71_I8@PURE_QUANTA.SOCKET4677_AZIF0045P001C01CS(CHIPS)':
 'VSS710': CDS_PINID='VSS710';
NODE_NAME     U1 CG78
 '@S9S_MB_2U_LIB.S9S_MB_2U(SCH_1):PAGE71_I8@PURE_QUANTA.SOCKET4677_AZIF0045P001C01CS(CHIPS)':
 'VSS713': CDS_PINID='VSS713';
NODE_NAME     U1 CG9
 '@S9S_MB_2U_LIB.S9S_MB_2U(SCH_1):PAGE71_I8@PURE_QUANTA.SOCKET4677_AZIF0045P001C01CS(CHIPS)':
 'VSS716': CDS_PINID='VSS716';
NODE_NAME     U1 CH12
 '@S9S_MB_2U_LIB.S9S_MB_2U(SCH_1):PAGE71_I8@PURE_QUANTA.SOCKET4677_AZIF0045P001C01CS(CHIPS)':
 'VSS718': CDS_PINID='VSS718';
NODE_NAME     U1 CH16
 '@S9S_MB_2U_LIB.S9S_MB_2U(SCH_1):PAGE71_I8@PURE_QUANTA.SOCKET4677_AZIF0045P001C01CS(CHIPS)':
 'VSS720': CDS_PINID='VSS720';
NODE_NAME     U1 CH20
 '@S9S_MB_2U_LIB.S9S_MB_2U(SCH_1):PAGE71_I8@PURE_QUANTA.SOCKET4677_AZIF0045P001C01CS(CHIPS)':
 'VSS721': CDS_PINID='VSS721';
NODE_NAME     U1 CH4
 '@S9S_MB_2U_LIB.S9S_MB_2U(SCH_1):PAGE71_I8@PURE_QUANTA.SOCKET4677_AZIF0045P001C01CS(CHIPS)':
 'VSS722': CDS_PINID='VSS722';
NODE_NAME     U1 CH67
 '@S9S_MB_2U_LIB.S9S_MB_2U(SCH_1):PAGE71_I8@PURE_QUANTA.SOCKET4677_AZIF0045P001C01CS(CHIPS)':
 'VSS727': CDS_PINID='VSS727';
NODE_NAME     U1 CH73
 '@S9S_MB_2U_LIB.S9S_MB_2U(SCH_1):PAGE71_I8@PURE_QUANTA.SOCKET4677_AZIF0045P001C01CS(CHIPS)':
 'VSS728': CDS_PINID='VSS728';
NODE_NAME     U1 CH79
 '@S9S_MB_2U_LIB.S9S_MB_2U(SCH_1):PAGE71_I8@PURE_QUANTA.SOCKET4677_AZIF0045P001C01CS(CHIPS)':
 'VSS729': CDS_PINID='VSS729';
NODE_NAME     U1 CH8
 '@S9S_MB_2U_LIB.S9S_MB_2U(SCH_1):PAGE71_I8@PURE_QUANTA.SOCKET4677_AZIF0045P001C01CS(CHIPS)':
 'VSS730': CDS_PINID='VSS730';
NODE_NAME     U1 CH83
 '@S9S_MB_2U_LIB.S9S_MB_2U(SCH_1):PAGE71_I8@PURE_QUANTA.SOCKET4677_AZIF0045P001C01CS(CHIPS)':
 'VSS731': CDS_PINID='VSS731';
NODE_NAME     U1 CH85
 '@S9S_MB_2U_LIB.S9S_MB_2U(SCH_1):PAGE71_I8@PURE_QUANTA.SOCKET4677_AZIF0045P001C01CS(CHIPS)':
 'VSS732': CDS_PINID='VSS732';
NODE_NAME     U1 CH87
 '@S9S_MB_2U_LIB.S9S_MB_2U(SCH_1):PAGE71_I8@PURE_QUANTA.SOCKET4677_AZIF0045P001C01CS(CHIPS)':
 'VSS733': CDS_PINID='VSS733';
NODE_NAME     U1 CH89
 '@S9S_MB_2U_LIB.S9S_MB_2U(SCH_1):PAGE71_I8@PURE_QUANTA.SOCKET4677_AZIF0045P001C01CS(CHIPS)':
 'VSS734': CDS_PINID='VSS734';
NODE_NAME     U1 CJ60
 '@S9S_MB_2U_LIB.S9S_MB_2U(SCH_1):PAGE71_I8@PURE_QUANTA.SOCKET4677_AZIF0045P001C01CS(CHIPS)':
 'VSS736': CDS_PINID='VSS736';
NODE_NAME     U1 CJ80
 '@S9S_MB_2U_LIB.S9S_MB_2U(SCH_1):PAGE71_I8@PURE_QUANTA.SOCKET4677_AZIF0045P001C01CS(CHIPS)':
 'VSS737': CDS_PINID='VSS737';
NODE_NAME     U1 CK12
 '@S9S_MB_2U_LIB.S9S_MB_2U(SCH_1):PAGE71_I8@PURE_QUANTA.SOCKET4677_AZIF0045P001C01CS(CHIPS)':
 'VSS740': CDS_PINID='VSS740';
NODE_NAME     U1 CK16
 '@S9S_MB_2U_LIB.S9S_MB_2U(SCH_1):PAGE71_I8@PURE_QUANTA.SOCKET4677_AZIF0045P001C01CS(CHIPS)':
 'VSS741': CDS_PINID='VSS741';
NODE_NAME     U1 CK20
 '@S9S_MB_2U_LIB.S9S_MB_2U(SCH_1):PAGE71_I8@PURE_QUANTA.SOCKET4677_AZIF0045P001C01CS(CHIPS)':
 'VSS742': CDS_PINID='VSS742';
NODE_NAME     U1 CK26
 '@S9S_MB_2U_LIB.S9S_MB_2U(SCH_1):PAGE71_I8@PURE_QUANTA.SOCKET4677_AZIF0045P001C01CS(CHIPS)':
 'VSS743': CDS_PINID='VSS743';
NODE_NAME     U1 CK8
 '@S9S_MB_2U_LIB.S9S_MB_2U(SCH_1):PAGE71_I8@PURE_QUANTA.SOCKET4677_AZIF0045P001C01CS(CHIPS)':
 'VSS746': CDS_PINID='VSS746';
NODE_NAME     U1 BR5
 '@S9S_MB_2U_LIB.S9S_MB_2U(SCH_1):PAGE72_I2@PURE_QUANTA.SOCKET4677_AZIF0045P001C01CS(CHIPS)':
 'VSS0': CDS_PINID='VSS0';
NODE_NAME     U1 AW21
 '@S9S_MB_2U_LIB.S9S_MB_2U(SCH_1):PAGE72_I2@PURE_QUANTA.SOCKET4677_AZIF0045P001C01CS(CHIPS)':
 'VSS356': CDS_PINID='VSS356';
NODE_NAME     U1 AW23
 '@S9S_MB_2U_LIB.S9S_MB_2U(SCH_1):PAGE72_I2@PURE_QUANTA.SOCKET4677_AZIF0045P001C01CS(CHIPS)':
 'VSS357': CDS_PINID='VSS357';
NODE_NAME     U1 AW25
 '@S9S_MB_2U_LIB.S9S_MB_2U(SCH_1):PAGE72_I2@PURE_QUANTA.SOCKET4677_AZIF0045P001C01CS(CHIPS)':
 'VSS358': CDS_PINID='VSS358';
NODE_NAME     U1 AW62
 '@S9S_MB_2U_LIB.S9S_MB_2U(SCH_1):PAGE72_I2@PURE_QUANTA.SOCKET4677_AZIF0045P001C01CS(CHIPS)':
 'VSS360': CDS_PINID='VSS360';
NODE_NAME     U1 AW66
 '@S9S_MB_2U_LIB.S9S_MB_2U(SCH_1):PAGE72_I2@PURE_QUANTA.SOCKET4677_AZIF0045P001C01CS(CHIPS)':
 'VSS361': CDS_PINID='VSS361';
NODE_NAME     U1 AW68
 '@S9S_MB_2U_LIB.S9S_MB_2U(SCH_1):PAGE72_I2@PURE_QUANTA.SOCKET4677_AZIF0045P001C01CS(CHIPS)':
 'VSS362': CDS_PINID='VSS362';
NODE_NAME     U1 AW72
 '@S9S_MB_2U_LIB.S9S_MB_2U(SCH_1):PAGE72_I2@PURE_QUANTA.SOCKET4677_AZIF0045P001C01CS(CHIPS)':
 'VSS363': CDS_PINID='VSS363';
NODE_NAME     U1 AW80
 '@S9S_MB_2U_LIB.S9S_MB_2U(SCH_1):PAGE72_I2@PURE_QUANTA.SOCKET4677_AZIF0045P001C01CS(CHIPS)':
 'VSS364': CDS_PINID='VSS364';
NODE_NAME     U1 AW82
 '@S9S_MB_2U_LIB.S9S_MB_2U(SCH_1):PAGE72_I2@PURE_QUANTA.SOCKET4677_AZIF0045P001C01CS(CHIPS)':
 'VSS365': CDS_PINID='VSS365';
NODE_NAME     U1 AW84
 '@S9S_MB_2U_LIB.S9S_MB_2U(SCH_1):PAGE72_I2@PURE_QUANTA.SOCKET4677_AZIF0045P001C01CS(CHIPS)':
 'VSS366': CDS_PINID='VSS366';
NODE_NAME     U1 AW88
 '@S9S_MB_2U_LIB.S9S_MB_2U(SCH_1):PAGE72_I2@PURE_QUANTA.SOCKET4677_AZIF0045P001C01CS(CHIPS)':
 'VSS367': CDS_PINID='VSS367';
NODE_NAME     U1 AY12
 '@S9S_MB_2U_LIB.S9S_MB_2U(SCH_1):PAGE72_I2@PURE_QUANTA.SOCKET4677_AZIF0045P001C01CS(CHIPS)':
 'VSS369': CDS_PINID='VSS369';
NODE_NAME     U1 AY16
 '@S9S_MB_2U_LIB.S9S_MB_2U(SCH_1):PAGE72_I2@PURE_QUANTA.SOCKET4677_AZIF0045P001C01CS(CHIPS)':
 'VSS370': CDS_PINID='VSS370';
NODE_NAME     U1 AY4
 '@S9S_MB_2U_LIB.S9S_MB_2U(SCH_1):PAGE72_I2@PURE_QUANTA.SOCKET4677_AZIF0045P001C01CS(CHIPS)':
 'VSS371': CDS_PINID='VSS371';
NODE_NAME     U1 AY71
 '@S9S_MB_2U_LIB.S9S_MB_2U(SCH_1):PAGE72_I2@PURE_QUANTA.SOCKET4677_AZIF0045P001C01CS(CHIPS)':
 'VSS372': CDS_PINID='VSS372';
NODE_NAME     U1 AY77
 '@S9S_MB_2U_LIB.S9S_MB_2U(SCH_1):PAGE72_I2@PURE_QUANTA.SOCKET4677_AZIF0045P001C01CS(CHIPS)':
 'VSS373': CDS_PINID='VSS373';
NODE_NAME     U1 AY79
 '@S9S_MB_2U_LIB.S9S_MB_2U(SCH_1):PAGE72_I2@PURE_QUANTA.SOCKET4677_AZIF0045P001C01CS(CHIPS)':
 'VSS374': CDS_PINID='VSS374';
NODE_NAME     U1 AY8
 '@S9S_MB_2U_LIB.S9S_MB_2U(SCH_1):PAGE72_I2@PURE_QUANTA.SOCKET4677_AZIF0045P001C01CS(CHIPS)':
 'VSS375': CDS_PINID='VSS375';
NODE_NAME     U1 AY81
 '@S9S_MB_2U_LIB.S9S_MB_2U(SCH_1):PAGE72_I2@PURE_QUANTA.SOCKET4677_AZIF0045P001C01CS(CHIPS)':
 'VSS376': CDS_PINID='VSS376';
NODE_NAME     U1 AY83
 '@S9S_MB_2U_LIB.S9S_MB_2U(SCH_1):PAGE72_I2@PURE_QUANTA.SOCKET4677_AZIF0045P001C01CS(CHIPS)':
 'VSS377': CDS_PINID='VSS377';
NODE_NAME     U1 BA17
 '@S9S_MB_2U_LIB.S9S_MB_2U(SCH_1):PAGE72_I2@PURE_QUANTA.SOCKET4677_AZIF0045P001C01CS(CHIPS)':
 'VSS393': CDS_PINID='VSS393';
NODE_NAME     U1 BA60
 '@S9S_MB_2U_LIB.S9S_MB_2U(SCH_1):PAGE72_I2@PURE_QUANTA.SOCKET4677_AZIF0045P001C01CS(CHIPS)':
 'VSS394': CDS_PINID='VSS394';
NODE_NAME     U1 BA64
 '@S9S_MB_2U_LIB.S9S_MB_2U(SCH_1):PAGE72_I2@PURE_QUANTA.SOCKET4677_AZIF0045P001C01CS(CHIPS)':
 'VSS395': CDS_PINID='VSS395';
NODE_NAME     U1 BA74
 '@S9S_MB_2U_LIB.S9S_MB_2U(SCH_1):PAGE72_I2@PURE_QUANTA.SOCKET4677_AZIF0045P001C01CS(CHIPS)':
 'VSS397': CDS_PINID='VSS397';
NODE_NAME     U1 BA84
 '@S9S_MB_2U_LIB.S9S_MB_2U(SCH_1):PAGE72_I2@PURE_QUANTA.SOCKET4677_AZIF0045P001C01CS(CHIPS)':
 'VSS398': CDS_PINID='VSS398';
NODE_NAME     U1 BA88
 '@S9S_MB_2U_LIB.S9S_MB_2U(SCH_1):PAGE72_I2@PURE_QUANTA.SOCKET4677_AZIF0045P001C01CS(CHIPS)':
 'VSS399': CDS_PINID='VSS399';
NODE_NAME     U1 BB10
 '@S9S_MB_2U_LIB.S9S_MB_2U(SCH_1):PAGE72_I2@PURE_QUANTA.SOCKET4677_AZIF0045P001C01CS(CHIPS)':
 'VSS400': CDS_PINID='VSS400';
NODE_NAME     U1 BB12
 '@S9S_MB_2U_LIB.S9S_MB_2U(SCH_1):PAGE72_I2@PURE_QUANTA.SOCKET4677_AZIF0045P001C01CS(CHIPS)':
 'VSS401': CDS_PINID='VSS401';
NODE_NAME     U1 BB16
 '@S9S_MB_2U_LIB.S9S_MB_2U(SCH_1):PAGE72_I2@PURE_QUANTA.SOCKET4677_AZIF0045P001C01CS(CHIPS)':
 'VSS402': CDS_PINID='VSS402';
NODE_NAME     U1 BB20
 '@S9S_MB_2U_LIB.S9S_MB_2U(SCH_1):PAGE72_I2@PURE_QUANTA.SOCKET4677_AZIF0045P001C01CS(CHIPS)':
 'VSS403': CDS_PINID='VSS403';
NODE_NAME     U1 BB22
 '@S9S_MB_2U_LIB.S9S_MB_2U(SCH_1):PAGE72_I2@PURE_QUANTA.SOCKET4677_AZIF0045P001C01CS(CHIPS)':
 'VSS404': CDS_PINID='VSS404';
NODE_NAME     U1 BB24
 '@S9S_MB_2U_LIB.S9S_MB_2U(SCH_1):PAGE72_I2@PURE_QUANTA.SOCKET4677_AZIF0045P001C01CS(CHIPS)':
 'VSS405': CDS_PINID='VSS405';
NODE_NAME     U1 BB26
 '@S9S_MB_2U_LIB.S9S_MB_2U(SCH_1):PAGE72_I2@PURE_QUANTA.SOCKET4677_AZIF0045P001C01CS(CHIPS)':
 'VSS406': CDS_PINID='VSS406';
NODE_NAME     U1 BB4
 '@S9S_MB_2U_LIB.S9S_MB_2U(SCH_1):PAGE72_I2@PURE_QUANTA.SOCKET4677_AZIF0045P001C01CS(CHIPS)':
 'VSS407': CDS_PINID='VSS407';
NODE_NAME     U1 BB63
 '@S9S_MB_2U_LIB.S9S_MB_2U(SCH_1):PAGE72_I2@PURE_QUANTA.SOCKET4677_AZIF0045P001C01CS(CHIPS)':
 'VSS408': CDS_PINID='VSS408';
NODE_NAME     U1 BB69
 '@S9S_MB_2U_LIB.S9S_MB_2U(SCH_1):PAGE72_I2@PURE_QUANTA.SOCKET4677_AZIF0045P001C01CS(CHIPS)':
 'VSS409': CDS_PINID='VSS409';
NODE_NAME     U1 BB71
 '@S9S_MB_2U_LIB.S9S_MB_2U(SCH_1):PAGE72_I2@PURE_QUANTA.SOCKET4677_AZIF0045P001C01CS(CHIPS)':
 'VSS410': CDS_PINID='VSS410';
NODE_NAME     U1 BB77
 '@S9S_MB_2U_LIB.S9S_MB_2U(SCH_1):PAGE72_I2@PURE_QUANTA.SOCKET4677_AZIF0045P001C01CS(CHIPS)':
 'VSS411': CDS_PINID='VSS411';
NODE_NAME     U1 BB79
 '@S9S_MB_2U_LIB.S9S_MB_2U(SCH_1):PAGE72_I2@PURE_QUANTA.SOCKET4677_AZIF0045P001C01CS(CHIPS)':
 'VSS412': CDS_PINID='VSS412';
NODE_NAME     U1 BB8
 '@S9S_MB_2U_LIB.S9S_MB_2U(SCH_1):PAGE72_I2@PURE_QUANTA.SOCKET4677_AZIF0045P001C01CS(CHIPS)':
 'VSS413': CDS_PINID='VSS413';
NODE_NAME     U1 BB83
 '@S9S_MB_2U_LIB.S9S_MB_2U(SCH_1):PAGE72_I2@PURE_QUANTA.SOCKET4677_AZIF0045P001C01CS(CHIPS)':
 'VSS414': CDS_PINID='VSS414';
NODE_NAME     U1 BB87
 '@S9S_MB_2U_LIB.S9S_MB_2U(SCH_1):PAGE72_I2@PURE_QUANTA.SOCKET4677_AZIF0045P001C01CS(CHIPS)':
 'VSS415': CDS_PINID='VSS415';
NODE_NAME     U1 BB91
 '@S9S_MB_2U_LIB.S9S_MB_2U(SCH_1):PAGE72_I2@PURE_QUANTA.SOCKET4677_AZIF0045P001C01CS(CHIPS)':
 'VSS416': CDS_PINID='VSS416';
NODE_NAME     U1 BC1
 '@S9S_MB_2U_LIB.S9S_MB_2U(SCH_1):PAGE72_I2@PURE_QUANTA.SOCKET4677_AZIF0045P001C01CS(CHIPS)':
 'VSS417': CDS_PINID='VSS417';
NODE_NAME     U1 BC13
 '@S9S_MB_2U_LIB.S9S_MB_2U(SCH_1):PAGE72_I2@PURE_QUANTA.SOCKET4677_AZIF0045P001C01CS(CHIPS)':
 'VSS418': CDS_PINID='VSS418';
NODE_NAME     U1 BC17
 '@S9S_MB_2U_LIB.S9S_MB_2U(SCH_1):PAGE72_I2@PURE_QUANTA.SOCKET4677_AZIF0045P001C01CS(CHIPS)':
 'VSS419': CDS_PINID='VSS419';
NODE_NAME     U1 BC5
 '@S9S_MB_2U_LIB.S9S_MB_2U(SCH_1):PAGE72_I2@PURE_QUANTA.SOCKET4677_AZIF0045P001C01CS(CHIPS)':
 'VSS420': CDS_PINID='VSS420';
NODE_NAME     U1 BC62
 '@S9S_MB_2U_LIB.S9S_MB_2U(SCH_1):PAGE72_I2@PURE_QUANTA.SOCKET4677_AZIF0045P001C01CS(CHIPS)':
 'VSS421': CDS_PINID='VSS421';
NODE_NAME     U1 BC66
 '@S9S_MB_2U_LIB.S9S_MB_2U(SCH_1):PAGE72_I2@PURE_QUANTA.SOCKET4677_AZIF0045P001C01CS(CHIPS)':
 'VSS422': CDS_PINID='VSS422';
NODE_NAME     U1 BC72
 '@S9S_MB_2U_LIB.S9S_MB_2U(SCH_1):PAGE72_I2@PURE_QUANTA.SOCKET4677_AZIF0045P001C01CS(CHIPS)':
 'VSS423': CDS_PINID='VSS423';
NODE_NAME     U1 BC76
 '@S9S_MB_2U_LIB.S9S_MB_2U(SCH_1):PAGE72_I2@PURE_QUANTA.SOCKET4677_AZIF0045P001C01CS(CHIPS)':
 'VSS424': CDS_PINID='VSS424';
NODE_NAME     U1 BC78
 '@S9S_MB_2U_LIB.S9S_MB_2U(SCH_1):PAGE72_I2@PURE_QUANTA.SOCKET4677_AZIF0045P001C01CS(CHIPS)':
 'VSS425': CDS_PINID='VSS425';
NODE_NAME     U1 BC84
 '@S9S_MB_2U_LIB.S9S_MB_2U(SCH_1):PAGE72_I2@PURE_QUANTA.SOCKET4677_AZIF0045P001C01CS(CHIPS)':
 'VSS426': CDS_PINID='VSS426';
NODE_NAME     U1 BC86
 '@S9S_MB_2U_LIB.S9S_MB_2U(SCH_1):PAGE72_I2@PURE_QUANTA.SOCKET4677_AZIF0045P001C01CS(CHIPS)':
 'VSS427': CDS_PINID='VSS427';
NODE_NAME     U1 BC88
 '@S9S_MB_2U_LIB.S9S_MB_2U(SCH_1):PAGE72_I2@PURE_QUANTA.SOCKET4677_AZIF0045P001C01CS(CHIPS)':
 'VSS428': CDS_PINID='VSS428';
NODE_NAME     U1 BC9
 '@S9S_MB_2U_LIB.S9S_MB_2U(SCH_1):PAGE72_I2@PURE_QUANTA.SOCKET4677_AZIF0045P001C01CS(CHIPS)':
 'VSS429': CDS_PINID='VSS429';
NODE_NAME     U1 BD12
 '@S9S_MB_2U_LIB.S9S_MB_2U(SCH_1):PAGE72_I2@PURE_QUANTA.SOCKET4677_AZIF0045P001C01CS(CHIPS)':
 'VSS430': CDS_PINID='VSS430';
NODE_NAME     U1 BD16
 '@S9S_MB_2U_LIB.S9S_MB_2U(SCH_1):PAGE72_I2@PURE_QUANTA.SOCKET4677_AZIF0045P001C01CS(CHIPS)':
 'VSS431': CDS_PINID='VSS431';
NODE_NAME     U1 BD20
 '@S9S_MB_2U_LIB.S9S_MB_2U(SCH_1):PAGE72_I2@PURE_QUANTA.SOCKET4677_AZIF0045P001C01CS(CHIPS)':
 'VSS432': CDS_PINID='VSS432';
NODE_NAME     U1 BD4
 '@S9S_MB_2U_LIB.S9S_MB_2U(SCH_1):PAGE72_I2@PURE_QUANTA.SOCKET4677_AZIF0045P001C01CS(CHIPS)':
 'VSS433': CDS_PINID='VSS433';
NODE_NAME     U1 BD8
 '@S9S_MB_2U_LIB.S9S_MB_2U(SCH_1):PAGE72_I2@PURE_QUANTA.SOCKET4677_AZIF0045P001C01CS(CHIPS)':
 'VSS434': CDS_PINID='VSS434';
NODE_NAME     U1 BD81
 '@S9S_MB_2U_LIB.S9S_MB_2U(SCH_1):PAGE72_I2@PURE_QUANTA.SOCKET4677_AZIF0045P001C01CS(CHIPS)':
 'VSS435': CDS_PINID='VSS435';
NODE_NAME     U1 BD85
 '@S9S_MB_2U_LIB.S9S_MB_2U(SCH_1):PAGE72_I2@PURE_QUANTA.SOCKET4677_AZIF0045P001C01CS(CHIPS)':
 'VSS437': CDS_PINID='VSS437';
NODE_NAME     U1 BD89
 '@S9S_MB_2U_LIB.S9S_MB_2U(SCH_1):PAGE72_I2@PURE_QUANTA.SOCKET4677_AZIF0045P001C01CS(CHIPS)':
 'VSS439': CDS_PINID='VSS439';
NODE_NAME     U1 BE64
 '@S9S_MB_2U_LIB.S9S_MB_2U(SCH_1):PAGE72_I2@PURE_QUANTA.SOCKET4677_AZIF0045P001C01CS(CHIPS)':
 'VSS440': CDS_PINID='VSS440';
NODE_NAME     U1 BE66
 '@S9S_MB_2U_LIB.S9S_MB_2U(SCH_1):PAGE72_I2@PURE_QUANTA.SOCKET4677_AZIF0045P001C01CS(CHIPS)':
 'VSS441': CDS_PINID='VSS441';
NODE_NAME     U1 BE68
 '@S9S_MB_2U_LIB.S9S_MB_2U(SCH_1):PAGE72_I2@PURE_QUANTA.SOCKET4677_AZIF0045P001C01CS(CHIPS)':
 'VSS442': CDS_PINID='VSS442';
NODE_NAME     U1 BE74
 '@S9S_MB_2U_LIB.S9S_MB_2U(SCH_1):PAGE72_I2@PURE_QUANTA.SOCKET4677_AZIF0045P001C01CS(CHIPS)':
 'VSS443': CDS_PINID='VSS443';
NODE_NAME     U1 BE76
 '@S9S_MB_2U_LIB.S9S_MB_2U(SCH_1):PAGE72_I2@PURE_QUANTA.SOCKET4677_AZIF0045P001C01CS(CHIPS)':
 'VSS444': CDS_PINID='VSS444';
NODE_NAME     U1 BE78
 '@S9S_MB_2U_LIB.S9S_MB_2U(SCH_1):PAGE72_I2@PURE_QUANTA.SOCKET4677_AZIF0045P001C01CS(CHIPS)':
 'VSS445': CDS_PINID='VSS445';
NODE_NAME     U1 BE84
 '@S9S_MB_2U_LIB.S9S_MB_2U(SCH_1):PAGE72_I2@PURE_QUANTA.SOCKET4677_AZIF0045P001C01CS(CHIPS)':
 'VSS446': CDS_PINID='VSS446';
NODE_NAME     U1 BF12
 '@S9S_MB_2U_LIB.S9S_MB_2U(SCH_1):PAGE72_I2@PURE_QUANTA.SOCKET4677_AZIF0045P001C01CS(CHIPS)':
 'VSS447': CDS_PINID='VSS447';
NODE_NAME     U1 BF16
 '@S9S_MB_2U_LIB.S9S_MB_2U(SCH_1):PAGE72_I2@PURE_QUANTA.SOCKET4677_AZIF0045P001C01CS(CHIPS)':
 'VSS448': CDS_PINID='VSS448';
NODE_NAME     U1 BF20
 '@S9S_MB_2U_LIB.S9S_MB_2U(SCH_1):PAGE72_I2@PURE_QUANTA.SOCKET4677_AZIF0045P001C01CS(CHIPS)':
 'VSS449': CDS_PINID='VSS449';
NODE_NAME     U1 BF4
 '@S9S_MB_2U_LIB.S9S_MB_2U(SCH_1):PAGE72_I2@PURE_QUANTA.SOCKET4677_AZIF0045P001C01CS(CHIPS)':
 'VSS450': CDS_PINID='VSS450';
NODE_NAME     U1 BF61
 '@S9S_MB_2U_LIB.S9S_MB_2U(SCH_1):PAGE72_I2@PURE_QUANTA.SOCKET4677_AZIF0045P001C01CS(CHIPS)':
 'VSS451': CDS_PINID='VSS451';
NODE_NAME     U1 BF63
 '@S9S_MB_2U_LIB.S9S_MB_2U(SCH_1):PAGE72_I2@PURE_QUANTA.SOCKET4677_AZIF0045P001C01CS(CHIPS)':
 'VSS452': CDS_PINID='VSS452';
NODE_NAME     U1 BF73
 '@S9S_MB_2U_LIB.S9S_MB_2U(SCH_1):PAGE72_I2@PURE_QUANTA.SOCKET4677_AZIF0045P001C01CS(CHIPS)':
 'VSS453': CDS_PINID='VSS453';
NODE_NAME     U1 BF75
 '@S9S_MB_2U_LIB.S9S_MB_2U(SCH_1):PAGE72_I2@PURE_QUANTA.SOCKET4677_AZIF0045P001C01CS(CHIPS)':
 'VSS454': CDS_PINID='VSS454';
NODE_NAME     U1 BF79
 '@S9S_MB_2U_LIB.S9S_MB_2U(SCH_1):PAGE72_I2@PURE_QUANTA.SOCKET4677_AZIF0045P001C01CS(CHIPS)':
 'VSS455': CDS_PINID='VSS455';
NODE_NAME     U1 BF8
 '@S9S_MB_2U_LIB.S9S_MB_2U(SCH_1):PAGE72_I2@PURE_QUANTA.SOCKET4677_AZIF0045P001C01CS(CHIPS)':
 'VSS456': CDS_PINID='VSS456';
NODE_NAME     U1 BF83
 '@S9S_MB_2U_LIB.S9S_MB_2U(SCH_1):PAGE72_I2@PURE_QUANTA.SOCKET4677_AZIF0045P001C01CS(CHIPS)':
 'VSS457': CDS_PINID='VSS457';
NODE_NAME     U1 BG1
 '@S9S_MB_2U_LIB.S9S_MB_2U(SCH_1):PAGE72_I2@PURE_QUANTA.SOCKET4677_AZIF0045P001C01CS(CHIPS)':
 'VSS458': CDS_PINID='VSS458';
NODE_NAME     U1 BG13
 '@S9S_MB_2U_LIB.S9S_MB_2U(SCH_1):PAGE72_I2@PURE_QUANTA.SOCKET4677_AZIF0045P001C01CS(CHIPS)':
 'VSS459': CDS_PINID='VSS459';
NODE_NAME     U1 BG17
 '@S9S_MB_2U_LIB.S9S_MB_2U(SCH_1):PAGE72_I2@PURE_QUANTA.SOCKET4677_AZIF0045P001C01CS(CHIPS)':
 'VSS460': CDS_PINID='VSS460';
NODE_NAME     U1 BG21
 '@S9S_MB_2U_LIB.S9S_MB_2U(SCH_1):PAGE72_I2@PURE_QUANTA.SOCKET4677_AZIF0045P001C01CS(CHIPS)':
 'VSS461': CDS_PINID='VSS461';
NODE_NAME     U1 BG23
 '@S9S_MB_2U_LIB.S9S_MB_2U(SCH_1):PAGE72_I2@PURE_QUANTA.SOCKET4677_AZIF0045P001C01CS(CHIPS)':
 'VSS462': CDS_PINID='VSS462';
NODE_NAME     U1 BG25
 '@S9S_MB_2U_LIB.S9S_MB_2U(SCH_1):PAGE72_I2@PURE_QUANTA.SOCKET4677_AZIF0045P001C01CS(CHIPS)':
 'VSS463': CDS_PINID='VSS463';
NODE_NAME     U1 BG5
 '@S9S_MB_2U_LIB.S9S_MB_2U(SCH_1):PAGE72_I2@PURE_QUANTA.SOCKET4677_AZIF0045P001C01CS(CHIPS)':
 'VSS464': CDS_PINID='VSS464';
NODE_NAME     U1 BG70
 '@S9S_MB_2U_LIB.S9S_MB_2U(SCH_1):PAGE72_I2@PURE_QUANTA.SOCKET4677_AZIF0045P001C01CS(CHIPS)':
 'VSS465': CDS_PINID='VSS465';
NODE_NAME     U1 BG9
 '@S9S_MB_2U_LIB.S9S_MB_2U(SCH_1):PAGE72_I2@PURE_QUANTA.SOCKET4677_AZIF0045P001C01CS(CHIPS)':
 'VSS466': CDS_PINID='VSS466';
NODE_NAME     U1 BH12
 '@S9S_MB_2U_LIB.S9S_MB_2U(SCH_1):PAGE72_I2@PURE_QUANTA.SOCKET4677_AZIF0045P001C01CS(CHIPS)':
 'VSS467': CDS_PINID='VSS467';
NODE_NAME     U1 BH16
 '@S9S_MB_2U_LIB.S9S_MB_2U(SCH_1):PAGE72_I2@PURE_QUANTA.SOCKET4677_AZIF0045P001C01CS(CHIPS)':
 'VSS468': CDS_PINID='VSS468';
NODE_NAME     U1 BH20
 '@S9S_MB_2U_LIB.S9S_MB_2U(SCH_1):PAGE72_I2@PURE_QUANTA.SOCKET4677_AZIF0045P001C01CS(CHIPS)':
 'VSS469': CDS_PINID='VSS469';
NODE_NAME     U1 BH4
 '@S9S_MB_2U_LIB.S9S_MB_2U(SCH_1):PAGE72_I2@PURE_QUANTA.SOCKET4677_AZIF0045P001C01CS(CHIPS)':
 'VSS470': CDS_PINID='VSS470';
NODE_NAME     U1 BH67
 '@S9S_MB_2U_LIB.S9S_MB_2U(SCH_1):PAGE72_I2@PURE_QUANTA.SOCKET4677_AZIF0045P001C01CS(CHIPS)':
 'VSS472': CDS_PINID='VSS472';
NODE_NAME     U1 BH73
 '@S9S_MB_2U_LIB.S9S_MB_2U(SCH_1):PAGE72_I2@PURE_QUANTA.SOCKET4677_AZIF0045P001C01CS(CHIPS)':
 'VSS473': CDS_PINID='VSS473';
NODE_NAME     U1 BH77
 '@S9S_MB_2U_LIB.S9S_MB_2U(SCH_1):PAGE72_I2@PURE_QUANTA.SOCKET4677_AZIF0045P001C01CS(CHIPS)':
 'VSS474': CDS_PINID='VSS474';
NODE_NAME     U1 BH8
 '@S9S_MB_2U_LIB.S9S_MB_2U(SCH_1):PAGE72_I2@PURE_QUANTA.SOCKET4677_AZIF0045P001C01CS(CHIPS)':
 'VSS475': CDS_PINID='VSS475';
NODE_NAME     U1 BH81
 '@S9S_MB_2U_LIB.S9S_MB_2U(SCH_1):PAGE72_I2@PURE_QUANTA.SOCKET4677_AZIF0045P001C01CS(CHIPS)':
 'VSS476': CDS_PINID='VSS476';
NODE_NAME     U1 BH83
 '@S9S_MB_2U_LIB.S9S_MB_2U(SCH_1):PAGE72_I2@PURE_QUANTA.SOCKET4677_AZIF0045P001C01CS(CHIPS)':
 'VSS477': CDS_PINID='VSS477';
NODE_NAME     U1 BJ62
 '@S9S_MB_2U_LIB.S9S_MB_2U(SCH_1):PAGE72_I2@PURE_QUANTA.SOCKET4677_AZIF0045P001C01CS(CHIPS)':
 'VSS479': CDS_PINID='VSS479';
NODE_NAME     U1 BJ68
 '@S9S_MB_2U_LIB.S9S_MB_2U(SCH_1):PAGE72_I2@PURE_QUANTA.SOCKET4677_AZIF0045P001C01CS(CHIPS)':
 'VSS480': CDS_PINID='VSS480';
NODE_NAME     U1 BJ80
 '@S9S_MB_2U_LIB.S9S_MB_2U(SCH_1):PAGE72_I2@PURE_QUANTA.SOCKET4677_AZIF0045P001C01CS(CHIPS)':
 'VSS481': CDS_PINID='VSS481';
NODE_NAME     U1 BJ82
 '@S9S_MB_2U_LIB.S9S_MB_2U(SCH_1):PAGE72_I2@PURE_QUANTA.SOCKET4677_AZIF0045P001C01CS(CHIPS)':
 'VSS482': CDS_PINID='VSS482';
NODE_NAME     U1 BJ84
 '@S9S_MB_2U_LIB.S9S_MB_2U(SCH_1):PAGE72_I2@PURE_QUANTA.SOCKET4677_AZIF0045P001C01CS(CHIPS)':
 'VSS483': CDS_PINID='VSS483';
NODE_NAME     U1 BJ86
 '@S9S_MB_2U_LIB.S9S_MB_2U(SCH_1):PAGE72_I2@PURE_QUANTA.SOCKET4677_AZIF0045P001C01CS(CHIPS)':
 'VSS484': CDS_PINID='VSS484';
NODE_NAME     U1 BJ88
 '@S9S_MB_2U_LIB.S9S_MB_2U(SCH_1):PAGE72_I2@PURE_QUANTA.SOCKET4677_AZIF0045P001C01CS(CHIPS)':
 'VSS485': CDS_PINID='VSS485';
NODE_NAME     U1 BJ90
 '@S9S_MB_2U_LIB.S9S_MB_2U(SCH_1):PAGE72_I2@PURE_QUANTA.SOCKET4677_AZIF0045P001C01CS(CHIPS)':
 'VSS486': CDS_PINID='VSS486';
NODE_NAME     U1 BK12
 '@S9S_MB_2U_LIB.S9S_MB_2U(SCH_1):PAGE72_I2@PURE_QUANTA.SOCKET4677_AZIF0045P001C01CS(CHIPS)':
 'VSS487': CDS_PINID='VSS487';
NODE_NAME     U1 BK16
 '@S9S_MB_2U_LIB.S9S_MB_2U(SCH_1):PAGE72_I2@PURE_QUANTA.SOCKET4677_AZIF0045P001C01CS(CHIPS)':
 'VSS488': CDS_PINID='VSS488';
NODE_NAME     U1 BK20
 '@S9S_MB_2U_LIB.S9S_MB_2U(SCH_1):PAGE72_I2@PURE_QUANTA.SOCKET4677_AZIF0045P001C01CS(CHIPS)':
 'VSS489': CDS_PINID='VSS489';
NODE_NAME     U1 BK4
 '@S9S_MB_2U_LIB.S9S_MB_2U(SCH_1):PAGE72_I2@PURE_QUANTA.SOCKET4677_AZIF0045P001C01CS(CHIPS)':
 'VSS490': CDS_PINID='VSS490';
NODE_NAME     U1 BK65
 '@S9S_MB_2U_LIB.S9S_MB_2U(SCH_1):PAGE72_I2@PURE_QUANTA.SOCKET4677_AZIF0045P001C01CS(CHIPS)':
 'VSS491': CDS_PINID='VSS491';
NODE_NAME     U1 BK71
 '@S9S_MB_2U_LIB.S9S_MB_2U(SCH_1):PAGE72_I2@PURE_QUANTA.SOCKET4677_AZIF0045P001C01CS(CHIPS)':
 'VSS492': CDS_PINID='VSS492';
NODE_NAME     U1 BK75
 '@S9S_MB_2U_LIB.S9S_MB_2U(SCH_1):PAGE72_I2@PURE_QUANTA.SOCKET4677_AZIF0045P001C01CS(CHIPS)':
 'VSS494': CDS_PINID='VSS494';
NODE_NAME     U1 BK79
 '@S9S_MB_2U_LIB.S9S_MB_2U(SCH_1):PAGE72_I2@PURE_QUANTA.SOCKET4677_AZIF0045P001C01CS(CHIPS)':
 'VSS495': CDS_PINID='VSS495';
NODE_NAME     U1 BK8
 '@S9S_MB_2U_LIB.S9S_MB_2U(SCH_1):PAGE72_I2@PURE_QUANTA.SOCKET4677_AZIF0045P001C01CS(CHIPS)':
 'VSS496': CDS_PINID='VSS496';
NODE_NAME     U1 BL1
 '@S9S_MB_2U_LIB.S9S_MB_2U(SCH_1):PAGE72_I2@PURE_QUANTA.SOCKET4677_AZIF0045P001C01CS(CHIPS)':
 'VSS497': CDS_PINID='VSS497';
NODE_NAME     U1 BL13
 '@S9S_MB_2U_LIB.S9S_MB_2U(SCH_1):PAGE72_I2@PURE_QUANTA.SOCKET4677_AZIF0045P001C01CS(CHIPS)':
 'VSS498': CDS_PINID='VSS498';
NODE_NAME     U1 BL17
 '@S9S_MB_2U_LIB.S9S_MB_2U(SCH_1):PAGE72_I2@PURE_QUANTA.SOCKET4677_AZIF0045P001C01CS(CHIPS)':
 'VSS499': CDS_PINID='VSS499';
NODE_NAME     U1 BL5
 '@S9S_MB_2U_LIB.S9S_MB_2U(SCH_1):PAGE72_I2@PURE_QUANTA.SOCKET4677_AZIF0045P001C01CS(CHIPS)':
 'VSS500': CDS_PINID='VSS500';
NODE_NAME     U1 BL68
 '@S9S_MB_2U_LIB.S9S_MB_2U(SCH_1):PAGE72_I2@PURE_QUANTA.SOCKET4677_AZIF0045P001C01CS(CHIPS)':
 'VSS501': CDS_PINID='VSS501';
NODE_NAME     U1 BL70
 '@S9S_MB_2U_LIB.S9S_MB_2U(SCH_1):PAGE72_I2@PURE_QUANTA.SOCKET4677_AZIF0045P001C01CS(CHIPS)':
 'VSS502': CDS_PINID='VSS502';
NODE_NAME     U1 BL72
 '@S9S_MB_2U_LIB.S9S_MB_2U(SCH_1):PAGE72_I2@PURE_QUANTA.SOCKET4677_AZIF0045P001C01CS(CHIPS)':
 'VSS503': CDS_PINID='VSS503';
NODE_NAME     U1 BL78
 '@S9S_MB_2U_LIB.S9S_MB_2U(SCH_1):PAGE72_I2@PURE_QUANTA.SOCKET4677_AZIF0045P001C01CS(CHIPS)':
 'VSS504': CDS_PINID='VSS504';
NODE_NAME     U1 BL9
 '@S9S_MB_2U_LIB.S9S_MB_2U(SCH_1):PAGE72_I2@PURE_QUANTA.SOCKET4677_AZIF0045P001C01CS(CHIPS)':
 'VSS505': CDS_PINID='VSS505';
NODE_NAME     U1 BM12
 '@S9S_MB_2U_LIB.S9S_MB_2U(SCH_1):PAGE72_I2@PURE_QUANTA.SOCKET4677_AZIF0045P001C01CS(CHIPS)':
 'VSS506': CDS_PINID='VSS506';
NODE_NAME     U1 BM16
 '@S9S_MB_2U_LIB.S9S_MB_2U(SCH_1):PAGE72_I2@PURE_QUANTA.SOCKET4677_AZIF0045P001C01CS(CHIPS)':
 'VSS507': CDS_PINID='VSS507';
NODE_NAME     U1 BM20
 '@S9S_MB_2U_LIB.S9S_MB_2U(SCH_1):PAGE72_I2@PURE_QUANTA.SOCKET4677_AZIF0045P001C01CS(CHIPS)':
 'VSS508': CDS_PINID='VSS508';
NODE_NAME     U1 BM22
 '@S9S_MB_2U_LIB.S9S_MB_2U(SCH_1):PAGE72_I2@PURE_QUANTA.SOCKET4677_AZIF0045P001C01CS(CHIPS)':
 'VSS509': CDS_PINID='VSS509';
NODE_NAME     U1 BM24
 '@S9S_MB_2U_LIB.S9S_MB_2U(SCH_1):PAGE72_I2@PURE_QUANTA.SOCKET4677_AZIF0045P001C01CS(CHIPS)':
 'VSS510': CDS_PINID='VSS510';
NODE_NAME     U1 BM26
 '@S9S_MB_2U_LIB.S9S_MB_2U(SCH_1):PAGE72_I2@PURE_QUANTA.SOCKET4677_AZIF0045P001C01CS(CHIPS)':
 'VSS511': CDS_PINID='VSS511';
NODE_NAME     U1 BM4
 '@S9S_MB_2U_LIB.S9S_MB_2U(SCH_1):PAGE72_I2@PURE_QUANTA.SOCKET4677_AZIF0045P001C01CS(CHIPS)':
 'VSS512': CDS_PINID='VSS512';
NODE_NAME     U1 BM61
 '@S9S_MB_2U_LIB.S9S_MB_2U(SCH_1):PAGE72_I2@PURE_QUANTA.SOCKET4677_AZIF0045P001C01CS(CHIPS)':
 'VSS513': CDS_PINID='VSS513';
NODE_NAME     U1 BM73
 '@S9S_MB_2U_LIB.S9S_MB_2U(SCH_1):PAGE72_I2@PURE_QUANTA.SOCKET4677_AZIF0045P001C01CS(CHIPS)':
 'VSS515': CDS_PINID='VSS515';
NODE_NAME     U1 BM77
 '@S9S_MB_2U_LIB.S9S_MB_2U(SCH_1):PAGE72_I2@PURE_QUANTA.SOCKET4677_AZIF0045P001C01CS(CHIPS)':
 'VSS516': CDS_PINID='VSS516';
NODE_NAME     U1 BM8
 '@S9S_MB_2U_LIB.S9S_MB_2U(SCH_1):PAGE72_I2@PURE_QUANTA.SOCKET4677_AZIF0045P001C01CS(CHIPS)':
 'VSS517': CDS_PINID='VSS517';
NODE_NAME     U1 BN31
 '@S9S_MB_2U_LIB.S9S_MB_2U(SCH_1):PAGE72_I2@PURE_QUANTA.SOCKET4677_AZIF0045P001C01CS(CHIPS)':
 'VSS518': CDS_PINID='VSS518';
NODE_NAME     U1 BN62
 '@S9S_MB_2U_LIB.S9S_MB_2U(SCH_1):PAGE72_I2@PURE_QUANTA.SOCKET4677_AZIF0045P001C01CS(CHIPS)':
 'VSS519': CDS_PINID='VSS519';
NODE_NAME     U1 BN70
 '@S9S_MB_2U_LIB.S9S_MB_2U(SCH_1):PAGE72_I2@PURE_QUANTA.SOCKET4677_AZIF0045P001C01CS(CHIPS)':
 'VSS520': CDS_PINID='VSS520';
NODE_NAME     U1 BP12
 '@S9S_MB_2U_LIB.S9S_MB_2U(SCH_1):PAGE72_I2@PURE_QUANTA.SOCKET4677_AZIF0045P001C01CS(CHIPS)':
 'VSS522': CDS_PINID='VSS522';
NODE_NAME     U1 BP16
 '@S9S_MB_2U_LIB.S9S_MB_2U(SCH_1):PAGE72_I2@PURE_QUANTA.SOCKET4677_AZIF0045P001C01CS(CHIPS)':
 'VSS523': CDS_PINID='VSS523';
NODE_NAME     U1 BP2
 '@S9S_MB_2U_LIB.S9S_MB_2U(SCH_1):PAGE72_I2@PURE_QUANTA.SOCKET4677_AZIF0045P001C01CS(CHIPS)':
 'VSS524': CDS_PINID='VSS524';
NODE_NAME     U1 BP20
 '@S9S_MB_2U_LIB.S9S_MB_2U(SCH_1):PAGE72_I2@PURE_QUANTA.SOCKET4677_AZIF0045P001C01CS(CHIPS)':
 'VSS525': CDS_PINID='VSS525';
NODE_NAME     U1 BP4
 '@S9S_MB_2U_LIB.S9S_MB_2U(SCH_1):PAGE72_I2@PURE_QUANTA.SOCKET4677_AZIF0045P001C01CS(CHIPS)':
 'VSS527': CDS_PINID='VSS527';
NODE_NAME     U1 BP63
 '@S9S_MB_2U_LIB.S9S_MB_2U(SCH_1):PAGE72_I2@PURE_QUANTA.SOCKET4677_AZIF0045P001C01CS(CHIPS)':
 'VSS528': CDS_PINID='VSS528';
NODE_NAME     U1 BP71
 '@S9S_MB_2U_LIB.S9S_MB_2U(SCH_1):PAGE72_I2@PURE_QUANTA.SOCKET4677_AZIF0045P001C01CS(CHIPS)':
 'VSS529': CDS_PINID='VSS529';
NODE_NAME     U1 BP73
 '@S9S_MB_2U_LIB.S9S_MB_2U(SCH_1):PAGE72_I2@PURE_QUANTA.SOCKET4677_AZIF0045P001C01CS(CHIPS)':
 'VSS530': CDS_PINID='VSS530';
NODE_NAME     U1 BP75
 '@S9S_MB_2U_LIB.S9S_MB_2U(SCH_1):PAGE72_I2@PURE_QUANTA.SOCKET4677_AZIF0045P001C01CS(CHIPS)':
 'VSS531': CDS_PINID='VSS531';
NODE_NAME     U1 BP77
 '@S9S_MB_2U_LIB.S9S_MB_2U(SCH_1):PAGE72_I2@PURE_QUANTA.SOCKET4677_AZIF0045P001C01CS(CHIPS)':
 'VSS532': CDS_PINID='VSS532';
NODE_NAME     U1 BP8
 '@S9S_MB_2U_LIB.S9S_MB_2U(SCH_1):PAGE72_I2@PURE_QUANTA.SOCKET4677_AZIF0045P001C01CS(CHIPS)':
 'VSS533': CDS_PINID='VSS533';
NODE_NAME     U1 BR13
 '@S9S_MB_2U_LIB.S9S_MB_2U(SCH_1):PAGE72_I2@PURE_QUANTA.SOCKET4677_AZIF0045P001C01CS(CHIPS)':
 'VSS535': CDS_PINID='VSS535';
NODE_NAME     U1 BR17
 '@S9S_MB_2U_LIB.S9S_MB_2U(SCH_1):PAGE72_I2@PURE_QUANTA.SOCKET4677_AZIF0045P001C01CS(CHIPS)':
 'VSS536': CDS_PINID='VSS536';
NODE_NAME     U1 BR27
 '@S9S_MB_2U_LIB.S9S_MB_2U(SCH_1):PAGE72_I2@PURE_QUANTA.SOCKET4677_AZIF0045P001C01CS(CHIPS)':
 'VSS538': CDS_PINID='VSS538';
NODE_NAME     U1 BR29
 '@S9S_MB_2U_LIB.S9S_MB_2U(SCH_1):PAGE72_I2@PURE_QUANTA.SOCKET4677_AZIF0045P001C01CS(CHIPS)':
 'VSS539': CDS_PINID='VSS539';
NODE_NAME     U1 BR31
 '@S9S_MB_2U_LIB.S9S_MB_2U(SCH_1):PAGE72_I2@PURE_QUANTA.SOCKET4677_AZIF0045P001C01CS(CHIPS)':
 'VSS540': CDS_PINID='VSS540';
NODE_NAME     U1 BR33
 '@S9S_MB_2U_LIB.S9S_MB_2U(SCH_1):PAGE72_I2@PURE_QUANTA.SOCKET4677_AZIF0045P001C01CS(CHIPS)':
 'VSS541': CDS_PINID='VSS541';
NODE_NAME     U1 BR9
 '@S9S_MB_2U_LIB.S9S_MB_2U(SCH_1):PAGE72_I2@PURE_QUANTA.SOCKET4677_AZIF0045P001C01CS(CHIPS)':
 'VSS572': CDS_PINID='VSS572';
NODE_NAME     U1 AK12
 '@S9S_MB_2U_LIB.S9S_MB_2U(SCH_1):PAGE72_I5@PURE_QUANTA.SOCKET4677_AZIF0045P001C01CS(CHIPS)':
 'VSS198': CDS_PINID='VSS198';
NODE_NAME     U1 AK16
 '@S9S_MB_2U_LIB.S9S_MB_2U(SCH_1):PAGE72_I5@PURE_QUANTA.SOCKET4677_AZIF0045P001C01CS(CHIPS)':
 'VSS199': CDS_PINID='VSS199';
NODE_NAME     U1 AK18
 '@S9S_MB_2U_LIB.S9S_MB_2U(SCH_1):PAGE72_I5@PURE_QUANTA.SOCKET4677_AZIF0045P001C01CS(CHIPS)':
 'VSS200': CDS_PINID='VSS200';
NODE_NAME     U1 AK24
 '@S9S_MB_2U_LIB.S9S_MB_2U(SCH_1):PAGE72_I5@PURE_QUANTA.SOCKET4677_AZIF0045P001C01CS(CHIPS)':
 'VSS201': CDS_PINID='VSS201';
NODE_NAME     U1 AK30
 '@S9S_MB_2U_LIB.S9S_MB_2U(SCH_1):PAGE72_I5@PURE_QUANTA.SOCKET4677_AZIF0045P001C01CS(CHIPS)':
 'VSS202': CDS_PINID='VSS202';
NODE_NAME     U1 AK36
 '@S9S_MB_2U_LIB.S9S_MB_2U(SCH_1):PAGE72_I5@PURE_QUANTA.SOCKET4677_AZIF0045P001C01CS(CHIPS)':
 'VSS203': CDS_PINID='VSS203';
NODE_NAME     U1 AK4
 '@S9S_MB_2U_LIB.S9S_MB_2U(SCH_1):PAGE72_I5@PURE_QUANTA.SOCKET4677_AZIF0045P001C01CS(CHIPS)':
 'VSS204': CDS_PINID='VSS204';
NODE_NAME     U1 AK42
 '@S9S_MB_2U_LIB.S9S_MB_2U(SCH_1):PAGE72_I5@PURE_QUANTA.SOCKET4677_AZIF0045P001C01CS(CHIPS)':
 'VSS205': CDS_PINID='VSS205';
NODE_NAME     U1 AK49
 '@S9S_MB_2U_LIB.S9S_MB_2U(SCH_1):PAGE72_I5@PURE_QUANTA.SOCKET4677_AZIF0045P001C01CS(CHIPS)':
 'VSS206': CDS_PINID='VSS206';
NODE_NAME     U1 AK55
 '@S9S_MB_2U_LIB.S9S_MB_2U(SCH_1):PAGE72_I5@PURE_QUANTA.SOCKET4677_AZIF0045P001C01CS(CHIPS)':
 'VSS207': CDS_PINID='VSS207';
NODE_NAME     U1 AK61
 '@S9S_MB_2U_LIB.S9S_MB_2U(SCH_1):PAGE72_I5@PURE_QUANTA.SOCKET4677_AZIF0045P001C01CS(CHIPS)':
 'VSS208': CDS_PINID='VSS208';
NODE_NAME     U1 AK67
 '@S9S_MB_2U_LIB.S9S_MB_2U(SCH_1):PAGE72_I5@PURE_QUANTA.SOCKET4677_AZIF0045P001C01CS(CHIPS)':
 'VSS209': CDS_PINID='VSS209';
NODE_NAME     U1 AK73
 '@S9S_MB_2U_LIB.S9S_MB_2U(SCH_1):PAGE72_I5@PURE_QUANTA.SOCKET4677_AZIF0045P001C01CS(CHIPS)':
 'VSS210': CDS_PINID='VSS210';
NODE_NAME     U1 AK79
 '@S9S_MB_2U_LIB.S9S_MB_2U(SCH_1):PAGE72_I5@PURE_QUANTA.SOCKET4677_AZIF0045P001C01CS(CHIPS)':
 'VSS211': CDS_PINID='VSS211';
NODE_NAME     U1 AK8
 '@S9S_MB_2U_LIB.S9S_MB_2U(SCH_1):PAGE72_I5@PURE_QUANTA.SOCKET4677_AZIF0045P001C01CS(CHIPS)':
 'VSS212': CDS_PINID='VSS212';
NODE_NAME     U1 AK81
 '@S9S_MB_2U_LIB.S9S_MB_2U(SCH_1):PAGE72_I5@PURE_QUANTA.SOCKET4677_AZIF0045P001C01CS(CHIPS)':
 'VSS213': CDS_PINID='VSS213';
NODE_NAME     U1 AK83
 '@S9S_MB_2U_LIB.S9S_MB_2U(SCH_1):PAGE72_I5@PURE_QUANTA.SOCKET4677_AZIF0045P001C01CS(CHIPS)':
 'VSS214': CDS_PINID='VSS214';
NODE_NAME     U1 AK87
 '@S9S_MB_2U_LIB.S9S_MB_2U(SCH_1):PAGE72_I5@PURE_QUANTA.SOCKET4677_AZIF0045P001C01CS(CHIPS)':
 'VSS215': CDS_PINID='VSS215';
NODE_NAME     U1 AK91
 '@S9S_MB_2U_LIB.S9S_MB_2U(SCH_1):PAGE72_I5@PURE_QUANTA.SOCKET4677_AZIF0045P001C01CS(CHIPS)':
 'VSS216': CDS_PINID='VSS216';
NODE_NAME     U1 AL1
 '@S9S_MB_2U_LIB.S9S_MB_2U(SCH_1):PAGE72_I5@PURE_QUANTA.SOCKET4677_AZIF0045P001C01CS(CHIPS)':
 'VSS217': CDS_PINID='VSS217';
NODE_NAME     U1 AL13
 '@S9S_MB_2U_LIB.S9S_MB_2U(SCH_1):PAGE72_I5@PURE_QUANTA.SOCKET4677_AZIF0045P001C01CS(CHIPS)':
 'VSS218': CDS_PINID='VSS218';
NODE_NAME     U1 AL17
 '@S9S_MB_2U_LIB.S9S_MB_2U(SCH_1):PAGE72_I5@PURE_QUANTA.SOCKET4677_AZIF0045P001C01CS(CHIPS)':
 'VSS219': CDS_PINID='VSS219';
NODE_NAME     U1 AL5
 '@S9S_MB_2U_LIB.S9S_MB_2U(SCH_1):PAGE72_I5@PURE_QUANTA.SOCKET4677_AZIF0045P001C01CS(CHIPS)':
 'VSS220': CDS_PINID='VSS220';
NODE_NAME     U1 AL52
 '@S9S_MB_2U_LIB.S9S_MB_2U(SCH_1):PAGE72_I5@PURE_QUANTA.SOCKET4677_AZIF0045P001C01CS(CHIPS)':
 'VSS221': CDS_PINID='VSS221';
NODE_NAME     U1 AL80
 '@S9S_MB_2U_LIB.S9S_MB_2U(SCH_1):PAGE72_I5@PURE_QUANTA.SOCKET4677_AZIF0045P001C01CS(CHIPS)':
 'VSS222': CDS_PINID='VSS222';
NODE_NAME     U1 AL82
 '@S9S_MB_2U_LIB.S9S_MB_2U(SCH_1):PAGE72_I5@PURE_QUANTA.SOCKET4677_AZIF0045P001C01CS(CHIPS)':
 'VSS223': CDS_PINID='VSS223';
NODE_NAME     U1 AL84
 '@S9S_MB_2U_LIB.S9S_MB_2U(SCH_1):PAGE72_I5@PURE_QUANTA.SOCKET4677_AZIF0045P001C01CS(CHIPS)':
 'VSS224': CDS_PINID='VSS224';
NODE_NAME     U1 AL88
 '@S9S_MB_2U_LIB.S9S_MB_2U(SCH_1):PAGE72_I5@PURE_QUANTA.SOCKET4677_AZIF0045P001C01CS(CHIPS)':
 'VSS225': CDS_PINID='VSS225';
NODE_NAME     U1 AL9
 '@S9S_MB_2U_LIB.S9S_MB_2U(SCH_1):PAGE72_I5@PURE_QUANTA.SOCKET4677_AZIF0045P001C01CS(CHIPS)':
 'VSS226': CDS_PINID='VSS226';
NODE_NAME     U1 AM12
 '@S9S_MB_2U_LIB.S9S_MB_2U(SCH_1):PAGE72_I5@PURE_QUANTA.SOCKET4677_AZIF0045P001C01CS(CHIPS)':
 'VSS227': CDS_PINID='VSS227';
NODE_NAME     U1 AM16
 '@S9S_MB_2U_LIB.S9S_MB_2U(SCH_1):PAGE72_I5@PURE_QUANTA.SOCKET4677_AZIF0045P001C01CS(CHIPS)':
 'VSS228': CDS_PINID='VSS228';
NODE_NAME     U1 AM18
 '@S9S_MB_2U_LIB.S9S_MB_2U(SCH_1):PAGE72_I5@PURE_QUANTA.SOCKET4677_AZIF0045P001C01CS(CHIPS)':
 'VSS229': CDS_PINID='VSS229';
NODE_NAME     U1 AM20
 '@S9S_MB_2U_LIB.S9S_MB_2U(SCH_1):PAGE72_I5@PURE_QUANTA.SOCKET4677_AZIF0045P001C01CS(CHIPS)':
 'VSS230': CDS_PINID='VSS230';
NODE_NAME     U1 AM22
 '@S9S_MB_2U_LIB.S9S_MB_2U(SCH_1):PAGE72_I5@PURE_QUANTA.SOCKET4677_AZIF0045P001C01CS(CHIPS)':
 'VSS231': CDS_PINID='VSS231';
NODE_NAME     U1 AM24
 '@S9S_MB_2U_LIB.S9S_MB_2U(SCH_1):PAGE72_I5@PURE_QUANTA.SOCKET4677_AZIF0045P001C01CS(CHIPS)':
 'VSS232': CDS_PINID='VSS232';
NODE_NAME     U1 AM26
 '@S9S_MB_2U_LIB.S9S_MB_2U(SCH_1):PAGE72_I5@PURE_QUANTA.SOCKET4677_AZIF0045P001C01CS(CHIPS)':
 'VSS233': CDS_PINID='VSS233';
NODE_NAME     U1 AM28
 '@S9S_MB_2U_LIB.S9S_MB_2U(SCH_1):PAGE72_I5@PURE_QUANTA.SOCKET4677_AZIF0045P001C01CS(CHIPS)':
 'VSS234': CDS_PINID='VSS234';
NODE_NAME     U1 AM30
 '@S9S_MB_2U_LIB.S9S_MB_2U(SCH_1):PAGE72_I5@PURE_QUANTA.SOCKET4677_AZIF0045P001C01CS(CHIPS)':
 'VSS235': CDS_PINID='VSS235';
NODE_NAME     U1 AM32
 '@S9S_MB_2U_LIB.S9S_MB_2U(SCH_1):PAGE72_I5@PURE_QUANTA.SOCKET4677_AZIF0045P001C01CS(CHIPS)':
 'VSS236': CDS_PINID='VSS236';
NODE_NAME     U1 AM34
 '@S9S_MB_2U_LIB.S9S_MB_2U(SCH_1):PAGE72_I5@PURE_QUANTA.SOCKET4677_AZIF0045P001C01CS(CHIPS)':
 'VSS237': CDS_PINID='VSS237';
NODE_NAME     U1 AM36
 '@S9S_MB_2U_LIB.S9S_MB_2U(SCH_1):PAGE72_I5@PURE_QUANTA.SOCKET4677_AZIF0045P001C01CS(CHIPS)':
 'VSS238': CDS_PINID='VSS238';
NODE_NAME     U1 AM38
 '@S9S_MB_2U_LIB.S9S_MB_2U(SCH_1):PAGE72_I5@PURE_QUANTA.SOCKET4677_AZIF0045P001C01CS(CHIPS)':
 'VSS239': CDS_PINID='VSS239';
NODE_NAME     U1 AM4
 '@S9S_MB_2U_LIB.S9S_MB_2U(SCH_1):PAGE72_I5@PURE_QUANTA.SOCKET4677_AZIF0045P001C01CS(CHIPS)':
 'VSS240': CDS_PINID='VSS240';
NODE_NAME     U1 AM40
 '@S9S_MB_2U_LIB.S9S_MB_2U(SCH_1):PAGE72_I5@PURE_QUANTA.SOCKET4677_AZIF0045P001C01CS(CHIPS)':
 'VSS241': CDS_PINID='VSS241';
NODE_NAME     U1 AM42
 '@S9S_MB_2U_LIB.S9S_MB_2U(SCH_1):PAGE72_I5@PURE_QUANTA.SOCKET4677_AZIF0045P001C01CS(CHIPS)':
 'VSS242': CDS_PINID='VSS242';
NODE_NAME     U1 AM44
 '@S9S_MB_2U_LIB.S9S_MB_2U(SCH_1):PAGE72_I5@PURE_QUANTA.SOCKET4677_AZIF0045P001C01CS(CHIPS)':
 'VSS243': CDS_PINID='VSS243';
NODE_NAME     U1 AM47
 '@S9S_MB_2U_LIB.S9S_MB_2U(SCH_1):PAGE72_I5@PURE_QUANTA.SOCKET4677_AZIF0045P001C01CS(CHIPS)':
 'VSS244': CDS_PINID='VSS244';
NODE_NAME     U1 AM49
 '@S9S_MB_2U_LIB.S9S_MB_2U(SCH_1):PAGE72_I5@PURE_QUANTA.SOCKET4677_AZIF0045P001C01CS(CHIPS)':
 'VSS245': CDS_PINID='VSS245';
NODE_NAME     U1 AM51
 '@S9S_MB_2U_LIB.S9S_MB_2U(SCH_1):PAGE72_I5@PURE_QUANTA.SOCKET4677_AZIF0045P001C01CS(CHIPS)':
 'VSS246': CDS_PINID='VSS246';
NODE_NAME     U1 AM53
 '@S9S_MB_2U_LIB.S9S_MB_2U(SCH_1):PAGE72_I5@PURE_QUANTA.SOCKET4677_AZIF0045P001C01CS(CHIPS)':
 'VSS247': CDS_PINID='VSS247';
NODE_NAME     U1 AM55
 '@S9S_MB_2U_LIB.S9S_MB_2U(SCH_1):PAGE72_I5@PURE_QUANTA.SOCKET4677_AZIF0045P001C01CS(CHIPS)':
 'VSS248': CDS_PINID='VSS248';
NODE_NAME     U1 AM57
 '@S9S_MB_2U_LIB.S9S_MB_2U(SCH_1):PAGE72_I5@PURE_QUANTA.SOCKET4677_AZIF0045P001C01CS(CHIPS)':
 'VSS249': CDS_PINID='VSS249';
NODE_NAME     U1 AM59
 '@S9S_MB_2U_LIB.S9S_MB_2U(SCH_1):PAGE72_I5@PURE_QUANTA.SOCKET4677_AZIF0045P001C01CS(CHIPS)':
 'VSS250': CDS_PINID='VSS250';
NODE_NAME     U1 AM61
 '@S9S_MB_2U_LIB.S9S_MB_2U(SCH_1):PAGE72_I5@PURE_QUANTA.SOCKET4677_AZIF0045P001C01CS(CHIPS)':
 'VSS251': CDS_PINID='VSS251';
NODE_NAME     U1 AM63
 '@S9S_MB_2U_LIB.S9S_MB_2U(SCH_1):PAGE72_I5@PURE_QUANTA.SOCKET4677_AZIF0045P001C01CS(CHIPS)':
 'VSS252': CDS_PINID='VSS252';
NODE_NAME     U1 AM65
 '@S9S_MB_2U_LIB.S9S_MB_2U(SCH_1):PAGE72_I5@PURE_QUANTA.SOCKET4677_AZIF0045P001C01CS(CHIPS)':
 'VSS253': CDS_PINID='VSS253';
NODE_NAME     U1 AM67
 '@S9S_MB_2U_LIB.S9S_MB_2U(SCH_1):PAGE72_I5@PURE_QUANTA.SOCKET4677_AZIF0045P001C01CS(CHIPS)':
 'VSS254': CDS_PINID='VSS254';
NODE_NAME     U1 AM69
 '@S9S_MB_2U_LIB.S9S_MB_2U(SCH_1):PAGE72_I5@PURE_QUANTA.SOCKET4677_AZIF0045P001C01CS(CHIPS)':
 'VSS255': CDS_PINID='VSS255';
NODE_NAME     U1 AM71
 '@S9S_MB_2U_LIB.S9S_MB_2U(SCH_1):PAGE72_I5@PURE_QUANTA.SOCKET4677_AZIF0045P001C01CS(CHIPS)':
 'VSS256': CDS_PINID='VSS256';
NODE_NAME     U1 AM73
 '@S9S_MB_2U_LIB.S9S_MB_2U(SCH_1):PAGE72_I5@PURE_QUANTA.SOCKET4677_AZIF0045P001C01CS(CHIPS)':
 'VSS257': CDS_PINID='VSS257';
NODE_NAME     U1 AM75
 '@S9S_MB_2U_LIB.S9S_MB_2U(SCH_1):PAGE72_I5@PURE_QUANTA.SOCKET4677_AZIF0045P001C01CS(CHIPS)':
 'VSS258': CDS_PINID='VSS258';
NODE_NAME     U1 AM77
 '@S9S_MB_2U_LIB.S9S_MB_2U(SCH_1):PAGE72_I5@PURE_QUANTA.SOCKET4677_AZIF0045P001C01CS(CHIPS)':
 'VSS259': CDS_PINID='VSS259';
NODE_NAME     U1 AM8
 '@S9S_MB_2U_LIB.S9S_MB_2U(SCH_1):PAGE72_I5@PURE_QUANTA.SOCKET4677_AZIF0045P001C01CS(CHIPS)':
 'VSS260': CDS_PINID='VSS260';
NODE_NAME     U1 AN52
 '@S9S_MB_2U_LIB.S9S_MB_2U(SCH_1):PAGE72_I5@PURE_QUANTA.SOCKET4677_AZIF0045P001C01CS(CHIPS)':
 'VSS261': CDS_PINID='VSS261';
NODE_NAME     U1 AN84
 '@S9S_MB_2U_LIB.S9S_MB_2U(SCH_1):PAGE72_I5@PURE_QUANTA.SOCKET4677_AZIF0045P001C01CS(CHIPS)':
 'VSS262': CDS_PINID='VSS262';
NODE_NAME     U1 AN88
 '@S9S_MB_2U_LIB.S9S_MB_2U(SCH_1):PAGE72_I5@PURE_QUANTA.SOCKET4677_AZIF0045P001C01CS(CHIPS)':
 'VSS263': CDS_PINID='VSS263';
NODE_NAME     U1 AP12
 '@S9S_MB_2U_LIB.S9S_MB_2U(SCH_1):PAGE72_I5@PURE_QUANTA.SOCKET4677_AZIF0045P001C01CS(CHIPS)':
 'VSS264': CDS_PINID='VSS264';
NODE_NAME     U1 AP16
 '@S9S_MB_2U_LIB.S9S_MB_2U(SCH_1):PAGE72_I5@PURE_QUANTA.SOCKET4677_AZIF0045P001C01CS(CHIPS)':
 'VSS265': CDS_PINID='VSS265';
NODE_NAME     U1 AP18
 '@S9S_MB_2U_LIB.S9S_MB_2U(SCH_1):PAGE72_I5@PURE_QUANTA.SOCKET4677_AZIF0045P001C01CS(CHIPS)':
 'VSS266': CDS_PINID='VSS266';
NODE_NAME     U1 AP24
 '@S9S_MB_2U_LIB.S9S_MB_2U(SCH_1):PAGE72_I5@PURE_QUANTA.SOCKET4677_AZIF0045P001C01CS(CHIPS)':
 'VSS267': CDS_PINID='VSS267';
NODE_NAME     U1 AP30
 '@S9S_MB_2U_LIB.S9S_MB_2U(SCH_1):PAGE72_I5@PURE_QUANTA.SOCKET4677_AZIF0045P001C01CS(CHIPS)':
 'VSS268': CDS_PINID='VSS268';
NODE_NAME     U1 AP36
 '@S9S_MB_2U_LIB.S9S_MB_2U(SCH_1):PAGE72_I5@PURE_QUANTA.SOCKET4677_AZIF0045P001C01CS(CHIPS)':
 'VSS269': CDS_PINID='VSS269';
NODE_NAME     U1 AP4
 '@S9S_MB_2U_LIB.S9S_MB_2U(SCH_1):PAGE72_I5@PURE_QUANTA.SOCKET4677_AZIF0045P001C01CS(CHIPS)':
 'VSS270': CDS_PINID='VSS270';
NODE_NAME     U1 AP42
 '@S9S_MB_2U_LIB.S9S_MB_2U(SCH_1):PAGE72_I5@PURE_QUANTA.SOCKET4677_AZIF0045P001C01CS(CHIPS)':
 'VSS271': CDS_PINID='VSS271';
NODE_NAME     U1 AP49
 '@S9S_MB_2U_LIB.S9S_MB_2U(SCH_1):PAGE72_I5@PURE_QUANTA.SOCKET4677_AZIF0045P001C01CS(CHIPS)':
 'VSS272': CDS_PINID='VSS272';
NODE_NAME     U1 AP55
 '@S9S_MB_2U_LIB.S9S_MB_2U(SCH_1):PAGE72_I5@PURE_QUANTA.SOCKET4677_AZIF0045P001C01CS(CHIPS)':
 'VSS273': CDS_PINID='VSS273';
NODE_NAME     U1 AP61
 '@S9S_MB_2U_LIB.S9S_MB_2U(SCH_1):PAGE72_I5@PURE_QUANTA.SOCKET4677_AZIF0045P001C01CS(CHIPS)':
 'VSS274': CDS_PINID='VSS274';
NODE_NAME     U1 AP67
 '@S9S_MB_2U_LIB.S9S_MB_2U(SCH_1):PAGE72_I5@PURE_QUANTA.SOCKET4677_AZIF0045P001C01CS(CHIPS)':
 'VSS275': CDS_PINID='VSS275';
NODE_NAME     U1 AP73
 '@S9S_MB_2U_LIB.S9S_MB_2U(SCH_1):PAGE72_I5@PURE_QUANTA.SOCKET4677_AZIF0045P001C01CS(CHIPS)':
 'VSS276': CDS_PINID='VSS276';
NODE_NAME     U1 AP79
 '@S9S_MB_2U_LIB.S9S_MB_2U(SCH_1):PAGE72_I5@PURE_QUANTA.SOCKET4677_AZIF0045P001C01CS(CHIPS)':
 'VSS277': CDS_PINID='VSS277';
NODE_NAME     U1 AP8
 '@S9S_MB_2U_LIB.S9S_MB_2U(SCH_1):PAGE72_I5@PURE_QUANTA.SOCKET4677_AZIF0045P001C01CS(CHIPS)':
 'VSS278': CDS_PINID='VSS278';
NODE_NAME     U1 AP83
 '@S9S_MB_2U_LIB.S9S_MB_2U(SCH_1):PAGE72_I5@PURE_QUANTA.SOCKET4677_AZIF0045P001C01CS(CHIPS)':
 'VSS279': CDS_PINID='VSS279';
NODE_NAME     U1 AP87
 '@S9S_MB_2U_LIB.S9S_MB_2U(SCH_1):PAGE72_I5@PURE_QUANTA.SOCKET4677_AZIF0045P001C01CS(CHIPS)':
 'VSS280': CDS_PINID='VSS280';
NODE_NAME     U1 AP91
 '@S9S_MB_2U_LIB.S9S_MB_2U(SCH_1):PAGE72_I5@PURE_QUANTA.SOCKET4677_AZIF0045P001C01CS(CHIPS)':
 'VSS281': CDS_PINID='VSS281';
NODE_NAME     U1 AR1
 '@S9S_MB_2U_LIB.S9S_MB_2U(SCH_1):PAGE72_I5@PURE_QUANTA.SOCKET4677_AZIF0045P001C01CS(CHIPS)':
 'VSS282': CDS_PINID='VSS282';
NODE_NAME     U1 AR13
 '@S9S_MB_2U_LIB.S9S_MB_2U(SCH_1):PAGE72_I5@PURE_QUANTA.SOCKET4677_AZIF0045P001C01CS(CHIPS)':
 'VSS283': CDS_PINID='VSS283';
NODE_NAME     U1 AR19
 '@S9S_MB_2U_LIB.S9S_MB_2U(SCH_1):PAGE72_I5@PURE_QUANTA.SOCKET4677_AZIF0045P001C01CS(CHIPS)':
 'VSS284': CDS_PINID='VSS284';
NODE_NAME     U1 AR23
 '@S9S_MB_2U_LIB.S9S_MB_2U(SCH_1):PAGE72_I5@PURE_QUANTA.SOCKET4677_AZIF0045P001C01CS(CHIPS)':
 'VSS285': CDS_PINID='VSS285';
NODE_NAME     U1 AR25
 '@S9S_MB_2U_LIB.S9S_MB_2U(SCH_1):PAGE72_I5@PURE_QUANTA.SOCKET4677_AZIF0045P001C01CS(CHIPS)':
 'VSS286': CDS_PINID='VSS286';
NODE_NAME     U1 AR29
 '@S9S_MB_2U_LIB.S9S_MB_2U(SCH_1):PAGE72_I5@PURE_QUANTA.SOCKET4677_AZIF0045P001C01CS(CHIPS)':
 'VSS287': CDS_PINID='VSS287';
NODE_NAME     U1 AR31
 '@S9S_MB_2U_LIB.S9S_MB_2U(SCH_1):PAGE72_I5@PURE_QUANTA.SOCKET4677_AZIF0045P001C01CS(CHIPS)':
 'VSS288': CDS_PINID='VSS288';
NODE_NAME     U1 AR35
 '@S9S_MB_2U_LIB.S9S_MB_2U(SCH_1):PAGE72_I5@PURE_QUANTA.SOCKET4677_AZIF0045P001C01CS(CHIPS)':
 'VSS289': CDS_PINID='VSS289';
NODE_NAME     U1 AR37
 '@S9S_MB_2U_LIB.S9S_MB_2U(SCH_1):PAGE72_I5@PURE_QUANTA.SOCKET4677_AZIF0045P001C01CS(CHIPS)':
 'VSS290': CDS_PINID='VSS290';
NODE_NAME     U1 AR41
 '@S9S_MB_2U_LIB.S9S_MB_2U(SCH_1):PAGE72_I5@PURE_QUANTA.SOCKET4677_AZIF0045P001C01CS(CHIPS)':
 'VSS291': CDS_PINID='VSS291';
NODE_NAME     U1 AR43
 '@S9S_MB_2U_LIB.S9S_MB_2U(SCH_1):PAGE72_I5@PURE_QUANTA.SOCKET4677_AZIF0045P001C01CS(CHIPS)':
 'VSS292': CDS_PINID='VSS292';
NODE_NAME     U1 AR48
 '@S9S_MB_2U_LIB.S9S_MB_2U(SCH_1):PAGE72_I5@PURE_QUANTA.SOCKET4677_AZIF0045P001C01CS(CHIPS)':
 'VSS293': CDS_PINID='VSS293';
NODE_NAME     U1 AR5
 '@S9S_MB_2U_LIB.S9S_MB_2U(SCH_1):PAGE72_I5@PURE_QUANTA.SOCKET4677_AZIF0045P001C01CS(CHIPS)':
 'VSS294': CDS_PINID='VSS294';
NODE_NAME     U1 AR50
 '@S9S_MB_2U_LIB.S9S_MB_2U(SCH_1):PAGE72_I5@PURE_QUANTA.SOCKET4677_AZIF0045P001C01CS(CHIPS)':
 'VSS295': CDS_PINID='VSS295';
NODE_NAME     U1 AR54
 '@S9S_MB_2U_LIB.S9S_MB_2U(SCH_1):PAGE72_I5@PURE_QUANTA.SOCKET4677_AZIF0045P001C01CS(CHIPS)':
 'VSS296': CDS_PINID='VSS296';
NODE_NAME     U1 AR56
 '@S9S_MB_2U_LIB.S9S_MB_2U(SCH_1):PAGE72_I5@PURE_QUANTA.SOCKET4677_AZIF0045P001C01CS(CHIPS)':
 'VSS297': CDS_PINID='VSS297';
NODE_NAME     U1 AR60
 '@S9S_MB_2U_LIB.S9S_MB_2U(SCH_1):PAGE72_I5@PURE_QUANTA.SOCKET4677_AZIF0045P001C01CS(CHIPS)':
 'VSS298': CDS_PINID='VSS298';
NODE_NAME     U1 AR62
 '@S9S_MB_2U_LIB.S9S_MB_2U(SCH_1):PAGE72_I5@PURE_QUANTA.SOCKET4677_AZIF0045P001C01CS(CHIPS)':
 'VSS299': CDS_PINID='VSS299';
NODE_NAME     U1 AR66
 '@S9S_MB_2U_LIB.S9S_MB_2U(SCH_1):PAGE72_I5@PURE_QUANTA.SOCKET4677_AZIF0045P001C01CS(CHIPS)':
 'VSS300': CDS_PINID='VSS300';
NODE_NAME     U1 AR68
 '@S9S_MB_2U_LIB.S9S_MB_2U(SCH_1):PAGE72_I5@PURE_QUANTA.SOCKET4677_AZIF0045P001C01CS(CHIPS)':
 'VSS301': CDS_PINID='VSS301';
NODE_NAME     U1 AR72
 '@S9S_MB_2U_LIB.S9S_MB_2U(SCH_1):PAGE72_I5@PURE_QUANTA.SOCKET4677_AZIF0045P001C01CS(CHIPS)':
 'VSS302': CDS_PINID='VSS302';
NODE_NAME     U1 AR74
 '@S9S_MB_2U_LIB.S9S_MB_2U(SCH_1):PAGE72_I5@PURE_QUANTA.SOCKET4677_AZIF0045P001C01CS(CHIPS)':
 'VSS303': CDS_PINID='VSS303';
NODE_NAME     U1 AR78
 '@S9S_MB_2U_LIB.S9S_MB_2U(SCH_1):PAGE72_I5@PURE_QUANTA.SOCKET4677_AZIF0045P001C01CS(CHIPS)':
 'VSS304': CDS_PINID='VSS304';
NODE_NAME     U1 AR82
 '@S9S_MB_2U_LIB.S9S_MB_2U(SCH_1):PAGE72_I5@PURE_QUANTA.SOCKET4677_AZIF0045P001C01CS(CHIPS)':
 'VSS305': CDS_PINID='VSS305';
NODE_NAME     U1 AR84
 '@S9S_MB_2U_LIB.S9S_MB_2U(SCH_1):PAGE72_I5@PURE_QUANTA.SOCKET4677_AZIF0045P001C01CS(CHIPS)':
 'VSS306': CDS_PINID='VSS306';
NODE_NAME     U1 AR88
 '@S9S_MB_2U_LIB.S9S_MB_2U(SCH_1):PAGE72_I5@PURE_QUANTA.SOCKET4677_AZIF0045P001C01CS(CHIPS)':
 'VSS307': CDS_PINID='VSS307';
NODE_NAME     U1 AR9
 '@S9S_MB_2U_LIB.S9S_MB_2U(SCH_1):PAGE72_I5@PURE_QUANTA.SOCKET4677_AZIF0045P001C01CS(CHIPS)':
 'VSS308': CDS_PINID='VSS308';
NODE_NAME     U1 AT12
 '@S9S_MB_2U_LIB.S9S_MB_2U(SCH_1):PAGE72_I5@PURE_QUANTA.SOCKET4677_AZIF0045P001C01CS(CHIPS)':
 'VSS309': CDS_PINID='VSS309';
NODE_NAME     U1 AT16
 '@S9S_MB_2U_LIB.S9S_MB_2U(SCH_1):PAGE72_I5@PURE_QUANTA.SOCKET4677_AZIF0045P001C01CS(CHIPS)':
 'VSS310': CDS_PINID='VSS310';
NODE_NAME     U1 AT20
 '@S9S_MB_2U_LIB.S9S_MB_2U(SCH_1):PAGE72_I5@PURE_QUANTA.SOCKET4677_AZIF0045P001C01CS(CHIPS)':
 'VSS311': CDS_PINID='VSS311';
NODE_NAME     U1 AT22
 '@S9S_MB_2U_LIB.S9S_MB_2U(SCH_1):PAGE72_I5@PURE_QUANTA.SOCKET4677_AZIF0045P001C01CS(CHIPS)':
 'VSS312': CDS_PINID='VSS312';
NODE_NAME     U1 AT26
 '@S9S_MB_2U_LIB.S9S_MB_2U(SCH_1):PAGE72_I5@PURE_QUANTA.SOCKET4677_AZIF0045P001C01CS(CHIPS)':
 'VSS313': CDS_PINID='VSS313';
NODE_NAME     U1 AT28
 '@S9S_MB_2U_LIB.S9S_MB_2U(SCH_1):PAGE72_I5@PURE_QUANTA.SOCKET4677_AZIF0045P001C01CS(CHIPS)':
 'VSS314': CDS_PINID='VSS314';
NODE_NAME     U1 AT32
 '@S9S_MB_2U_LIB.S9S_MB_2U(SCH_1):PAGE72_I5@PURE_QUANTA.SOCKET4677_AZIF0045P001C01CS(CHIPS)':
 'VSS315': CDS_PINID='VSS315';
NODE_NAME     U1 AT34
 '@S9S_MB_2U_LIB.S9S_MB_2U(SCH_1):PAGE72_I5@PURE_QUANTA.SOCKET4677_AZIF0045P001C01CS(CHIPS)':
 'VSS316': CDS_PINID='VSS316';
NODE_NAME     U1 AT38
 '@S9S_MB_2U_LIB.S9S_MB_2U(SCH_1):PAGE72_I5@PURE_QUANTA.SOCKET4677_AZIF0045P001C01CS(CHIPS)':
 'VSS317': CDS_PINID='VSS317';
NODE_NAME     U1 AT4
 '@S9S_MB_2U_LIB.S9S_MB_2U(SCH_1):PAGE72_I5@PURE_QUANTA.SOCKET4677_AZIF0045P001C01CS(CHIPS)':
 'VSS318': CDS_PINID='VSS318';
NODE_NAME     U1 AT40
 '@S9S_MB_2U_LIB.S9S_MB_2U(SCH_1):PAGE72_I5@PURE_QUANTA.SOCKET4677_AZIF0045P001C01CS(CHIPS)':
 'VSS319': CDS_PINID='VSS319';
NODE_NAME     U1 AT44
 '@S9S_MB_2U_LIB.S9S_MB_2U(SCH_1):PAGE72_I5@PURE_QUANTA.SOCKET4677_AZIF0045P001C01CS(CHIPS)':
 'VSS320': CDS_PINID='VSS320';
NODE_NAME     U1 AT51
 '@S9S_MB_2U_LIB.S9S_MB_2U(SCH_1):PAGE72_I5@PURE_QUANTA.SOCKET4677_AZIF0045P001C01CS(CHIPS)':
 'VSS321': CDS_PINID='VSS321';
NODE_NAME     U1 AT53
 '@S9S_MB_2U_LIB.S9S_MB_2U(SCH_1):PAGE72_I5@PURE_QUANTA.SOCKET4677_AZIF0045P001C01CS(CHIPS)':
 'VSS322': CDS_PINID='VSS322';
NODE_NAME     U1 AT57
 '@S9S_MB_2U_LIB.S9S_MB_2U(SCH_1):PAGE72_I5@PURE_QUANTA.SOCKET4677_AZIF0045P001C01CS(CHIPS)':
 'VSS323': CDS_PINID='VSS323';
NODE_NAME     U1 AT59
 '@S9S_MB_2U_LIB.S9S_MB_2U(SCH_1):PAGE72_I5@PURE_QUANTA.SOCKET4677_AZIF0045P001C01CS(CHIPS)':
 'VSS324': CDS_PINID='VSS324';
NODE_NAME     U1 AT63
 '@S9S_MB_2U_LIB.S9S_MB_2U(SCH_1):PAGE72_I5@PURE_QUANTA.SOCKET4677_AZIF0045P001C01CS(CHIPS)':
 'VSS325': CDS_PINID='VSS325';
NODE_NAME     U1 AT65
 '@S9S_MB_2U_LIB.S9S_MB_2U(SCH_1):PAGE72_I5@PURE_QUANTA.SOCKET4677_AZIF0045P001C01CS(CHIPS)':
 'VSS326': CDS_PINID='VSS326';
NODE_NAME     U1 AT69
 '@S9S_MB_2U_LIB.S9S_MB_2U(SCH_1):PAGE72_I5@PURE_QUANTA.SOCKET4677_AZIF0045P001C01CS(CHIPS)':
 'VSS327': CDS_PINID='VSS327';
NODE_NAME     U1 AT71
 '@S9S_MB_2U_LIB.S9S_MB_2U(SCH_1):PAGE72_I5@PURE_QUANTA.SOCKET4677_AZIF0045P001C01CS(CHIPS)':
 'VSS328': CDS_PINID='VSS328';
NODE_NAME     U1 AT75
 '@S9S_MB_2U_LIB.S9S_MB_2U(SCH_1):PAGE72_I5@PURE_QUANTA.SOCKET4677_AZIF0045P001C01CS(CHIPS)':
 'VSS329': CDS_PINID='VSS329';
NODE_NAME     U1 AT77
 '@S9S_MB_2U_LIB.S9S_MB_2U(SCH_1):PAGE72_I5@PURE_QUANTA.SOCKET4677_AZIF0045P001C01CS(CHIPS)':
 'VSS330': CDS_PINID='VSS330';
NODE_NAME     U1 AT79
 '@S9S_MB_2U_LIB.S9S_MB_2U(SCH_1):PAGE72_I5@PURE_QUANTA.SOCKET4677_AZIF0045P001C01CS(CHIPS)':
 'VSS331': CDS_PINID='VSS331';
NODE_NAME     U1 AT8
 '@S9S_MB_2U_LIB.S9S_MB_2U(SCH_1):PAGE72_I5@PURE_QUANTA.SOCKET4677_AZIF0045P001C01CS(CHIPS)':
 'VSS332': CDS_PINID='VSS332';
NODE_NAME     U1 AU27
 '@S9S_MB_2U_LIB.S9S_MB_2U(SCH_1):PAGE72_I5@PURE_QUANTA.SOCKET4677_AZIF0045P001C01CS(CHIPS)':
 'VSS333': CDS_PINID='VSS333';
NODE_NAME     U1 AU31
 '@S9S_MB_2U_LIB.S9S_MB_2U(SCH_1):PAGE72_I5@PURE_QUANTA.SOCKET4677_AZIF0045P001C01CS(CHIPS)':
 'VSS334': CDS_PINID='VSS334';
NODE_NAME     U1 AU37
 '@S9S_MB_2U_LIB.S9S_MB_2U(SCH_1):PAGE72_I5@PURE_QUANTA.SOCKET4677_AZIF0045P001C01CS(CHIPS)':
 'VSS335': CDS_PINID='VSS335';
NODE_NAME     U1 AU39
 '@S9S_MB_2U_LIB.S9S_MB_2U(SCH_1):PAGE72_I5@PURE_QUANTA.SOCKET4677_AZIF0045P001C01CS(CHIPS)':
 'VSS336': CDS_PINID='VSS336';
NODE_NAME     U1 AU41
 '@S9S_MB_2U_LIB.S9S_MB_2U(SCH_1):PAGE72_I5@PURE_QUANTA.SOCKET4677_AZIF0045P001C01CS(CHIPS)':
 'VSS337': CDS_PINID='VSS337';
NODE_NAME     U1 AU45
 '@S9S_MB_2U_LIB.S9S_MB_2U(SCH_1):PAGE72_I5@PURE_QUANTA.SOCKET4677_AZIF0045P001C01CS(CHIPS)':
 'VSS338': CDS_PINID='VSS338';
NODE_NAME     U1 AU48
 '@S9S_MB_2U_LIB.S9S_MB_2U(SCH_1):PAGE72_I5@PURE_QUANTA.SOCKET4677_AZIF0045P001C01CS(CHIPS)':
 'VSS339': CDS_PINID='VSS339';
NODE_NAME     U1 AU70
 '@S9S_MB_2U_LIB.S9S_MB_2U(SCH_1):PAGE72_I5@PURE_QUANTA.SOCKET4677_AZIF0045P001C01CS(CHIPS)':
 'VSS340': CDS_PINID='VSS340';
NODE_NAME     U1 AU72
 '@S9S_MB_2U_LIB.S9S_MB_2U(SCH_1):PAGE72_I5@PURE_QUANTA.SOCKET4677_AZIF0045P001C01CS(CHIPS)':
 'VSS341': CDS_PINID='VSS341';
NODE_NAME     U1 AU74
 '@S9S_MB_2U_LIB.S9S_MB_2U(SCH_1):PAGE72_I5@PURE_QUANTA.SOCKET4677_AZIF0045P001C01CS(CHIPS)':
 'VSS342': CDS_PINID='VSS342';
NODE_NAME     U1 AU76
 '@S9S_MB_2U_LIB.S9S_MB_2U(SCH_1):PAGE72_I5@PURE_QUANTA.SOCKET4677_AZIF0045P001C01CS(CHIPS)':
 'VSS343': CDS_PINID='VSS343';
NODE_NAME     U1 AU80
 '@S9S_MB_2U_LIB.S9S_MB_2U(SCH_1):PAGE72_I5@PURE_QUANTA.SOCKET4677_AZIF0045P001C01CS(CHIPS)':
 'VSS344': CDS_PINID='VSS344';
NODE_NAME     U1 AU84
 '@S9S_MB_2U_LIB.S9S_MB_2U(SCH_1):PAGE72_I5@PURE_QUANTA.SOCKET4677_AZIF0045P001C01CS(CHIPS)':
 'VSS345': CDS_PINID='VSS345';
NODE_NAME     U1 AU88
 '@S9S_MB_2U_LIB.S9S_MB_2U(SCH_1):PAGE72_I5@PURE_QUANTA.SOCKET4677_AZIF0045P001C01CS(CHIPS)':
 'VSS346': CDS_PINID='VSS346';
NODE_NAME     U1 AV12
 '@S9S_MB_2U_LIB.S9S_MB_2U(SCH_1):PAGE72_I5@PURE_QUANTA.SOCKET4677_AZIF0045P001C01CS(CHIPS)':
 'VSS347': CDS_PINID='VSS347';
NODE_NAME     U1 AV16
 '@S9S_MB_2U_LIB.S9S_MB_2U(SCH_1):PAGE72_I5@PURE_QUANTA.SOCKET4677_AZIF0045P001C01CS(CHIPS)':
 'VSS348': CDS_PINID='VSS348';
NODE_NAME     U1 AV4
 '@S9S_MB_2U_LIB.S9S_MB_2U(SCH_1):PAGE72_I5@PURE_QUANTA.SOCKET4677_AZIF0045P001C01CS(CHIPS)':
 'VSS349': CDS_PINID='VSS349';
NODE_NAME     U1 AV77
 '@S9S_MB_2U_LIB.S9S_MB_2U(SCH_1):PAGE72_I5@PURE_QUANTA.SOCKET4677_AZIF0045P001C01CS(CHIPS)':
 'VSS350': CDS_PINID='VSS350';
NODE_NAME     U1 AV8
 '@S9S_MB_2U_LIB.S9S_MB_2U(SCH_1):PAGE72_I5@PURE_QUANTA.SOCKET4677_AZIF0045P001C01CS(CHIPS)':
 'VSS351': CDS_PINID='VSS351';
NODE_NAME     U1 AV87
 '@S9S_MB_2U_LIB.S9S_MB_2U(SCH_1):PAGE72_I5@PURE_QUANTA.SOCKET4677_AZIF0045P001C01CS(CHIPS)':
 'VSS352': CDS_PINID='VSS352';
NODE_NAME     U1 AV91
 '@S9S_MB_2U_LIB.S9S_MB_2U(SCH_1):PAGE72_I5@PURE_QUANTA.SOCKET4677_AZIF0045P001C01CS(CHIPS)':
 'VSS353': CDS_PINID='VSS353';
NODE_NAME     U1 AW1
 '@S9S_MB_2U_LIB.S9S_MB_2U(SCH_1):PAGE72_I5@PURE_QUANTA.SOCKET4677_AZIF0045P001C01CS(CHIPS)':
 'VSS354': CDS_PINID='VSS354';
NODE_NAME     U1 AW13
 '@S9S_MB_2U_LIB.S9S_MB_2U(SCH_1):PAGE72_I5@PURE_QUANTA.SOCKET4677_AZIF0045P001C01CS(CHIPS)':
 'VSS355': CDS_PINID='VSS355';
NODE_NAME     U1 AW5
 '@S9S_MB_2U_LIB.S9S_MB_2U(SCH_1):PAGE72_I5@PURE_QUANTA.SOCKET4677_AZIF0045P001C01CS(CHIPS)':
 'VSS359': CDS_PINID='VSS359';
NODE_NAME     U1 AW9
 '@S9S_MB_2U_LIB.S9S_MB_2U(SCH_1):PAGE72_I5@PURE_QUANTA.SOCKET4677_AZIF0045P001C01CS(CHIPS)':
 'VSS368': CDS_PINID='VSS368';
NODE_NAME     U1 AA82
 '@S9S_MB_2U_LIB.S9S_MB_2U(SCH_1):PAGE72_I8@PURE_QUANTA.SOCKET4677_AZIF0045P001C01CS(CHIPS)':
 'VSS38': CDS_PINID='VSS38';
NODE_NAME     U1 AA84
 '@S9S_MB_2U_LIB.S9S_MB_2U(SCH_1):PAGE72_I8@PURE_QUANTA.SOCKET4677_AZIF0045P001C01CS(CHIPS)':
 'VSS39': CDS_PINID='VSS39';
NODE_NAME     U1 AA88
 '@S9S_MB_2U_LIB.S9S_MB_2U(SCH_1):PAGE72_I8@PURE_QUANTA.SOCKET4677_AZIF0045P001C01CS(CHIPS)':
 'VSS40': CDS_PINID='VSS40';
NODE_NAME     U1 AB12
 '@S9S_MB_2U_LIB.S9S_MB_2U(SCH_1):PAGE72_I8@PURE_QUANTA.SOCKET4677_AZIF0045P001C01CS(CHIPS)':
 'VSS41': CDS_PINID='VSS41';
NODE_NAME     U1 AB16
 '@S9S_MB_2U_LIB.S9S_MB_2U(SCH_1):PAGE72_I8@PURE_QUANTA.SOCKET4677_AZIF0045P001C01CS(CHIPS)':
 'VSS42': CDS_PINID='VSS42';
NODE_NAME     U1 AB20
 '@S9S_MB_2U_LIB.S9S_MB_2U(SCH_1):PAGE72_I8@PURE_QUANTA.SOCKET4677_AZIF0045P001C01CS(CHIPS)':
 'VSS43': CDS_PINID='VSS43';
NODE_NAME     U1 AB22
 '@S9S_MB_2U_LIB.S9S_MB_2U(SCH_1):PAGE72_I8@PURE_QUANTA.SOCKET4677_AZIF0045P001C01CS(CHIPS)':
 'VSS44': CDS_PINID='VSS44';
NODE_NAME     U1 AB26
 '@S9S_MB_2U_LIB.S9S_MB_2U(SCH_1):PAGE72_I8@PURE_QUANTA.SOCKET4677_AZIF0045P001C01CS(CHIPS)':
 'VSS45': CDS_PINID='VSS45';
NODE_NAME     U1 AB28
 '@S9S_MB_2U_LIB.S9S_MB_2U(SCH_1):PAGE72_I8@PURE_QUANTA.SOCKET4677_AZIF0045P001C01CS(CHIPS)':
 'VSS46': CDS_PINID='VSS46';
NODE_NAME     U1 AB32
 '@S9S_MB_2U_LIB.S9S_MB_2U(SCH_1):PAGE72_I8@PURE_QUANTA.SOCKET4677_AZIF0045P001C01CS(CHIPS)':
 'VSS47': CDS_PINID='VSS47';
NODE_NAME     U1 AB34
 '@S9S_MB_2U_LIB.S9S_MB_2U(SCH_1):PAGE72_I8@PURE_QUANTA.SOCKET4677_AZIF0045P001C01CS(CHIPS)':
 'VSS48': CDS_PINID='VSS48';
NODE_NAME     U1 AB38
 '@S9S_MB_2U_LIB.S9S_MB_2U(SCH_1):PAGE72_I8@PURE_QUANTA.SOCKET4677_AZIF0045P001C01CS(CHIPS)':
 'VSS49': CDS_PINID='VSS49';
NODE_NAME     U1 AB4
 '@S9S_MB_2U_LIB.S9S_MB_2U(SCH_1):PAGE72_I8@PURE_QUANTA.SOCKET4677_AZIF0045P001C01CS(CHIPS)':
 'VSS50': CDS_PINID='VSS50';
NODE_NAME     U1 AB40
 '@S9S_MB_2U_LIB.S9S_MB_2U(SCH_1):PAGE72_I8@PURE_QUANTA.SOCKET4677_AZIF0045P001C01CS(CHIPS)':
 'VSS51': CDS_PINID='VSS51';
NODE_NAME     U1 AB44
 '@S9S_MB_2U_LIB.S9S_MB_2U(SCH_1):PAGE72_I8@PURE_QUANTA.SOCKET4677_AZIF0045P001C01CS(CHIPS)':
 'VSS52': CDS_PINID='VSS52';
NODE_NAME     U1 AB47
 '@S9S_MB_2U_LIB.S9S_MB_2U(SCH_1):PAGE72_I8@PURE_QUANTA.SOCKET4677_AZIF0045P001C01CS(CHIPS)':
 'VSS53': CDS_PINID='VSS53';
NODE_NAME     U1 AB51
 '@S9S_MB_2U_LIB.S9S_MB_2U(SCH_1):PAGE72_I8@PURE_QUANTA.SOCKET4677_AZIF0045P001C01CS(CHIPS)':
 'VSS54': CDS_PINID='VSS54';
NODE_NAME     U1 AB53
 '@S9S_MB_2U_LIB.S9S_MB_2U(SCH_1):PAGE72_I8@PURE_QUANTA.SOCKET4677_AZIF0045P001C01CS(CHIPS)':
 'VSS55': CDS_PINID='VSS55';
NODE_NAME     U1 AB57
 '@S9S_MB_2U_LIB.S9S_MB_2U(SCH_1):PAGE72_I8@PURE_QUANTA.SOCKET4677_AZIF0045P001C01CS(CHIPS)':
 'VSS56': CDS_PINID='VSS56';
NODE_NAME     U1 AB59
 '@S9S_MB_2U_LIB.S9S_MB_2U(SCH_1):PAGE72_I8@PURE_QUANTA.SOCKET4677_AZIF0045P001C01CS(CHIPS)':
 'VSS57': CDS_PINID='VSS57';
NODE_NAME     U1 AB63
 '@S9S_MB_2U_LIB.S9S_MB_2U(SCH_1):PAGE72_I8@PURE_QUANTA.SOCKET4677_AZIF0045P001C01CS(CHIPS)':
 'VSS58': CDS_PINID='VSS58';
NODE_NAME     U1 AB65
 '@S9S_MB_2U_LIB.S9S_MB_2U(SCH_1):PAGE72_I8@PURE_QUANTA.SOCKET4677_AZIF0045P001C01CS(CHIPS)':
 'VSS59': CDS_PINID='VSS59';
NODE_NAME     U1 AB69
 '@S9S_MB_2U_LIB.S9S_MB_2U(SCH_1):PAGE72_I8@PURE_QUANTA.SOCKET4677_AZIF0045P001C01CS(CHIPS)':
 'VSS60': CDS_PINID='VSS60';
NODE_NAME     U1 AB71
 '@S9S_MB_2U_LIB.S9S_MB_2U(SCH_1):PAGE72_I8@PURE_QUANTA.SOCKET4677_AZIF0045P001C01CS(CHIPS)':
 'VSS61': CDS_PINID='VSS61';
NODE_NAME     U1 AB75
 '@S9S_MB_2U_LIB.S9S_MB_2U(SCH_1):PAGE72_I8@PURE_QUANTA.SOCKET4677_AZIF0045P001C01CS(CHIPS)':
 'VSS62': CDS_PINID='VSS62';
NODE_NAME     U1 AB77
 '@S9S_MB_2U_LIB.S9S_MB_2U(SCH_1):PAGE72_I8@PURE_QUANTA.SOCKET4677_AZIF0045P001C01CS(CHIPS)':
 'VSS63': CDS_PINID='VSS63';
NODE_NAME     U1 AB79
 '@S9S_MB_2U_LIB.S9S_MB_2U(SCH_1):PAGE72_I8@PURE_QUANTA.SOCKET4677_AZIF0045P001C01CS(CHIPS)':
 'VSS64': CDS_PINID='VSS64';
NODE_NAME     U1 AB8
 '@S9S_MB_2U_LIB.S9S_MB_2U(SCH_1):PAGE72_I8@PURE_QUANTA.SOCKET4677_AZIF0045P001C01CS(CHIPS)':
 'VSS65': CDS_PINID='VSS65';
NODE_NAME     U1 AB81
 '@S9S_MB_2U_LIB.S9S_MB_2U(SCH_1):PAGE72_I8@PURE_QUANTA.SOCKET4677_AZIF0045P001C01CS(CHIPS)':
 'VSS66': CDS_PINID='VSS66';
NODE_NAME     U1 AB83
 '@S9S_MB_2U_LIB.S9S_MB_2U(SCH_1):PAGE72_I8@PURE_QUANTA.SOCKET4677_AZIF0045P001C01CS(CHIPS)':
 'VSS67': CDS_PINID='VSS67';
NODE_NAME     U1 AB87
 '@S9S_MB_2U_LIB.S9S_MB_2U(SCH_1):PAGE72_I8@PURE_QUANTA.SOCKET4677_AZIF0045P001C01CS(CHIPS)':
 'VSS68': CDS_PINID='VSS68';
NODE_NAME     U1 AB91
 '@S9S_MB_2U_LIB.S9S_MB_2U(SCH_1):PAGE72_I8@PURE_QUANTA.SOCKET4677_AZIF0045P001C01CS(CHIPS)':
 'VSS69': CDS_PINID='VSS69';
NODE_NAME     U1 AC1
 '@S9S_MB_2U_LIB.S9S_MB_2U(SCH_1):PAGE72_I8@PURE_QUANTA.SOCKET4677_AZIF0045P001C01CS(CHIPS)':
 'VSS70': CDS_PINID='VSS70';
NODE_NAME     U1 AC13
 '@S9S_MB_2U_LIB.S9S_MB_2U(SCH_1):PAGE72_I8@PURE_QUANTA.SOCKET4677_AZIF0045P001C01CS(CHIPS)':
 'VSS71': CDS_PINID='VSS71';
NODE_NAME     U1 AC21
 '@S9S_MB_2U_LIB.S9S_MB_2U(SCH_1):PAGE72_I8@PURE_QUANTA.SOCKET4677_AZIF0045P001C01CS(CHIPS)':
 'VSS72': CDS_PINID='VSS72';
NODE_NAME     U1 AC27
 '@S9S_MB_2U_LIB.S9S_MB_2U(SCH_1):PAGE72_I8@PURE_QUANTA.SOCKET4677_AZIF0045P001C01CS(CHIPS)':
 'VSS73': CDS_PINID='VSS73';
NODE_NAME     U1 AC33
 '@S9S_MB_2U_LIB.S9S_MB_2U(SCH_1):PAGE72_I8@PURE_QUANTA.SOCKET4677_AZIF0045P001C01CS(CHIPS)':
 'VSS74': CDS_PINID='VSS74';
NODE_NAME     U1 AC39
 '@S9S_MB_2U_LIB.S9S_MB_2U(SCH_1):PAGE72_I8@PURE_QUANTA.SOCKET4677_AZIF0045P001C01CS(CHIPS)':
 'VSS75': CDS_PINID='VSS75';
NODE_NAME     U1 AC45
 '@S9S_MB_2U_LIB.S9S_MB_2U(SCH_1):PAGE72_I8@PURE_QUANTA.SOCKET4677_AZIF0045P001C01CS(CHIPS)':
 'VSS76': CDS_PINID='VSS76';
NODE_NAME     U1 AC5
 '@S9S_MB_2U_LIB.S9S_MB_2U(SCH_1):PAGE72_I8@PURE_QUANTA.SOCKET4677_AZIF0045P001C01CS(CHIPS)':
 'VSS77': CDS_PINID='VSS77';
NODE_NAME     U1 AC52
 '@S9S_MB_2U_LIB.S9S_MB_2U(SCH_1):PAGE72_I8@PURE_QUANTA.SOCKET4677_AZIF0045P001C01CS(CHIPS)':
 'VSS78': CDS_PINID='VSS78';
NODE_NAME     U1 AC58
 '@S9S_MB_2U_LIB.S9S_MB_2U(SCH_1):PAGE72_I8@PURE_QUANTA.SOCKET4677_AZIF0045P001C01CS(CHIPS)':
 'VSS79': CDS_PINID='VSS79';
NODE_NAME     U1 AC64
 '@S9S_MB_2U_LIB.S9S_MB_2U(SCH_1):PAGE72_I8@PURE_QUANTA.SOCKET4677_AZIF0045P001C01CS(CHIPS)':
 'VSS80': CDS_PINID='VSS80';
NODE_NAME     U1 AC70
 '@S9S_MB_2U_LIB.S9S_MB_2U(SCH_1):PAGE72_I8@PURE_QUANTA.SOCKET4677_AZIF0045P001C01CS(CHIPS)':
 'VSS81': CDS_PINID='VSS81';
NODE_NAME     U1 AC76
 '@S9S_MB_2U_LIB.S9S_MB_2U(SCH_1):PAGE72_I8@PURE_QUANTA.SOCKET4677_AZIF0045P001C01CS(CHIPS)':
 'VSS82': CDS_PINID='VSS82';
NODE_NAME     U1 AC84
 '@S9S_MB_2U_LIB.S9S_MB_2U(SCH_1):PAGE72_I8@PURE_QUANTA.SOCKET4677_AZIF0045P001C01CS(CHIPS)':
 'VSS83': CDS_PINID='VSS83';
NODE_NAME     U1 AC88
 '@S9S_MB_2U_LIB.S9S_MB_2U(SCH_1):PAGE72_I8@PURE_QUANTA.SOCKET4677_AZIF0045P001C01CS(CHIPS)':
 'VSS84': CDS_PINID='VSS84';
NODE_NAME     U1 AC9
 '@S9S_MB_2U_LIB.S9S_MB_2U(SCH_1):PAGE72_I8@PURE_QUANTA.SOCKET4677_AZIF0045P001C01CS(CHIPS)':
 'VSS85': CDS_PINID='VSS85';
NODE_NAME     U1 AD12
 '@S9S_MB_2U_LIB.S9S_MB_2U(SCH_1):PAGE72_I8@PURE_QUANTA.SOCKET4677_AZIF0045P001C01CS(CHIPS)':
 'VSS86': CDS_PINID='VSS86';
NODE_NAME     U1 AD16
 '@S9S_MB_2U_LIB.S9S_MB_2U(SCH_1):PAGE72_I8@PURE_QUANTA.SOCKET4677_AZIF0045P001C01CS(CHIPS)':
 'VSS87': CDS_PINID='VSS87';
NODE_NAME     U1 AD4
 '@S9S_MB_2U_LIB.S9S_MB_2U(SCH_1):PAGE72_I8@PURE_QUANTA.SOCKET4677_AZIF0045P001C01CS(CHIPS)':
 'VSS88': CDS_PINID='VSS88';
NODE_NAME     U1 AD42
 '@S9S_MB_2U_LIB.S9S_MB_2U(SCH_1):PAGE72_I8@PURE_QUANTA.SOCKET4677_AZIF0045P001C01CS(CHIPS)':
 'VSS89': CDS_PINID='VSS89';
NODE_NAME     U1 AD79
 '@S9S_MB_2U_LIB.S9S_MB_2U(SCH_1):PAGE72_I8@PURE_QUANTA.SOCKET4677_AZIF0045P001C01CS(CHIPS)':
 'VSS90': CDS_PINID='VSS90';
NODE_NAME     U1 AD8
 '@S9S_MB_2U_LIB.S9S_MB_2U(SCH_1):PAGE72_I8@PURE_QUANTA.SOCKET4677_AZIF0045P001C01CS(CHIPS)':
 'VSS91': CDS_PINID='VSS91';
NODE_NAME     U1 AD83
 '@S9S_MB_2U_LIB.S9S_MB_2U(SCH_1):PAGE72_I8@PURE_QUANTA.SOCKET4677_AZIF0045P001C01CS(CHIPS)':
 'VSS92': CDS_PINID='VSS92';
NODE_NAME     U1 AE17
 '@S9S_MB_2U_LIB.S9S_MB_2U(SCH_1):PAGE72_I8@PURE_QUANTA.SOCKET4677_AZIF0045P001C01CS(CHIPS)':
 'VSS93': CDS_PINID='VSS93';
NODE_NAME     U1 AE19
 '@S9S_MB_2U_LIB.S9S_MB_2U(SCH_1):PAGE72_I8@PURE_QUANTA.SOCKET4677_AZIF0045P001C01CS(CHIPS)':
 'VSS94': CDS_PINID='VSS94';
NODE_NAME     U1 AE21
 '@S9S_MB_2U_LIB.S9S_MB_2U(SCH_1):PAGE72_I8@PURE_QUANTA.SOCKET4677_AZIF0045P001C01CS(CHIPS)':
 'VSS95': CDS_PINID='VSS95';
NODE_NAME     U1 AE23
 '@S9S_MB_2U_LIB.S9S_MB_2U(SCH_1):PAGE72_I8@PURE_QUANTA.SOCKET4677_AZIF0045P001C01CS(CHIPS)':
 'VSS96': CDS_PINID='VSS96';
NODE_NAME     U1 AE25
 '@S9S_MB_2U_LIB.S9S_MB_2U(SCH_1):PAGE72_I8@PURE_QUANTA.SOCKET4677_AZIF0045P001C01CS(CHIPS)':
 'VSS97': CDS_PINID='VSS97';
NODE_NAME     U1 AE27
 '@S9S_MB_2U_LIB.S9S_MB_2U(SCH_1):PAGE72_I8@PURE_QUANTA.SOCKET4677_AZIF0045P001C01CS(CHIPS)':
 'VSS98': CDS_PINID='VSS98';
NODE_NAME     U1 AE29
 '@S9S_MB_2U_LIB.S9S_MB_2U(SCH_1):PAGE72_I8@PURE_QUANTA.SOCKET4677_AZIF0045P001C01CS(CHIPS)':
 'VSS99': CDS_PINID='VSS99';
NODE_NAME     U1 AE31
 '@S9S_MB_2U_LIB.S9S_MB_2U(SCH_1):PAGE72_I8@PURE_QUANTA.SOCKET4677_AZIF0045P001C01CS(CHIPS)':
 'VSS100': CDS_PINID='VSS100';
NODE_NAME     U1 AE33
 '@S9S_MB_2U_LIB.S9S_MB_2U(SCH_1):PAGE72_I8@PURE_QUANTA.SOCKET4677_AZIF0045P001C01CS(CHIPS)':
 'VSS101': CDS_PINID='VSS101';
NODE_NAME     U1 AE35
 '@S9S_MB_2U_LIB.S9S_MB_2U(SCH_1):PAGE72_I8@PURE_QUANTA.SOCKET4677_AZIF0045P001C01CS(CHIPS)':
 'VSS102': CDS_PINID='VSS102';
NODE_NAME     U1 AE37
 '@S9S_MB_2U_LIB.S9S_MB_2U(SCH_1):PAGE72_I8@PURE_QUANTA.SOCKET4677_AZIF0045P001C01CS(CHIPS)':
 'VSS103': CDS_PINID='VSS103';
NODE_NAME     U1 AE39
 '@S9S_MB_2U_LIB.S9S_MB_2U(SCH_1):PAGE72_I8@PURE_QUANTA.SOCKET4677_AZIF0045P001C01CS(CHIPS)':
 'VSS104': CDS_PINID='VSS104';
NODE_NAME     U1 AE41
 '@S9S_MB_2U_LIB.S9S_MB_2U(SCH_1):PAGE72_I8@PURE_QUANTA.SOCKET4677_AZIF0045P001C01CS(CHIPS)':
 'VSS105': CDS_PINID='VSS105';
NODE_NAME     U1 AE43
 '@S9S_MB_2U_LIB.S9S_MB_2U(SCH_1):PAGE72_I8@PURE_QUANTA.SOCKET4677_AZIF0045P001C01CS(CHIPS)':
 'VSS106': CDS_PINID='VSS106';
NODE_NAME     U1 AE45
 '@S9S_MB_2U_LIB.S9S_MB_2U(SCH_1):PAGE72_I8@PURE_QUANTA.SOCKET4677_AZIF0045P001C01CS(CHIPS)':
 'VSS107': CDS_PINID='VSS107';
NODE_NAME     U1 AE48
 '@S9S_MB_2U_LIB.S9S_MB_2U(SCH_1):PAGE72_I8@PURE_QUANTA.SOCKET4677_AZIF0045P001C01CS(CHIPS)':
 'VSS108': CDS_PINID='VSS108';
NODE_NAME     U1 AE50
 '@S9S_MB_2U_LIB.S9S_MB_2U(SCH_1):PAGE72_I8@PURE_QUANTA.SOCKET4677_AZIF0045P001C01CS(CHIPS)':
 'VSS109': CDS_PINID='VSS109';
NODE_NAME     U1 AE52
 '@S9S_MB_2U_LIB.S9S_MB_2U(SCH_1):PAGE72_I8@PURE_QUANTA.SOCKET4677_AZIF0045P001C01CS(CHIPS)':
 'VSS110': CDS_PINID='VSS110';
NODE_NAME     U1 AE54
 '@S9S_MB_2U_LIB.S9S_MB_2U(SCH_1):PAGE72_I8@PURE_QUANTA.SOCKET4677_AZIF0045P001C01CS(CHIPS)':
 'VSS111': CDS_PINID='VSS111';
NODE_NAME     U1 AE56
 '@S9S_MB_2U_LIB.S9S_MB_2U(SCH_1):PAGE72_I8@PURE_QUANTA.SOCKET4677_AZIF0045P001C01CS(CHIPS)':
 'VSS112': CDS_PINID='VSS112';
NODE_NAME     U1 AE58
 '@S9S_MB_2U_LIB.S9S_MB_2U(SCH_1):PAGE72_I8@PURE_QUANTA.SOCKET4677_AZIF0045P001C01CS(CHIPS)':
 'VSS113': CDS_PINID='VSS113';
NODE_NAME     U1 AE60
 '@S9S_MB_2U_LIB.S9S_MB_2U(SCH_1):PAGE72_I8@PURE_QUANTA.SOCKET4677_AZIF0045P001C01CS(CHIPS)':
 'VSS114': CDS_PINID='VSS114';
NODE_NAME     U1 AE62
 '@S9S_MB_2U_LIB.S9S_MB_2U(SCH_1):PAGE72_I8@PURE_QUANTA.SOCKET4677_AZIF0045P001C01CS(CHIPS)':
 'VSS115': CDS_PINID='VSS115';
NODE_NAME     U1 AE64
 '@S9S_MB_2U_LIB.S9S_MB_2U(SCH_1):PAGE72_I8@PURE_QUANTA.SOCKET4677_AZIF0045P001C01CS(CHIPS)':
 'VSS116': CDS_PINID='VSS116';
NODE_NAME     U1 AE66
 '@S9S_MB_2U_LIB.S9S_MB_2U(SCH_1):PAGE72_I8@PURE_QUANTA.SOCKET4677_AZIF0045P001C01CS(CHIPS)':
 'VSS117': CDS_PINID='VSS117';
NODE_NAME     U1 AE68
 '@S9S_MB_2U_LIB.S9S_MB_2U(SCH_1):PAGE72_I8@PURE_QUANTA.SOCKET4677_AZIF0045P001C01CS(CHIPS)':
 'VSS118': CDS_PINID='VSS118';
NODE_NAME     U1 AE70
 '@S9S_MB_2U_LIB.S9S_MB_2U(SCH_1):PAGE72_I8@PURE_QUANTA.SOCKET4677_AZIF0045P001C01CS(CHIPS)':
 'VSS119': CDS_PINID='VSS119';
NODE_NAME     U1 AE72
 '@S9S_MB_2U_LIB.S9S_MB_2U(SCH_1):PAGE72_I8@PURE_QUANTA.SOCKET4677_AZIF0045P001C01CS(CHIPS)':
 'VSS120': CDS_PINID='VSS120';
NODE_NAME     U1 AE74
 '@S9S_MB_2U_LIB.S9S_MB_2U(SCH_1):PAGE72_I8@PURE_QUANTA.SOCKET4677_AZIF0045P001C01CS(CHIPS)':
 'VSS121': CDS_PINID='VSS121';
NODE_NAME     U1 AE76
 '@S9S_MB_2U_LIB.S9S_MB_2U(SCH_1):PAGE72_I8@PURE_QUANTA.SOCKET4677_AZIF0045P001C01CS(CHIPS)':
 'VSS122': CDS_PINID='VSS122';
NODE_NAME     U1 AE78
 '@S9S_MB_2U_LIB.S9S_MB_2U(SCH_1):PAGE72_I8@PURE_QUANTA.SOCKET4677_AZIF0045P001C01CS(CHIPS)':
 'VSS123': CDS_PINID='VSS123';
NODE_NAME     U1 AE84
 '@S9S_MB_2U_LIB.S9S_MB_2U(SCH_1):PAGE72_I8@PURE_QUANTA.SOCKET4677_AZIF0045P001C01CS(CHIPS)':
 'VSS124': CDS_PINID='VSS124';
NODE_NAME     U1 AE88
 '@S9S_MB_2U_LIB.S9S_MB_2U(SCH_1):PAGE72_I8@PURE_QUANTA.SOCKET4677_AZIF0045P001C01CS(CHIPS)':
 'VSS125': CDS_PINID='VSS125';
NODE_NAME     U1 AF12
 '@S9S_MB_2U_LIB.S9S_MB_2U(SCH_1):PAGE72_I8@PURE_QUANTA.SOCKET4677_AZIF0045P001C01CS(CHIPS)':
 'VSS126': CDS_PINID='VSS126';
NODE_NAME     U1 AF16
 '@S9S_MB_2U_LIB.S9S_MB_2U(SCH_1):PAGE72_I8@PURE_QUANTA.SOCKET4677_AZIF0045P001C01CS(CHIPS)':
 'VSS127': CDS_PINID='VSS127';
NODE_NAME     U1 AF4
 '@S9S_MB_2U_LIB.S9S_MB_2U(SCH_1):PAGE72_I8@PURE_QUANTA.SOCKET4677_AZIF0045P001C01CS(CHIPS)':
 'VSS128': CDS_PINID='VSS128';
NODE_NAME     U1 AF42
 '@S9S_MB_2U_LIB.S9S_MB_2U(SCH_1):PAGE72_I8@PURE_QUANTA.SOCKET4677_AZIF0045P001C01CS(CHIPS)':
 'VSS129': CDS_PINID='VSS129';
NODE_NAME     U1 AF8
 '@S9S_MB_2U_LIB.S9S_MB_2U(SCH_1):PAGE72_I8@PURE_QUANTA.SOCKET4677_AZIF0045P001C01CS(CHIPS)':
 'VSS130': CDS_PINID='VSS130';
NODE_NAME     U1 AF81
 '@S9S_MB_2U_LIB.S9S_MB_2U(SCH_1):PAGE72_I8@PURE_QUANTA.SOCKET4677_AZIF0045P001C01CS(CHIPS)':
 'VSS131': CDS_PINID='VSS131';
NODE_NAME     U1 AF87
 '@S9S_MB_2U_LIB.S9S_MB_2U(SCH_1):PAGE72_I8@PURE_QUANTA.SOCKET4677_AZIF0045P001C01CS(CHIPS)':
 'VSS132': CDS_PINID='VSS132';
NODE_NAME     U1 AF91
 '@S9S_MB_2U_LIB.S9S_MB_2U(SCH_1):PAGE72_I8@PURE_QUANTA.SOCKET4677_AZIF0045P001C01CS(CHIPS)':
 'VSS133': CDS_PINID='VSS133';
NODE_NAME     U1 AG1
 '@S9S_MB_2U_LIB.S9S_MB_2U(SCH_1):PAGE72_I8@PURE_QUANTA.SOCKET4677_AZIF0045P001C01CS(CHIPS)':
 'VSS134': CDS_PINID='VSS134';
NODE_NAME     U1 AG13
 '@S9S_MB_2U_LIB.S9S_MB_2U(SCH_1):PAGE72_I8@PURE_QUANTA.SOCKET4677_AZIF0045P001C01CS(CHIPS)':
 'VSS135': CDS_PINID='VSS135';
NODE_NAME     U1 AG21
 '@S9S_MB_2U_LIB.S9S_MB_2U(SCH_1):PAGE72_I8@PURE_QUANTA.SOCKET4677_AZIF0045P001C01CS(CHIPS)':
 'VSS136': CDS_PINID='VSS136';
NODE_NAME     U1 AG27
 '@S9S_MB_2U_LIB.S9S_MB_2U(SCH_1):PAGE72_I8@PURE_QUANTA.SOCKET4677_AZIF0045P001C01CS(CHIPS)':
 'VSS137': CDS_PINID='VSS137';
NODE_NAME     U1 AG33
 '@S9S_MB_2U_LIB.S9S_MB_2U(SCH_1):PAGE72_I8@PURE_QUANTA.SOCKET4677_AZIF0045P001C01CS(CHIPS)':
 'VSS138': CDS_PINID='VSS138';
NODE_NAME     U1 AG39
 '@S9S_MB_2U_LIB.S9S_MB_2U(SCH_1):PAGE72_I8@PURE_QUANTA.SOCKET4677_AZIF0045P001C01CS(CHIPS)':
 'VSS139': CDS_PINID='VSS139';
NODE_NAME     U1 AG45
 '@S9S_MB_2U_LIB.S9S_MB_2U(SCH_1):PAGE72_I8@PURE_QUANTA.SOCKET4677_AZIF0045P001C01CS(CHIPS)':
 'VSS140': CDS_PINID='VSS140';
NODE_NAME     U1 AG5
 '@S9S_MB_2U_LIB.S9S_MB_2U(SCH_1):PAGE72_I8@PURE_QUANTA.SOCKET4677_AZIF0045P001C01CS(CHIPS)':
 'VSS141': CDS_PINID='VSS141';
NODE_NAME     U1 AG52
 '@S9S_MB_2U_LIB.S9S_MB_2U(SCH_1):PAGE72_I8@PURE_QUANTA.SOCKET4677_AZIF0045P001C01CS(CHIPS)':
 'VSS142': CDS_PINID='VSS142';
NODE_NAME     U1 AG58
 '@S9S_MB_2U_LIB.S9S_MB_2U(SCH_1):PAGE72_I8@PURE_QUANTA.SOCKET4677_AZIF0045P001C01CS(CHIPS)':
 'VSS143': CDS_PINID='VSS143';
NODE_NAME     U1 AG64
 '@S9S_MB_2U_LIB.S9S_MB_2U(SCH_1):PAGE72_I8@PURE_QUANTA.SOCKET4677_AZIF0045P001C01CS(CHIPS)':
 'VSS144': CDS_PINID='VSS144';
NODE_NAME     U1 AG70
 '@S9S_MB_2U_LIB.S9S_MB_2U(SCH_1):PAGE72_I8@PURE_QUANTA.SOCKET4677_AZIF0045P001C01CS(CHIPS)':
 'VSS145': CDS_PINID='VSS145';
NODE_NAME     U1 AG76
 '@S9S_MB_2U_LIB.S9S_MB_2U(SCH_1):PAGE72_I8@PURE_QUANTA.SOCKET4677_AZIF0045P001C01CS(CHIPS)':
 'VSS146': CDS_PINID='VSS146';
NODE_NAME     U1 AG84
 '@S9S_MB_2U_LIB.S9S_MB_2U(SCH_1):PAGE72_I8@PURE_QUANTA.SOCKET4677_AZIF0045P001C01CS(CHIPS)':
 'VSS147': CDS_PINID='VSS147';
NODE_NAME     U1 AG88
 '@S9S_MB_2U_LIB.S9S_MB_2U(SCH_1):PAGE72_I8@PURE_QUANTA.SOCKET4677_AZIF0045P001C01CS(CHIPS)':
 'VSS148': CDS_PINID='VSS148';
NODE_NAME     U1 AG9
 '@S9S_MB_2U_LIB.S9S_MB_2U(SCH_1):PAGE72_I8@PURE_QUANTA.SOCKET4677_AZIF0045P001C01CS(CHIPS)':
 'VSS149': CDS_PINID='VSS149';
NODE_NAME     U1 AH12
 '@S9S_MB_2U_LIB.S9S_MB_2U(SCH_1):PAGE72_I8@PURE_QUANTA.SOCKET4677_AZIF0045P001C01CS(CHIPS)':
 'VSS150': CDS_PINID='VSS150';
NODE_NAME     U1 AH16
 '@S9S_MB_2U_LIB.S9S_MB_2U(SCH_1):PAGE72_I8@PURE_QUANTA.SOCKET4677_AZIF0045P001C01CS(CHIPS)':
 'VSS151': CDS_PINID='VSS151';
NODE_NAME     U1 AH20
 '@S9S_MB_2U_LIB.S9S_MB_2U(SCH_1):PAGE72_I8@PURE_QUANTA.SOCKET4677_AZIF0045P001C01CS(CHIPS)':
 'VSS152': CDS_PINID='VSS152';
NODE_NAME     U1 AH22
 '@S9S_MB_2U_LIB.S9S_MB_2U(SCH_1):PAGE72_I8@PURE_QUANTA.SOCKET4677_AZIF0045P001C01CS(CHIPS)':
 'VSS153': CDS_PINID='VSS153';
NODE_NAME     U1 AH26
 '@S9S_MB_2U_LIB.S9S_MB_2U(SCH_1):PAGE72_I8@PURE_QUANTA.SOCKET4677_AZIF0045P001C01CS(CHIPS)':
 'VSS154': CDS_PINID='VSS154';
NODE_NAME     U1 AH28
 '@S9S_MB_2U_LIB.S9S_MB_2U(SCH_1):PAGE72_I8@PURE_QUANTA.SOCKET4677_AZIF0045P001C01CS(CHIPS)':
 'VSS155': CDS_PINID='VSS155';
NODE_NAME     U1 AH32
 '@S9S_MB_2U_LIB.S9S_MB_2U(SCH_1):PAGE72_I8@PURE_QUANTA.SOCKET4677_AZIF0045P001C01CS(CHIPS)':
 'VSS156': CDS_PINID='VSS156';
NODE_NAME     U1 AH34
 '@S9S_MB_2U_LIB.S9S_MB_2U(SCH_1):PAGE72_I8@PURE_QUANTA.SOCKET4677_AZIF0045P001C01CS(CHIPS)':
 'VSS157': CDS_PINID='VSS157';
NODE_NAME     U1 AH38
 '@S9S_MB_2U_LIB.S9S_MB_2U(SCH_1):PAGE72_I8@PURE_QUANTA.SOCKET4677_AZIF0045P001C01CS(CHIPS)':
 'VSS158': CDS_PINID='VSS158';
NODE_NAME     U1 AH4
 '@S9S_MB_2U_LIB.S9S_MB_2U(SCH_1):PAGE72_I8@PURE_QUANTA.SOCKET4677_AZIF0045P001C01CS(CHIPS)':
 'VSS159': CDS_PINID='VSS159';
NODE_NAME     U1 AH40
 '@S9S_MB_2U_LIB.S9S_MB_2U(SCH_1):PAGE72_I8@PURE_QUANTA.SOCKET4677_AZIF0045P001C01CS(CHIPS)':
 'VSS160': CDS_PINID='VSS160';
NODE_NAME     U1 AH44
 '@S9S_MB_2U_LIB.S9S_MB_2U(SCH_1):PAGE72_I8@PURE_QUANTA.SOCKET4677_AZIF0045P001C01CS(CHIPS)':
 'VSS161': CDS_PINID='VSS161';
NODE_NAME     U1 AH47
 '@S9S_MB_2U_LIB.S9S_MB_2U(SCH_1):PAGE72_I8@PURE_QUANTA.SOCKET4677_AZIF0045P001C01CS(CHIPS)':
 'VSS162': CDS_PINID='VSS162';
NODE_NAME     U1 AH51
 '@S9S_MB_2U_LIB.S9S_MB_2U(SCH_1):PAGE72_I8@PURE_QUANTA.SOCKET4677_AZIF0045P001C01CS(CHIPS)':
 'VSS163': CDS_PINID='VSS163';
NODE_NAME     U1 AH53
 '@S9S_MB_2U_LIB.S9S_MB_2U(SCH_1):PAGE72_I8@PURE_QUANTA.SOCKET4677_AZIF0045P001C01CS(CHIPS)':
 'VSS164': CDS_PINID='VSS164';
NODE_NAME     U1 AH57
 '@S9S_MB_2U_LIB.S9S_MB_2U(SCH_1):PAGE72_I8@PURE_QUANTA.SOCKET4677_AZIF0045P001C01CS(CHIPS)':
 'VSS165': CDS_PINID='VSS165';
NODE_NAME     U1 AH59
 '@S9S_MB_2U_LIB.S9S_MB_2U(SCH_1):PAGE72_I8@PURE_QUANTA.SOCKET4677_AZIF0045P001C01CS(CHIPS)':
 'VSS166': CDS_PINID='VSS166';
NODE_NAME     U1 AH63
 '@S9S_MB_2U_LIB.S9S_MB_2U(SCH_1):PAGE72_I8@PURE_QUANTA.SOCKET4677_AZIF0045P001C01CS(CHIPS)':
 'VSS167': CDS_PINID='VSS167';
NODE_NAME     U1 AH65
 '@S9S_MB_2U_LIB.S9S_MB_2U(SCH_1):PAGE72_I8@PURE_QUANTA.SOCKET4677_AZIF0045P001C01CS(CHIPS)':
 'VSS168': CDS_PINID='VSS168';
NODE_NAME     U1 AH69
 '@S9S_MB_2U_LIB.S9S_MB_2U(SCH_1):PAGE72_I8@PURE_QUANTA.SOCKET4677_AZIF0045P001C01CS(CHIPS)':
 'VSS169': CDS_PINID='VSS169';
NODE_NAME     U1 AH71
 '@S9S_MB_2U_LIB.S9S_MB_2U(SCH_1):PAGE72_I8@PURE_QUANTA.SOCKET4677_AZIF0045P001C01CS(CHIPS)':
 'VSS170': CDS_PINID='VSS170';
NODE_NAME     U1 AH75
 '@S9S_MB_2U_LIB.S9S_MB_2U(SCH_1):PAGE72_I8@PURE_QUANTA.SOCKET4677_AZIF0045P001C01CS(CHIPS)':
 'VSS171': CDS_PINID='VSS171';
NODE_NAME     U1 AH77
 '@S9S_MB_2U_LIB.S9S_MB_2U(SCH_1):PAGE72_I8@PURE_QUANTA.SOCKET4677_AZIF0045P001C01CS(CHIPS)':
 'VSS172': CDS_PINID='VSS172';
NODE_NAME     U1 AH79
 '@S9S_MB_2U_LIB.S9S_MB_2U(SCH_1):PAGE72_I8@PURE_QUANTA.SOCKET4677_AZIF0045P001C01CS(CHIPS)':
 'VSS173': CDS_PINID='VSS173';
NODE_NAME     U1 AH8
 '@S9S_MB_2U_LIB.S9S_MB_2U(SCH_1):PAGE72_I8@PURE_QUANTA.SOCKET4677_AZIF0045P001C01CS(CHIPS)':
 'VSS174': CDS_PINID='VSS174';
NODE_NAME     U1 AH83
 '@S9S_MB_2U_LIB.S9S_MB_2U(SCH_1):PAGE72_I8@PURE_QUANTA.SOCKET4677_AZIF0045P001C01CS(CHIPS)':
 'VSS175': CDS_PINID='VSS175';
NODE_NAME     U1 AJ19
 '@S9S_MB_2U_LIB.S9S_MB_2U(SCH_1):PAGE72_I8@PURE_QUANTA.SOCKET4677_AZIF0045P001C01CS(CHIPS)':
 'VSS176': CDS_PINID='VSS176';
NODE_NAME     U1 AJ23
 '@S9S_MB_2U_LIB.S9S_MB_2U(SCH_1):PAGE72_I8@PURE_QUANTA.SOCKET4677_AZIF0045P001C01CS(CHIPS)':
 'VSS177': CDS_PINID='VSS177';
NODE_NAME     U1 AJ25
 '@S9S_MB_2U_LIB.S9S_MB_2U(SCH_1):PAGE72_I8@PURE_QUANTA.SOCKET4677_AZIF0045P001C01CS(CHIPS)':
 'VSS178': CDS_PINID='VSS178';
NODE_NAME     U1 AJ29
 '@S9S_MB_2U_LIB.S9S_MB_2U(SCH_1):PAGE72_I8@PURE_QUANTA.SOCKET4677_AZIF0045P001C01CS(CHIPS)':
 'VSS179': CDS_PINID='VSS179';
NODE_NAME     U1 AJ31
 '@S9S_MB_2U_LIB.S9S_MB_2U(SCH_1):PAGE72_I8@PURE_QUANTA.SOCKET4677_AZIF0045P001C01CS(CHIPS)':
 'VSS180': CDS_PINID='VSS180';
NODE_NAME     U1 AJ35
 '@S9S_MB_2U_LIB.S9S_MB_2U(SCH_1):PAGE72_I8@PURE_QUANTA.SOCKET4677_AZIF0045P001C01CS(CHIPS)':
 'VSS181': CDS_PINID='VSS181';
NODE_NAME     U1 AJ37
 '@S9S_MB_2U_LIB.S9S_MB_2U(SCH_1):PAGE72_I8@PURE_QUANTA.SOCKET4677_AZIF0045P001C01CS(CHIPS)':
 'VSS182': CDS_PINID='VSS182';
NODE_NAME     U1 AJ41
 '@S9S_MB_2U_LIB.S9S_MB_2U(SCH_1):PAGE72_I8@PURE_QUANTA.SOCKET4677_AZIF0045P001C01CS(CHIPS)':
 'VSS183': CDS_PINID='VSS183';
NODE_NAME     U1 AJ43
 '@S9S_MB_2U_LIB.S9S_MB_2U(SCH_1):PAGE72_I8@PURE_QUANTA.SOCKET4677_AZIF0045P001C01CS(CHIPS)':
 'VSS184': CDS_PINID='VSS184';
NODE_NAME     U1 AJ48
 '@S9S_MB_2U_LIB.S9S_MB_2U(SCH_1):PAGE72_I8@PURE_QUANTA.SOCKET4677_AZIF0045P001C01CS(CHIPS)':
 'VSS185': CDS_PINID='VSS185';
NODE_NAME     U1 AJ50
 '@S9S_MB_2U_LIB.S9S_MB_2U(SCH_1):PAGE72_I8@PURE_QUANTA.SOCKET4677_AZIF0045P001C01CS(CHIPS)':
 'VSS186': CDS_PINID='VSS186';
NODE_NAME     U1 AJ54
 '@S9S_MB_2U_LIB.S9S_MB_2U(SCH_1):PAGE72_I8@PURE_QUANTA.SOCKET4677_AZIF0045P001C01CS(CHIPS)':
 'VSS187': CDS_PINID='VSS187';
NODE_NAME     U1 AJ56
 '@S9S_MB_2U_LIB.S9S_MB_2U(SCH_1):PAGE72_I8@PURE_QUANTA.SOCKET4677_AZIF0045P001C01CS(CHIPS)':
 'VSS188': CDS_PINID='VSS188';
NODE_NAME     U1 AJ60
 '@S9S_MB_2U_LIB.S9S_MB_2U(SCH_1):PAGE72_I8@PURE_QUANTA.SOCKET4677_AZIF0045P001C01CS(CHIPS)':
 'VSS189': CDS_PINID='VSS189';
NODE_NAME     U1 AJ62
 '@S9S_MB_2U_LIB.S9S_MB_2U(SCH_1):PAGE72_I8@PURE_QUANTA.SOCKET4677_AZIF0045P001C01CS(CHIPS)':
 'VSS190': CDS_PINID='VSS190';
NODE_NAME     U1 AJ66
 '@S9S_MB_2U_LIB.S9S_MB_2U(SCH_1):PAGE72_I8@PURE_QUANTA.SOCKET4677_AZIF0045P001C01CS(CHIPS)':
 'VSS191': CDS_PINID='VSS191';
NODE_NAME     U1 AJ68
 '@S9S_MB_2U_LIB.S9S_MB_2U(SCH_1):PAGE72_I8@PURE_QUANTA.SOCKET4677_AZIF0045P001C01CS(CHIPS)':
 'VSS192': CDS_PINID='VSS192';
NODE_NAME     U1 AJ72
 '@S9S_MB_2U_LIB.S9S_MB_2U(SCH_1):PAGE72_I8@PURE_QUANTA.SOCKET4677_AZIF0045P001C01CS(CHIPS)':
 'VSS193': CDS_PINID='VSS193';
NODE_NAME     U1 AJ74
 '@S9S_MB_2U_LIB.S9S_MB_2U(SCH_1):PAGE72_I8@PURE_QUANTA.SOCKET4677_AZIF0045P001C01CS(CHIPS)':
 'VSS194': CDS_PINID='VSS194';
NODE_NAME     U1 AJ78
 '@S9S_MB_2U_LIB.S9S_MB_2U(SCH_1):PAGE72_I8@PURE_QUANTA.SOCKET4677_AZIF0045P001C01CS(CHIPS)':
 'VSS195': CDS_PINID='VSS195';
NODE_NAME     U1 AJ84
 '@S9S_MB_2U_LIB.S9S_MB_2U(SCH_1):PAGE72_I8@PURE_QUANTA.SOCKET4677_AZIF0045P001C01CS(CHIPS)':
 'VSS196': CDS_PINID='VSS196';
NODE_NAME     U1 AJ88
 '@S9S_MB_2U_LIB.S9S_MB_2U(SCH_1):PAGE72_I8@PURE_QUANTA.SOCKET4677_AZIF0045P001C01CS(CHIPS)':
 'VSS197': CDS_PINID='VSS197';
NODE_NAME     U1 AA19
 '@S9S_MB_2U_LIB.S9S_MB_2U(SCH_1):PAGE73_I2@PURE_QUANTA.SOCKET4677_AZIF0045P001C01CS(CHIPS)':
 'VSS17': CDS_PINID='VSS17';
NODE_NAME     U1 AA23
 '@S9S_MB_2U_LIB.S9S_MB_2U(SCH_1):PAGE73_I2@PURE_QUANTA.SOCKET4677_AZIF0045P001C01CS(CHIPS)':
 'VSS18': CDS_PINID='VSS18';
NODE_NAME     U1 AA25
 '@S9S_MB_2U_LIB.S9S_MB_2U(SCH_1):PAGE73_I2@PURE_QUANTA.SOCKET4677_AZIF0045P001C01CS(CHIPS)':
 'VSS19': CDS_PINID='VSS19';
NODE_NAME     U1 AA29
 '@S9S_MB_2U_LIB.S9S_MB_2U(SCH_1):PAGE73_I2@PURE_QUANTA.SOCKET4677_AZIF0045P001C01CS(CHIPS)':
 'VSS20': CDS_PINID='VSS20';
NODE_NAME     U1 AA31
 '@S9S_MB_2U_LIB.S9S_MB_2U(SCH_1):PAGE73_I2@PURE_QUANTA.SOCKET4677_AZIF0045P001C01CS(CHIPS)':
 'VSS21': CDS_PINID='VSS21';
NODE_NAME     U1 AA35
 '@S9S_MB_2U_LIB.S9S_MB_2U(SCH_1):PAGE73_I2@PURE_QUANTA.SOCKET4677_AZIF0045P001C01CS(CHIPS)':
 'VSS22': CDS_PINID='VSS22';
NODE_NAME     U1 AA37
 '@S9S_MB_2U_LIB.S9S_MB_2U(SCH_1):PAGE73_I2@PURE_QUANTA.SOCKET4677_AZIF0045P001C01CS(CHIPS)':
 'VSS23': CDS_PINID='VSS23';
NODE_NAME     U1 AA41
 '@S9S_MB_2U_LIB.S9S_MB_2U(SCH_1):PAGE73_I2@PURE_QUANTA.SOCKET4677_AZIF0045P001C01CS(CHIPS)':
 'VSS24': CDS_PINID='VSS24';
NODE_NAME     U1 AA43
 '@S9S_MB_2U_LIB.S9S_MB_2U(SCH_1):PAGE73_I2@PURE_QUANTA.SOCKET4677_AZIF0045P001C01CS(CHIPS)':
 'VSS25': CDS_PINID='VSS25';
NODE_NAME     U1 AA48
 '@S9S_MB_2U_LIB.S9S_MB_2U(SCH_1):PAGE73_I2@PURE_QUANTA.SOCKET4677_AZIF0045P001C01CS(CHIPS)':
 'VSS26': CDS_PINID='VSS26';
NODE_NAME     U1 AA50
 '@S9S_MB_2U_LIB.S9S_MB_2U(SCH_1):PAGE73_I2@PURE_QUANTA.SOCKET4677_AZIF0045P001C01CS(CHIPS)':
 'VSS27': CDS_PINID='VSS27';
NODE_NAME     U1 AA54
 '@S9S_MB_2U_LIB.S9S_MB_2U(SCH_1):PAGE73_I2@PURE_QUANTA.SOCKET4677_AZIF0045P001C01CS(CHIPS)':
 'VSS28': CDS_PINID='VSS28';
NODE_NAME     U1 AA56
 '@S9S_MB_2U_LIB.S9S_MB_2U(SCH_1):PAGE73_I2@PURE_QUANTA.SOCKET4677_AZIF0045P001C01CS(CHIPS)':
 'VSS29': CDS_PINID='VSS29';
NODE_NAME     U1 AA60
 '@S9S_MB_2U_LIB.S9S_MB_2U(SCH_1):PAGE73_I2@PURE_QUANTA.SOCKET4677_AZIF0045P001C01CS(CHIPS)':
 'VSS30': CDS_PINID='VSS30';
NODE_NAME     U1 AA62
 '@S9S_MB_2U_LIB.S9S_MB_2U(SCH_1):PAGE73_I2@PURE_QUANTA.SOCKET4677_AZIF0045P001C01CS(CHIPS)':
 'VSS31': CDS_PINID='VSS31';
NODE_NAME     U1 AA66
 '@S9S_MB_2U_LIB.S9S_MB_2U(SCH_1):PAGE73_I2@PURE_QUANTA.SOCKET4677_AZIF0045P001C01CS(CHIPS)':
 'VSS32': CDS_PINID='VSS32';
NODE_NAME     U1 AA68
 '@S9S_MB_2U_LIB.S9S_MB_2U(SCH_1):PAGE73_I2@PURE_QUANTA.SOCKET4677_AZIF0045P001C01CS(CHIPS)':
 'VSS33': CDS_PINID='VSS33';
NODE_NAME     U1 AA72
 '@S9S_MB_2U_LIB.S9S_MB_2U(SCH_1):PAGE73_I2@PURE_QUANTA.SOCKET4677_AZIF0045P001C01CS(CHIPS)':
 'VSS34': CDS_PINID='VSS34';
NODE_NAME     U1 AA74
 '@S9S_MB_2U_LIB.S9S_MB_2U(SCH_1):PAGE73_I2@PURE_QUANTA.SOCKET4677_AZIF0045P001C01CS(CHIPS)':
 'VSS35': CDS_PINID='VSS35';
NODE_NAME     U1 AA78
 '@S9S_MB_2U_LIB.S9S_MB_2U(SCH_1):PAGE73_I2@PURE_QUANTA.SOCKET4677_AZIF0045P001C01CS(CHIPS)':
 'VSS36': CDS_PINID='VSS36';
NODE_NAME     U1 AA80
 '@S9S_MB_2U_LIB.S9S_MB_2U(SCH_1):PAGE73_I2@PURE_QUANTA.SOCKET4677_AZIF0045P001C01CS(CHIPS)':
 'VSS37': CDS_PINID='VSS37';
NODE_NAME     U1 P32
 '@S9S_MB_2U_LIB.S9S_MB_2U(SCH_1):PAGE73_I2@PURE_QUANTA.SOCKET4677_AZIF0045P001C01CS(CHIPS)':
 'VSS1690': CDS_PINID='VSS1690';
NODE_NAME     U1 N76
 '@S9S_MB_2U_LIB.S9S_MB_2U(SCH_1):PAGE73_I2@PURE_QUANTA.SOCKET4677_AZIF0045P001C01CS(CHIPS)':
 'VSS1696': CDS_PINID='VSS1696';
NODE_NAME     U1 P51
 '@S9S_MB_2U_LIB.S9S_MB_2U(SCH_1):PAGE73_I2@PURE_QUANTA.SOCKET4677_AZIF0045P001C01CS(CHIPS)':
 'VSS1697': CDS_PINID='VSS1697';
NODE_NAME     U1 N78
 '@S9S_MB_2U_LIB.S9S_MB_2U(SCH_1):PAGE73_I2@PURE_QUANTA.SOCKET4677_AZIF0045P001C01CS(CHIPS)':
 'VSS1698': CDS_PINID='VSS1698';
NODE_NAME     U1 P57
 '@S9S_MB_2U_LIB.S9S_MB_2U(SCH_1):PAGE73_I2@PURE_QUANTA.SOCKET4677_AZIF0045P001C01CS(CHIPS)':
 'VSS1699': CDS_PINID='VSS1699';
NODE_NAME     U1 N80
 '@S9S_MB_2U_LIB.S9S_MB_2U(SCH_1):PAGE73_I2@PURE_QUANTA.SOCKET4677_AZIF0045P001C01CS(CHIPS)':
 'VSS1700': CDS_PINID='VSS1700';
NODE_NAME     U1 N82
 '@S9S_MB_2U_LIB.S9S_MB_2U(SCH_1):PAGE73_I2@PURE_QUANTA.SOCKET4677_AZIF0045P001C01CS(CHIPS)':
 'VSS1701': CDS_PINID='VSS1701';
NODE_NAME     U1 N84
 '@S9S_MB_2U_LIB.S9S_MB_2U(SCH_1):PAGE73_I2@PURE_QUANTA.SOCKET4677_AZIF0045P001C01CS(CHIPS)':
 'VSS1702': CDS_PINID='VSS1702';
NODE_NAME     U1 N88
 '@S9S_MB_2U_LIB.S9S_MB_2U(SCH_1):PAGE73_I2@PURE_QUANTA.SOCKET4677_AZIF0045P001C01CS(CHIPS)':
 'VSS1703': CDS_PINID='VSS1703';
NODE_NAME     U1 P71
 '@S9S_MB_2U_LIB.S9S_MB_2U(SCH_1):PAGE73_I2@PURE_QUANTA.SOCKET4677_AZIF0045P001C01CS(CHIPS)':
 'VSS1704': CDS_PINID='VSS1704';
NODE_NAME     U1 P12
 '@S9S_MB_2U_LIB.S9S_MB_2U(SCH_1):PAGE73_I2@PURE_QUANTA.SOCKET4677_AZIF0045P001C01CS(CHIPS)':
 'VSS1705': CDS_PINID='VSS1705';
NODE_NAME     U1 P16
 '@S9S_MB_2U_LIB.S9S_MB_2U(SCH_1):PAGE73_I2@PURE_QUANTA.SOCKET4677_AZIF0045P001C01CS(CHIPS)':
 'VSS1706': CDS_PINID='VSS1706';
NODE_NAME     U1 P20
 '@S9S_MB_2U_LIB.S9S_MB_2U(SCH_1):PAGE73_I2@PURE_QUANTA.SOCKET4677_AZIF0045P001C01CS(CHIPS)':
 'VSS1707': CDS_PINID='VSS1707';
NODE_NAME     U1 P22
 '@S9S_MB_2U_LIB.S9S_MB_2U(SCH_1):PAGE73_I2@PURE_QUANTA.SOCKET4677_AZIF0045P001C01CS(CHIPS)':
 'VSS1708': CDS_PINID='VSS1708';
NODE_NAME     U1 P26
 '@S9S_MB_2U_LIB.S9S_MB_2U(SCH_1):PAGE73_I2@PURE_QUANTA.SOCKET4677_AZIF0045P001C01CS(CHIPS)':
 'VSS1709': CDS_PINID='VSS1709';
NODE_NAME     U1 P28
 '@S9S_MB_2U_LIB.S9S_MB_2U(SCH_1):PAGE73_I2@PURE_QUANTA.SOCKET4677_AZIF0045P001C01CS(CHIPS)':
 'VSS1710': CDS_PINID='VSS1710';
NODE_NAME     U1 R1
 '@S9S_MB_2U_LIB.S9S_MB_2U(SCH_1):PAGE73_I2@PURE_QUANTA.SOCKET4677_AZIF0045P001C01CS(CHIPS)':
 'VSS1711': CDS_PINID='VSS1711';
NODE_NAME     U1 P34
 '@S9S_MB_2U_LIB.S9S_MB_2U(SCH_1):PAGE73_I2@PURE_QUANTA.SOCKET4677_AZIF0045P001C01CS(CHIPS)':
 'VSS1712': CDS_PINID='VSS1712';
NODE_NAME     U1 P38
 '@S9S_MB_2U_LIB.S9S_MB_2U(SCH_1):PAGE73_I2@PURE_QUANTA.SOCKET4677_AZIF0045P001C01CS(CHIPS)':
 'VSS1713': CDS_PINID='VSS1713';
NODE_NAME     U1 R19
 '@S9S_MB_2U_LIB.S9S_MB_2U(SCH_1):PAGE73_I2@PURE_QUANTA.SOCKET4677_AZIF0045P001C01CS(CHIPS)':
 'VSS1714': CDS_PINID='VSS1714';
NODE_NAME     U1 R23
 '@S9S_MB_2U_LIB.S9S_MB_2U(SCH_1):PAGE73_I2@PURE_QUANTA.SOCKET4677_AZIF0045P001C01CS(CHIPS)':
 'VSS1715': CDS_PINID='VSS1715';
NODE_NAME     U1 P4
 '@S9S_MB_2U_LIB.S9S_MB_2U(SCH_1):PAGE73_I2@PURE_QUANTA.SOCKET4677_AZIF0045P001C01CS(CHIPS)':
 'VSS1716': CDS_PINID='VSS1716';
NODE_NAME     U1 P40
 '@S9S_MB_2U_LIB.S9S_MB_2U(SCH_1):PAGE73_I2@PURE_QUANTA.SOCKET4677_AZIF0045P001C01CS(CHIPS)':
 'VSS1717': CDS_PINID='VSS1717';
NODE_NAME     U1 P44
 '@S9S_MB_2U_LIB.S9S_MB_2U(SCH_1):PAGE73_I2@PURE_QUANTA.SOCKET4677_AZIF0045P001C01CS(CHIPS)':
 'VSS1718': CDS_PINID='VSS1718';
NODE_NAME     U1 P47
 '@S9S_MB_2U_LIB.S9S_MB_2U(SCH_1):PAGE73_I2@PURE_QUANTA.SOCKET4677_AZIF0045P001C01CS(CHIPS)':
 'VSS1719': CDS_PINID='VSS1719';
NODE_NAME     U1 P53
 '@S9S_MB_2U_LIB.S9S_MB_2U(SCH_1):PAGE73_I2@PURE_QUANTA.SOCKET4677_AZIF0045P001C01CS(CHIPS)':
 'VSS1720': CDS_PINID='VSS1720';
NODE_NAME     U1 P59
 '@S9S_MB_2U_LIB.S9S_MB_2U(SCH_1):PAGE73_I2@PURE_QUANTA.SOCKET4677_AZIF0045P001C01CS(CHIPS)':
 'VSS1721': CDS_PINID='VSS1721';
NODE_NAME     U1 P63
 '@S9S_MB_2U_LIB.S9S_MB_2U(SCH_1):PAGE73_I2@PURE_QUANTA.SOCKET4677_AZIF0045P001C01CS(CHIPS)':
 'VSS1722': CDS_PINID='VSS1722';
NODE_NAME     U1 R48
 '@S9S_MB_2U_LIB.S9S_MB_2U(SCH_1):PAGE73_I2@PURE_QUANTA.SOCKET4677_AZIF0045P001C01CS(CHIPS)':
 'VSS1723': CDS_PINID='VSS1723';
NODE_NAME     U1 P65
 '@S9S_MB_2U_LIB.S9S_MB_2U(SCH_1):PAGE73_I2@PURE_QUANTA.SOCKET4677_AZIF0045P001C01CS(CHIPS)':
 'VSS1724': CDS_PINID='VSS1724';
NODE_NAME     U1 P69
 '@S9S_MB_2U_LIB.S9S_MB_2U(SCH_1):PAGE73_I2@PURE_QUANTA.SOCKET4677_AZIF0045P001C01CS(CHIPS)':
 'VSS1725': CDS_PINID='VSS1725';
NODE_NAME     U1 P75
 '@S9S_MB_2U_LIB.S9S_MB_2U(SCH_1):PAGE73_I2@PURE_QUANTA.SOCKET4677_AZIF0045P001C01CS(CHIPS)':
 'VSS1726': CDS_PINID='VSS1726';
NODE_NAME     U1 P77
 '@S9S_MB_2U_LIB.S9S_MB_2U(SCH_1):PAGE73_I2@PURE_QUANTA.SOCKET4677_AZIF0045P001C01CS(CHIPS)':
 'VSS1727': CDS_PINID='VSS1727';
NODE_NAME     U1 R60
 '@S9S_MB_2U_LIB.S9S_MB_2U(SCH_1):PAGE73_I2@PURE_QUANTA.SOCKET4677_AZIF0045P001C01CS(CHIPS)':
 'VSS1728': CDS_PINID='VSS1728';
NODE_NAME     U1 P8
 '@S9S_MB_2U_LIB.S9S_MB_2U(SCH_1):PAGE73_I2@PURE_QUANTA.SOCKET4677_AZIF0045P001C01CS(CHIPS)':
 'VSS1729': CDS_PINID='VSS1729';
NODE_NAME     U1 R66
 '@S9S_MB_2U_LIB.S9S_MB_2U(SCH_1):PAGE73_I2@PURE_QUANTA.SOCKET4677_AZIF0045P001C01CS(CHIPS)':
 'VSS1730': CDS_PINID='VSS1730';
NODE_NAME     U1 P87
 '@S9S_MB_2U_LIB.S9S_MB_2U(SCH_1):PAGE73_I2@PURE_QUANTA.SOCKET4677_AZIF0045P001C01CS(CHIPS)':
 'VSS1731': CDS_PINID='VSS1731';
NODE_NAME     U1 P91
 '@S9S_MB_2U_LIB.S9S_MB_2U(SCH_1):PAGE73_I2@PURE_QUANTA.SOCKET4677_AZIF0045P001C01CS(CHIPS)':
 'VSS1732': CDS_PINID='VSS1732';
NODE_NAME     U1 R13
 '@S9S_MB_2U_LIB.S9S_MB_2U(SCH_1):PAGE73_I2@PURE_QUANTA.SOCKET4677_AZIF0045P001C01CS(CHIPS)':
 'VSS1733': CDS_PINID='VSS1733';
NODE_NAME     U1 R17
 '@S9S_MB_2U_LIB.S9S_MB_2U(SCH_1):PAGE73_I2@PURE_QUANTA.SOCKET4677_AZIF0045P001C01CS(CHIPS)':
 'VSS1734': CDS_PINID='VSS1734';
NODE_NAME     U1 R25
 '@S9S_MB_2U_LIB.S9S_MB_2U(SCH_1):PAGE73_I2@PURE_QUANTA.SOCKET4677_AZIF0045P001C01CS(CHIPS)':
 'VSS1735': CDS_PINID='VSS1735';
NODE_NAME     U1 R29
 '@S9S_MB_2U_LIB.S9S_MB_2U(SCH_1):PAGE73_I2@PURE_QUANTA.SOCKET4677_AZIF0045P001C01CS(CHIPS)':
 'VSS1736': CDS_PINID='VSS1736';
NODE_NAME     U1 R31
 '@S9S_MB_2U_LIB.S9S_MB_2U(SCH_1):PAGE73_I2@PURE_QUANTA.SOCKET4677_AZIF0045P001C01CS(CHIPS)':
 'VSS1737': CDS_PINID='VSS1737';
NODE_NAME     U1 R35
 '@S9S_MB_2U_LIB.S9S_MB_2U(SCH_1):PAGE73_I2@PURE_QUANTA.SOCKET4677_AZIF0045P001C01CS(CHIPS)':
 'VSS1738': CDS_PINID='VSS1738';
NODE_NAME     U1 T12
 '@S9S_MB_2U_LIB.S9S_MB_2U(SCH_1):PAGE73_I2@PURE_QUANTA.SOCKET4677_AZIF0045P001C01CS(CHIPS)':
 'VSS1739': CDS_PINID='VSS1739';
NODE_NAME     U1 T16
 '@S9S_MB_2U_LIB.S9S_MB_2U(SCH_1):PAGE73_I2@PURE_QUANTA.SOCKET4677_AZIF0045P001C01CS(CHIPS)':
 'VSS1740': CDS_PINID='VSS1740';
NODE_NAME     U1 T18
 '@S9S_MB_2U_LIB.S9S_MB_2U(SCH_1):PAGE73_I2@PURE_QUANTA.SOCKET4677_AZIF0045P001C01CS(CHIPS)':
 'VSS1741': CDS_PINID='VSS1741';
NODE_NAME     U1 R37
 '@S9S_MB_2U_LIB.S9S_MB_2U(SCH_1):PAGE73_I2@PURE_QUANTA.SOCKET4677_AZIF0045P001C01CS(CHIPS)':
 'VSS1742': CDS_PINID='VSS1742';
NODE_NAME     U1 R41
 '@S9S_MB_2U_LIB.S9S_MB_2U(SCH_1):PAGE73_I2@PURE_QUANTA.SOCKET4677_AZIF0045P001C01CS(CHIPS)':
 'VSS1743': CDS_PINID='VSS1743';
NODE_NAME     U1 R43
 '@S9S_MB_2U_LIB.S9S_MB_2U(SCH_1):PAGE73_I2@PURE_QUANTA.SOCKET4677_AZIF0045P001C01CS(CHIPS)':
 'VSS1744': CDS_PINID='VSS1744';
NODE_NAME     U1 R5
 '@S9S_MB_2U_LIB.S9S_MB_2U(SCH_1):PAGE73_I2@PURE_QUANTA.SOCKET4677_AZIF0045P001C01CS(CHIPS)':
 'VSS1745': CDS_PINID='VSS1745';
NODE_NAME     U1 T36
 '@S9S_MB_2U_LIB.S9S_MB_2U(SCH_1):PAGE73_I2@PURE_QUANTA.SOCKET4677_AZIF0045P001C01CS(CHIPS)':
 'VSS1746': CDS_PINID='VSS1746';
NODE_NAME     U1 R50
 '@S9S_MB_2U_LIB.S9S_MB_2U(SCH_1):PAGE73_I2@PURE_QUANTA.SOCKET4677_AZIF0045P001C01CS(CHIPS)':
 'VSS1747': CDS_PINID='VSS1747';
NODE_NAME     U1 R54
 '@S9S_MB_2U_LIB.S9S_MB_2U(SCH_1):PAGE73_I2@PURE_QUANTA.SOCKET4677_AZIF0045P001C01CS(CHIPS)':
 'VSS1748': CDS_PINID='VSS1748';
NODE_NAME     U1 T49
 '@S9S_MB_2U_LIB.S9S_MB_2U(SCH_1):PAGE73_I2@PURE_QUANTA.SOCKET4677_AZIF0045P001C01CS(CHIPS)':
 'VSS1749': CDS_PINID='VSS1749';
NODE_NAME     U1 T55
 '@S9S_MB_2U_LIB.S9S_MB_2U(SCH_1):PAGE73_I2@PURE_QUANTA.SOCKET4677_AZIF0045P001C01CS(CHIPS)':
 'VSS1750': CDS_PINID='VSS1750';
NODE_NAME     U1 R56
 '@S9S_MB_2U_LIB.S9S_MB_2U(SCH_1):PAGE73_I2@PURE_QUANTA.SOCKET4677_AZIF0045P001C01CS(CHIPS)':
 'VSS1751': CDS_PINID='VSS1751';
NODE_NAME     U1 R62
 '@S9S_MB_2U_LIB.S9S_MB_2U(SCH_1):PAGE73_I2@PURE_QUANTA.SOCKET4677_AZIF0045P001C01CS(CHIPS)':
 'VSS1752': CDS_PINID='VSS1752';
NODE_NAME     U1 R68
 '@S9S_MB_2U_LIB.S9S_MB_2U(SCH_1):PAGE73_I2@PURE_QUANTA.SOCKET4677_AZIF0045P001C01CS(CHIPS)':
 'VSS1753': CDS_PINID='VSS1753';
NODE_NAME     U1 R72
 '@S9S_MB_2U_LIB.S9S_MB_2U(SCH_1):PAGE73_I2@PURE_QUANTA.SOCKET4677_AZIF0045P001C01CS(CHIPS)':
 'VSS1754': CDS_PINID='VSS1754';
NODE_NAME     U1 R74
 '@S9S_MB_2U_LIB.S9S_MB_2U(SCH_1):PAGE73_I2@PURE_QUANTA.SOCKET4677_AZIF0045P001C01CS(CHIPS)':
 'VSS1755': CDS_PINID='VSS1755';
NODE_NAME     U1 R78
 '@S9S_MB_2U_LIB.S9S_MB_2U(SCH_1):PAGE73_I2@PURE_QUANTA.SOCKET4677_AZIF0045P001C01CS(CHIPS)':
 'VSS1756': CDS_PINID='VSS1756';
NODE_NAME     U1 R84
 '@S9S_MB_2U_LIB.S9S_MB_2U(SCH_1):PAGE73_I2@PURE_QUANTA.SOCKET4677_AZIF0045P001C01CS(CHIPS)':
 'VSS1757': CDS_PINID='VSS1757';
NODE_NAME     U1 R88
 '@S9S_MB_2U_LIB.S9S_MB_2U(SCH_1):PAGE73_I2@PURE_QUANTA.SOCKET4677_AZIF0045P001C01CS(CHIPS)':
 'VSS1758': CDS_PINID='VSS1758';
NODE_NAME     U1 R9
 '@S9S_MB_2U_LIB.S9S_MB_2U(SCH_1):PAGE73_I2@PURE_QUANTA.SOCKET4677_AZIF0045P001C01CS(CHIPS)':
 'VSS1759': CDS_PINID='VSS1759';
NODE_NAME     U1 T24
 '@S9S_MB_2U_LIB.S9S_MB_2U(SCH_1):PAGE73_I2@PURE_QUANTA.SOCKET4677_AZIF0045P001C01CS(CHIPS)':
 'VSS1760': CDS_PINID='VSS1760';
NODE_NAME     U1 T30
 '@S9S_MB_2U_LIB.S9S_MB_2U(SCH_1):PAGE73_I2@PURE_QUANTA.SOCKET4677_AZIF0045P001C01CS(CHIPS)':
 'VSS1761': CDS_PINID='VSS1761';
NODE_NAME     U1 T4
 '@S9S_MB_2U_LIB.S9S_MB_2U(SCH_1):PAGE73_I2@PURE_QUANTA.SOCKET4677_AZIF0045P001C01CS(CHIPS)':
 'VSS1762': CDS_PINID='VSS1762';
NODE_NAME     U1 T42
 '@S9S_MB_2U_LIB.S9S_MB_2U(SCH_1):PAGE73_I2@PURE_QUANTA.SOCKET4677_AZIF0045P001C01CS(CHIPS)':
 'VSS1763': CDS_PINID='VSS1763';
NODE_NAME     U1 T61
 '@S9S_MB_2U_LIB.S9S_MB_2U(SCH_1):PAGE73_I2@PURE_QUANTA.SOCKET4677_AZIF0045P001C01CS(CHIPS)':
 'VSS1764': CDS_PINID='VSS1764';
NODE_NAME     U1 T67
 '@S9S_MB_2U_LIB.S9S_MB_2U(SCH_1):PAGE73_I2@PURE_QUANTA.SOCKET4677_AZIF0045P001C01CS(CHIPS)':
 'VSS1765': CDS_PINID='VSS1765';
NODE_NAME     U1 U52
 '@S9S_MB_2U_LIB.S9S_MB_2U(SCH_1):PAGE73_I2@PURE_QUANTA.SOCKET4677_AZIF0045P001C01CS(CHIPS)':
 'VSS1766': CDS_PINID='VSS1766';
NODE_NAME     U1 T73
 '@S9S_MB_2U_LIB.S9S_MB_2U(SCH_1):PAGE73_I2@PURE_QUANTA.SOCKET4677_AZIF0045P001C01CS(CHIPS)':
 'VSS1767': CDS_PINID='VSS1767';
NODE_NAME     U1 T79
 '@S9S_MB_2U_LIB.S9S_MB_2U(SCH_1):PAGE73_I2@PURE_QUANTA.SOCKET4677_AZIF0045P001C01CS(CHIPS)':
 'VSS1768': CDS_PINID='VSS1768';
NODE_NAME     U1 T8
 '@S9S_MB_2U_LIB.S9S_MB_2U(SCH_1):PAGE73_I2@PURE_QUANTA.SOCKET4677_AZIF0045P001C01CS(CHIPS)':
 'VSS1769': CDS_PINID='VSS1769';
NODE_NAME     U1 T83
 '@S9S_MB_2U_LIB.S9S_MB_2U(SCH_1):PAGE73_I2@PURE_QUANTA.SOCKET4677_AZIF0045P001C01CS(CHIPS)':
 'VSS1770': CDS_PINID='VSS1770';
NODE_NAME     U1 U39
 '@S9S_MB_2U_LIB.S9S_MB_2U(SCH_1):PAGE73_I2@PURE_QUANTA.SOCKET4677_AZIF0045P001C01CS(CHIPS)':
 'VSS1771': CDS_PINID='VSS1771';
NODE_NAME     U1 U82
 '@S9S_MB_2U_LIB.S9S_MB_2U(SCH_1):PAGE73_I2@PURE_QUANTA.SOCKET4677_AZIF0045P001C01CS(CHIPS)':
 'VSS1772': CDS_PINID='VSS1772';
NODE_NAME     U1 U84
 '@S9S_MB_2U_LIB.S9S_MB_2U(SCH_1):PAGE73_I2@PURE_QUANTA.SOCKET4677_AZIF0045P001C01CS(CHIPS)':
 'VSS1773': CDS_PINID='VSS1773';
NODE_NAME     U1 U88
 '@S9S_MB_2U_LIB.S9S_MB_2U(SCH_1):PAGE73_I2@PURE_QUANTA.SOCKET4677_AZIF0045P001C01CS(CHIPS)':
 'VSS1774': CDS_PINID='VSS1774';
NODE_NAME     U1 V12
 '@S9S_MB_2U_LIB.S9S_MB_2U(SCH_1):PAGE73_I2@PURE_QUANTA.SOCKET4677_AZIF0045P001C01CS(CHIPS)':
 'VSS1775': CDS_PINID='VSS1775';
NODE_NAME     U1 V16
 '@S9S_MB_2U_LIB.S9S_MB_2U(SCH_1):PAGE73_I2@PURE_QUANTA.SOCKET4677_AZIF0045P001C01CS(CHIPS)':
 'VSS1776': CDS_PINID='VSS1776';
NODE_NAME     U1 V18
 '@S9S_MB_2U_LIB.S9S_MB_2U(SCH_1):PAGE73_I2@PURE_QUANTA.SOCKET4677_AZIF0045P001C01CS(CHIPS)':
 'VSS1777': CDS_PINID='VSS1777';
NODE_NAME     U1 V20
 '@S9S_MB_2U_LIB.S9S_MB_2U(SCH_1):PAGE73_I2@PURE_QUANTA.SOCKET4677_AZIF0045P001C01CS(CHIPS)':
 'VSS1778': CDS_PINID='VSS1778';
NODE_NAME     U1 V22
 '@S9S_MB_2U_LIB.S9S_MB_2U(SCH_1):PAGE73_I2@PURE_QUANTA.SOCKET4677_AZIF0045P001C01CS(CHIPS)':
 'VSS1779': CDS_PINID='VSS1779';
NODE_NAME     U1 V24
 '@S9S_MB_2U_LIB.S9S_MB_2U(SCH_1):PAGE73_I2@PURE_QUANTA.SOCKET4677_AZIF0045P001C01CS(CHIPS)':
 'VSS1780': CDS_PINID='VSS1780';
NODE_NAME     U1 V26
 '@S9S_MB_2U_LIB.S9S_MB_2U(SCH_1):PAGE73_I2@PURE_QUANTA.SOCKET4677_AZIF0045P001C01CS(CHIPS)':
 'VSS1781': CDS_PINID='VSS1781';
NODE_NAME     U1 V28
 '@S9S_MB_2U_LIB.S9S_MB_2U(SCH_1):PAGE73_I2@PURE_QUANTA.SOCKET4677_AZIF0045P001C01CS(CHIPS)':
 'VSS1782': CDS_PINID='VSS1782';
NODE_NAME     U1 V30
 '@S9S_MB_2U_LIB.S9S_MB_2U(SCH_1):PAGE73_I2@PURE_QUANTA.SOCKET4677_AZIF0045P001C01CS(CHIPS)':
 'VSS1783': CDS_PINID='VSS1783';
NODE_NAME     U1 V32
 '@S9S_MB_2U_LIB.S9S_MB_2U(SCH_1):PAGE73_I2@PURE_QUANTA.SOCKET4677_AZIF0045P001C01CS(CHIPS)':
 'VSS1784': CDS_PINID='VSS1784';
NODE_NAME     U1 V34
 '@S9S_MB_2U_LIB.S9S_MB_2U(SCH_1):PAGE73_I2@PURE_QUANTA.SOCKET4677_AZIF0045P001C01CS(CHIPS)':
 'VSS1785': CDS_PINID='VSS1785';
NODE_NAME     U1 V36
 '@S9S_MB_2U_LIB.S9S_MB_2U(SCH_1):PAGE73_I2@PURE_QUANTA.SOCKET4677_AZIF0045P001C01CS(CHIPS)':
 'VSS1786': CDS_PINID='VSS1786';
NODE_NAME     U1 V38
 '@S9S_MB_2U_LIB.S9S_MB_2U(SCH_1):PAGE73_I2@PURE_QUANTA.SOCKET4677_AZIF0045P001C01CS(CHIPS)':
 'VSS1787': CDS_PINID='VSS1787';
NODE_NAME     U1 V4
 '@S9S_MB_2U_LIB.S9S_MB_2U(SCH_1):PAGE73_I2@PURE_QUANTA.SOCKET4677_AZIF0045P001C01CS(CHIPS)':
 'VSS1788': CDS_PINID='VSS1788';
NODE_NAME     U1 V49
 '@S9S_MB_2U_LIB.S9S_MB_2U(SCH_1):PAGE73_I2@PURE_QUANTA.SOCKET4677_AZIF0045P001C01CS(CHIPS)':
 'VSS1789': CDS_PINID='VSS1789';
NODE_NAME     U1 V40
 '@S9S_MB_2U_LIB.S9S_MB_2U(SCH_1):PAGE73_I2@PURE_QUANTA.SOCKET4677_AZIF0045P001C01CS(CHIPS)':
 'VSS1790': CDS_PINID='VSS1790';
NODE_NAME     U1 V42
 '@S9S_MB_2U_LIB.S9S_MB_2U(SCH_1):PAGE73_I2@PURE_QUANTA.SOCKET4677_AZIF0045P001C01CS(CHIPS)':
 'VSS1791': CDS_PINID='VSS1791';
NODE_NAME     U1 V44
 '@S9S_MB_2U_LIB.S9S_MB_2U(SCH_1):PAGE73_I2@PURE_QUANTA.SOCKET4677_AZIF0045P001C01CS(CHIPS)':
 'VSS1792': CDS_PINID='VSS1792';
NODE_NAME     U1 V47
 '@S9S_MB_2U_LIB.S9S_MB_2U(SCH_1):PAGE73_I2@PURE_QUANTA.SOCKET4677_AZIF0045P001C01CS(CHIPS)':
 'VSS1793': CDS_PINID='VSS1793';
NODE_NAME     U1 V51
 '@S9S_MB_2U_LIB.S9S_MB_2U(SCH_1):PAGE73_I2@PURE_QUANTA.SOCKET4677_AZIF0045P001C01CS(CHIPS)':
 'VSS1794': CDS_PINID='VSS1794';
NODE_NAME     U1 V53
 '@S9S_MB_2U_LIB.S9S_MB_2U(SCH_1):PAGE73_I2@PURE_QUANTA.SOCKET4677_AZIF0045P001C01CS(CHIPS)':
 'VSS1795': CDS_PINID='VSS1795';
NODE_NAME     U1 V55
 '@S9S_MB_2U_LIB.S9S_MB_2U(SCH_1):PAGE73_I2@PURE_QUANTA.SOCKET4677_AZIF0045P001C01CS(CHIPS)':
 'VSS1796': CDS_PINID='VSS1796';
NODE_NAME     U1 V57
 '@S9S_MB_2U_LIB.S9S_MB_2U(SCH_1):PAGE73_I2@PURE_QUANTA.SOCKET4677_AZIF0045P001C01CS(CHIPS)':
 'VSS1797': CDS_PINID='VSS1797';
NODE_NAME     U1 V59
 '@S9S_MB_2U_LIB.S9S_MB_2U(SCH_1):PAGE73_I2@PURE_QUANTA.SOCKET4677_AZIF0045P001C01CS(CHIPS)':
 'VSS1798': CDS_PINID='VSS1798';
NODE_NAME     U1 V61
 '@S9S_MB_2U_LIB.S9S_MB_2U(SCH_1):PAGE73_I2@PURE_QUANTA.SOCKET4677_AZIF0045P001C01CS(CHIPS)':
 'VSS1799': CDS_PINID='VSS1799';
NODE_NAME     U1 V71
 '@S9S_MB_2U_LIB.S9S_MB_2U(SCH_1):PAGE73_I2@PURE_QUANTA.SOCKET4677_AZIF0045P001C01CS(CHIPS)':
 'VSS1800': CDS_PINID='VSS1800';
NODE_NAME     U1 V73
 '@S9S_MB_2U_LIB.S9S_MB_2U(SCH_1):PAGE73_I2@PURE_QUANTA.SOCKET4677_AZIF0045P001C01CS(CHIPS)':
 'VSS1801': CDS_PINID='VSS1801';
NODE_NAME     U1 V63
 '@S9S_MB_2U_LIB.S9S_MB_2U(SCH_1):PAGE73_I2@PURE_QUANTA.SOCKET4677_AZIF0045P001C01CS(CHIPS)':
 'VSS1802': CDS_PINID='VSS1802';
NODE_NAME     U1 V65
 '@S9S_MB_2U_LIB.S9S_MB_2U(SCH_1):PAGE73_I2@PURE_QUANTA.SOCKET4677_AZIF0045P001C01CS(CHIPS)':
 'VSS1803': CDS_PINID='VSS1803';
NODE_NAME     U1 V67
 '@S9S_MB_2U_LIB.S9S_MB_2U(SCH_1):PAGE73_I2@PURE_QUANTA.SOCKET4677_AZIF0045P001C01CS(CHIPS)':
 'VSS1804': CDS_PINID='VSS1804';
NODE_NAME     U1 V69
 '@S9S_MB_2U_LIB.S9S_MB_2U(SCH_1):PAGE73_I2@PURE_QUANTA.SOCKET4677_AZIF0045P001C01CS(CHIPS)':
 'VSS1805': CDS_PINID='VSS1805';
NODE_NAME     U1 V75
 '@S9S_MB_2U_LIB.S9S_MB_2U(SCH_1):PAGE73_I2@PURE_QUANTA.SOCKET4677_AZIF0045P001C01CS(CHIPS)':
 'VSS1806': CDS_PINID='VSS1806';
NODE_NAME     U1 V91
 '@S9S_MB_2U_LIB.S9S_MB_2U(SCH_1):PAGE73_I2@PURE_QUANTA.SOCKET4677_AZIF0045P001C01CS(CHIPS)':
 'VSS1807': CDS_PINID='VSS1807';
NODE_NAME     U1 W1
 '@S9S_MB_2U_LIB.S9S_MB_2U(SCH_1):PAGE73_I2@PURE_QUANTA.SOCKET4677_AZIF0045P001C01CS(CHIPS)':
 'VSS1808': CDS_PINID='VSS1808';
NODE_NAME     U1 W13
 '@S9S_MB_2U_LIB.S9S_MB_2U(SCH_1):PAGE73_I2@PURE_QUANTA.SOCKET4677_AZIF0045P001C01CS(CHIPS)':
 'VSS1809': CDS_PINID='VSS1809';
NODE_NAME     U1 V77
 '@S9S_MB_2U_LIB.S9S_MB_2U(SCH_1):PAGE73_I2@PURE_QUANTA.SOCKET4677_AZIF0045P001C01CS(CHIPS)':
 'VSS1810': CDS_PINID='VSS1810';
NODE_NAME     U1 V79
 '@S9S_MB_2U_LIB.S9S_MB_2U(SCH_1):PAGE73_I2@PURE_QUANTA.SOCKET4677_AZIF0045P001C01CS(CHIPS)':
 'VSS1811': CDS_PINID='VSS1811';
NODE_NAME     U1 V8
 '@S9S_MB_2U_LIB.S9S_MB_2U(SCH_1):PAGE73_I2@PURE_QUANTA.SOCKET4677_AZIF0045P001C01CS(CHIPS)':
 'VSS1812': CDS_PINID='VSS1812';
NODE_NAME     U1 V87
 '@S9S_MB_2U_LIB.S9S_MB_2U(SCH_1):PAGE73_I2@PURE_QUANTA.SOCKET4677_AZIF0045P001C01CS(CHIPS)':
 'VSS1813': CDS_PINID='VSS1813';
NODE_NAME     U1 W5
 '@S9S_MB_2U_LIB.S9S_MB_2U(SCH_1):PAGE73_I2@PURE_QUANTA.SOCKET4677_AZIF0045P001C01CS(CHIPS)':
 'VSS1814': CDS_PINID='VSS1814';
NODE_NAME     U1 W52
 '@S9S_MB_2U_LIB.S9S_MB_2U(SCH_1):PAGE73_I2@PURE_QUANTA.SOCKET4677_AZIF0045P001C01CS(CHIPS)':
 'VSS1815': CDS_PINID='VSS1815';
NODE_NAME     U1 W39
 '@S9S_MB_2U_LIB.S9S_MB_2U(SCH_1):PAGE73_I2@PURE_QUANTA.SOCKET4677_AZIF0045P001C01CS(CHIPS)':
 'VSS1816': CDS_PINID='VSS1816';
NODE_NAME     U1 W84
 '@S9S_MB_2U_LIB.S9S_MB_2U(SCH_1):PAGE73_I2@PURE_QUANTA.SOCKET4677_AZIF0045P001C01CS(CHIPS)':
 'VSS1817': CDS_PINID='VSS1817';
NODE_NAME     U1 W88
 '@S9S_MB_2U_LIB.S9S_MB_2U(SCH_1):PAGE73_I2@PURE_QUANTA.SOCKET4677_AZIF0045P001C01CS(CHIPS)':
 'VSS1818': CDS_PINID='VSS1818';
NODE_NAME     U1 W9
 '@S9S_MB_2U_LIB.S9S_MB_2U(SCH_1):PAGE73_I2@PURE_QUANTA.SOCKET4677_AZIF0045P001C01CS(CHIPS)':
 'VSS1819': CDS_PINID='VSS1819';
NODE_NAME     U1 Y12
 '@S9S_MB_2U_LIB.S9S_MB_2U(SCH_1):PAGE73_I2@PURE_QUANTA.SOCKET4677_AZIF0045P001C01CS(CHIPS)':
 'VSS1820': CDS_PINID='VSS1820';
NODE_NAME     U1 Y16
 '@S9S_MB_2U_LIB.S9S_MB_2U(SCH_1):PAGE73_I2@PURE_QUANTA.SOCKET4677_AZIF0045P001C01CS(CHIPS)':
 'VSS1821': CDS_PINID='VSS1821';
NODE_NAME     U1 Y18
 '@S9S_MB_2U_LIB.S9S_MB_2U(SCH_1):PAGE73_I2@PURE_QUANTA.SOCKET4677_AZIF0045P001C01CS(CHIPS)':
 'VSS1822': CDS_PINID='VSS1822';
NODE_NAME     U1 Y24
 '@S9S_MB_2U_LIB.S9S_MB_2U(SCH_1):PAGE73_I2@PURE_QUANTA.SOCKET4677_AZIF0045P001C01CS(CHIPS)':
 'VSS1823': CDS_PINID='VSS1823';
NODE_NAME     U1 Y30
 '@S9S_MB_2U_LIB.S9S_MB_2U(SCH_1):PAGE73_I2@PURE_QUANTA.SOCKET4677_AZIF0045P001C01CS(CHIPS)':
 'VSS1824': CDS_PINID='VSS1824';
NODE_NAME     U1 Y36
 '@S9S_MB_2U_LIB.S9S_MB_2U(SCH_1):PAGE73_I2@PURE_QUANTA.SOCKET4677_AZIF0045P001C01CS(CHIPS)':
 'VSS1825': CDS_PINID='VSS1825';
NODE_NAME     U1 Y4
 '@S9S_MB_2U_LIB.S9S_MB_2U(SCH_1):PAGE73_I2@PURE_QUANTA.SOCKET4677_AZIF0045P001C01CS(CHIPS)':
 'VSS1826': CDS_PINID='VSS1826';
NODE_NAME     U1 Y42
 '@S9S_MB_2U_LIB.S9S_MB_2U(SCH_1):PAGE73_I2@PURE_QUANTA.SOCKET4677_AZIF0045P001C01CS(CHIPS)':
 'VSS1827': CDS_PINID='VSS1827';
NODE_NAME     U1 Y61
 '@S9S_MB_2U_LIB.S9S_MB_2U(SCH_1):PAGE73_I2@PURE_QUANTA.SOCKET4677_AZIF0045P001C01CS(CHIPS)':
 'VSS1828': CDS_PINID='VSS1828';
NODE_NAME     U1 Y67
 '@S9S_MB_2U_LIB.S9S_MB_2U(SCH_1):PAGE73_I2@PURE_QUANTA.SOCKET4677_AZIF0045P001C01CS(CHIPS)':
 'VSS1829': CDS_PINID='VSS1829';
NODE_NAME     U1 Y49
 '@S9S_MB_2U_LIB.S9S_MB_2U(SCH_1):PAGE73_I2@PURE_QUANTA.SOCKET4677_AZIF0045P001C01CS(CHIPS)':
 'VSS1830': CDS_PINID='VSS1830';
NODE_NAME     U1 Y55
 '@S9S_MB_2U_LIB.S9S_MB_2U(SCH_1):PAGE73_I2@PURE_QUANTA.SOCKET4677_AZIF0045P001C01CS(CHIPS)':
 'VSS1831': CDS_PINID='VSS1831';
NODE_NAME     U1 Y8
 '@S9S_MB_2U_LIB.S9S_MB_2U(SCH_1):PAGE73_I2@PURE_QUANTA.SOCKET4677_AZIF0045P001C01CS(CHIPS)':
 'VSS1832': CDS_PINID='VSS1832';
NODE_NAME     U1 Y73
 '@S9S_MB_2U_LIB.S9S_MB_2U(SCH_1):PAGE73_I2@PURE_QUANTA.SOCKET4677_AZIF0045P001C01CS(CHIPS)':
 'VSS1833': CDS_PINID='VSS1833';
NODE_NAME     U1 E52
 '@S9S_MB_2U_LIB.S9S_MB_2U(SCH_1):PAGE73_I5@PURE_QUANTA.SOCKET4677_AZIF0045P001C01CS(CHIPS)':
 'VSS1126': CDS_PINID='VSS1126';
NODE_NAME     U1 E74
 '@S9S_MB_2U_LIB.S9S_MB_2U(SCH_1):PAGE73_I5@PURE_QUANTA.SOCKET4677_AZIF0045P001C01CS(CHIPS)':
 'VSS1129': CDS_PINID='VSS1129';
NODE_NAME     U1 E78
 '@S9S_MB_2U_LIB.S9S_MB_2U(SCH_1):PAGE73_I5@PURE_QUANTA.SOCKET4677_AZIF0045P001C01CS(CHIPS)':
 'VSS1131': CDS_PINID='VSS1131';
NODE_NAME     U1 E76
 '@S9S_MB_2U_LIB.S9S_MB_2U(SCH_1):PAGE73_I5@PURE_QUANTA.SOCKET4677_AZIF0045P001C01CS(CHIPS)':
 'VSS1272': CDS_PINID='VSS1272';
NODE_NAME     U1 E86
 '@S9S_MB_2U_LIB.S9S_MB_2U(SCH_1):PAGE73_I5@PURE_QUANTA.SOCKET4677_AZIF0045P001C01CS(CHIPS)':
 'VSS1273': CDS_PINID='VSS1273';
NODE_NAME     U1 F12
 '@S9S_MB_2U_LIB.S9S_MB_2U(SCH_1):PAGE73_I5@PURE_QUANTA.SOCKET4677_AZIF0045P001C01CS(CHIPS)':
 'VSS1494': CDS_PINID='VSS1494';
NODE_NAME     U1 F18
 '@S9S_MB_2U_LIB.S9S_MB_2U(SCH_1):PAGE73_I5@PURE_QUANTA.SOCKET4677_AZIF0045P001C01CS(CHIPS)':
 'VSS1495': CDS_PINID='VSS1495';
NODE_NAME     U1 F42
 '@S9S_MB_2U_LIB.S9S_MB_2U(SCH_1):PAGE73_I5@PURE_QUANTA.SOCKET4677_AZIF0045P001C01CS(CHIPS)':
 'VSS1502': CDS_PINID='VSS1502';
NODE_NAME     U1 F55
 '@S9S_MB_2U_LIB.S9S_MB_2U(SCH_1):PAGE73_I5@PURE_QUANTA.SOCKET4677_AZIF0045P001C01CS(CHIPS)':
 'VSS1504': CDS_PINID='VSS1504';
NODE_NAME     U1 F6
 '@S9S_MB_2U_LIB.S9S_MB_2U(SCH_1):PAGE73_I5@PURE_QUANTA.SOCKET4677_AZIF0045P001C01CS(CHIPS)':
 'VSS1507': CDS_PINID='VSS1507';
NODE_NAME     U1 F61
 '@S9S_MB_2U_LIB.S9S_MB_2U(SCH_1):PAGE73_I5@PURE_QUANTA.SOCKET4677_AZIF0045P001C01CS(CHIPS)':
 'VSS1508': CDS_PINID='VSS1508';
NODE_NAME     U1 F67
 '@S9S_MB_2U_LIB.S9S_MB_2U(SCH_1):PAGE73_I5@PURE_QUANTA.SOCKET4677_AZIF0045P001C01CS(CHIPS)':
 'VSS1509': CDS_PINID='VSS1509';
NODE_NAME     U1 F73
 '@S9S_MB_2U_LIB.S9S_MB_2U(SCH_1):PAGE73_I5@PURE_QUANTA.SOCKET4677_AZIF0045P001C01CS(CHIPS)':
 'VSS1510': CDS_PINID='VSS1510';
NODE_NAME     U1 F79
 '@S9S_MB_2U_LIB.S9S_MB_2U(SCH_1):PAGE73_I5@PURE_QUANTA.SOCKET4677_AZIF0045P001C01CS(CHIPS)':
 'VSS1511': CDS_PINID='VSS1511';
NODE_NAME     U1 G11
 '@S9S_MB_2U_LIB.S9S_MB_2U(SCH_1):PAGE73_I5@PURE_QUANTA.SOCKET4677_AZIF0045P001C01CS(CHIPS)':
 'VSS1514': CDS_PINID='VSS1514';
NODE_NAME     U1 G17
 '@S9S_MB_2U_LIB.S9S_MB_2U(SCH_1):PAGE73_I5@PURE_QUANTA.SOCKET4677_AZIF0045P001C01CS(CHIPS)':
 'VSS1516': CDS_PINID='VSS1516';
NODE_NAME     U1 G25
 '@S9S_MB_2U_LIB.S9S_MB_2U(SCH_1):PAGE73_I5@PURE_QUANTA.SOCKET4677_AZIF0045P001C01CS(CHIPS)':
 'VSS1519': CDS_PINID='VSS1519';
NODE_NAME     U1 G3
 '@S9S_MB_2U_LIB.S9S_MB_2U(SCH_1):PAGE73_I5@PURE_QUANTA.SOCKET4677_AZIF0045P001C01CS(CHIPS)':
 'VSS1521': CDS_PINID='VSS1521';
NODE_NAME     U1 G35
 '@S9S_MB_2U_LIB.S9S_MB_2U(SCH_1):PAGE73_I5@PURE_QUANTA.SOCKET4677_AZIF0045P001C01CS(CHIPS)':
 'VSS1523': CDS_PINID='VSS1523';
NODE_NAME     U1 G48
 '@S9S_MB_2U_LIB.S9S_MB_2U(SCH_1):PAGE73_I5@PURE_QUANTA.SOCKET4677_AZIF0045P001C01CS(CHIPS)':
 'VSS1527': CDS_PINID='VSS1527';
NODE_NAME     U1 G60
 '@S9S_MB_2U_LIB.S9S_MB_2U(SCH_1):PAGE73_I5@PURE_QUANTA.SOCKET4677_AZIF0045P001C01CS(CHIPS)':
 'VSS1532': CDS_PINID='VSS1532';
NODE_NAME     U1 G66
 '@S9S_MB_2U_LIB.S9S_MB_2U(SCH_1):PAGE73_I5@PURE_QUANTA.SOCKET4677_AZIF0045P001C01CS(CHIPS)':
 'VSS1534': CDS_PINID='VSS1534';
NODE_NAME     U1 G68
 '@S9S_MB_2U_LIB.S9S_MB_2U(SCH_1):PAGE73_I5@PURE_QUANTA.SOCKET4677_AZIF0045P001C01CS(CHIPS)':
 'VSS1535': CDS_PINID='VSS1535';
NODE_NAME     U1 G7
 '@S9S_MB_2U_LIB.S9S_MB_2U(SCH_1):PAGE73_I5@PURE_QUANTA.SOCKET4677_AZIF0045P001C01CS(CHIPS)':
 'VSS1536': CDS_PINID='VSS1536';
NODE_NAME     U1 G74
 '@S9S_MB_2U_LIB.S9S_MB_2U(SCH_1):PAGE73_I5@PURE_QUANTA.SOCKET4677_AZIF0045P001C01CS(CHIPS)':
 'VSS1538': CDS_PINID='VSS1538';
NODE_NAME     U1 H14
 '@S9S_MB_2U_LIB.S9S_MB_2U(SCH_1):PAGE73_I5@PURE_QUANTA.SOCKET4677_AZIF0045P001C01CS(CHIPS)':
 'VSS1544': CDS_PINID='VSS1544';
NODE_NAME     U1 H2
 '@S9S_MB_2U_LIB.S9S_MB_2U(SCH_1):PAGE73_I5@PURE_QUANTA.SOCKET4677_AZIF0045P001C01CS(CHIPS)':
 'VSS1546': CDS_PINID='VSS1546';
NODE_NAME     U1 H51
 '@S9S_MB_2U_LIB.S9S_MB_2U(SCH_1):PAGE73_I5@PURE_QUANTA.SOCKET4677_AZIF0045P001C01CS(CHIPS)':
 'VSS1558': CDS_PINID='VSS1558';
NODE_NAME     U1 H57
 '@S9S_MB_2U_LIB.S9S_MB_2U(SCH_1):PAGE73_I5@PURE_QUANTA.SOCKET4677_AZIF0045P001C01CS(CHIPS)':
 'VSS1560': CDS_PINID='VSS1560';
NODE_NAME     U1 H65
 '@S9S_MB_2U_LIB.S9S_MB_2U(SCH_1):PAGE73_I5@PURE_QUANTA.SOCKET4677_AZIF0045P001C01CS(CHIPS)':
 'VSS1564': CDS_PINID='VSS1564';
NODE_NAME     U1 H75
 '@S9S_MB_2U_LIB.S9S_MB_2U(SCH_1):PAGE73_I5@PURE_QUANTA.SOCKET4677_AZIF0045P001C01CS(CHIPS)':
 'VSS1567': CDS_PINID='VSS1567';
NODE_NAME     U1 F24
 '@S9S_MB_2U_LIB.S9S_MB_2U(SCH_1):PAGE73_I5@PURE_QUANTA.SOCKET4677_AZIF0045P001C01CS(CHIPS)':
 'VSS1570': CDS_PINID='VSS1570';
NODE_NAME     U1 F30
 '@S9S_MB_2U_LIB.S9S_MB_2U(SCH_1):PAGE73_I5@PURE_QUANTA.SOCKET4677_AZIF0045P001C01CS(CHIPS)':
 'VSS1571': CDS_PINID='VSS1571';
NODE_NAME     U1 F36
 '@S9S_MB_2U_LIB.S9S_MB_2U(SCH_1):PAGE73_I5@PURE_QUANTA.SOCKET4677_AZIF0045P001C01CS(CHIPS)':
 'VSS1572': CDS_PINID='VSS1572';
NODE_NAME     U1 F4
 '@S9S_MB_2U_LIB.S9S_MB_2U(SCH_1):PAGE73_I5@PURE_QUANTA.SOCKET4677_AZIF0045P001C01CS(CHIPS)':
 'VSS1573': CDS_PINID='VSS1573';
NODE_NAME     U1 F49
 '@S9S_MB_2U_LIB.S9S_MB_2U(SCH_1):PAGE73_I5@PURE_QUANTA.SOCKET4677_AZIF0045P001C01CS(CHIPS)':
 'VSS1574': CDS_PINID='VSS1574';
NODE_NAME     U1 J21
 '@S9S_MB_2U_LIB.S9S_MB_2U(SCH_1):PAGE73_I5@PURE_QUANTA.SOCKET4677_AZIF0045P001C01CS(CHIPS)':
 'VSS1575': CDS_PINID='VSS1575';
NODE_NAME     U1 F83
 '@S9S_MB_2U_LIB.S9S_MB_2U(SCH_1):PAGE73_I5@PURE_QUANTA.SOCKET4677_AZIF0045P001C01CS(CHIPS)':
 'VSS1576': CDS_PINID='VSS1576';
NODE_NAME     U1 F89
 '@S9S_MB_2U_LIB.S9S_MB_2U(SCH_1):PAGE73_I5@PURE_QUANTA.SOCKET4677_AZIF0045P001C01CS(CHIPS)':
 'VSS1577': CDS_PINID='VSS1577';
NODE_NAME     U1 G13
 '@S9S_MB_2U_LIB.S9S_MB_2U(SCH_1):PAGE73_I5@PURE_QUANTA.SOCKET4677_AZIF0045P001C01CS(CHIPS)':
 'VSS1578': CDS_PINID='VSS1578';
NODE_NAME     U1 G19
 '@S9S_MB_2U_LIB.S9S_MB_2U(SCH_1):PAGE73_I5@PURE_QUANTA.SOCKET4677_AZIF0045P001C01CS(CHIPS)':
 'VSS1579': CDS_PINID='VSS1579';
NODE_NAME     U1 J39
 '@S9S_MB_2U_LIB.S9S_MB_2U(SCH_1):PAGE73_I5@PURE_QUANTA.SOCKET4677_AZIF0045P001C01CS(CHIPS)':
 'VSS1580': CDS_PINID='VSS1580';
NODE_NAME     U1 G23
 '@S9S_MB_2U_LIB.S9S_MB_2U(SCH_1):PAGE73_I5@PURE_QUANTA.SOCKET4677_AZIF0045P001C01CS(CHIPS)':
 'VSS1581': CDS_PINID='VSS1581';
NODE_NAME     U1 J5
 '@S9S_MB_2U_LIB.S9S_MB_2U(SCH_1):PAGE73_I5@PURE_QUANTA.SOCKET4677_AZIF0045P001C01CS(CHIPS)':
 'VSS1582': CDS_PINID='VSS1582';
NODE_NAME     U1 G29
 '@S9S_MB_2U_LIB.S9S_MB_2U(SCH_1):PAGE73_I5@PURE_QUANTA.SOCKET4677_AZIF0045P001C01CS(CHIPS)':
 'VSS1583': CDS_PINID='VSS1583';
NODE_NAME     U1 G31
 '@S9S_MB_2U_LIB.S9S_MB_2U(SCH_1):PAGE73_I5@PURE_QUANTA.SOCKET4677_AZIF0045P001C01CS(CHIPS)':
 'VSS1584': CDS_PINID='VSS1584';
NODE_NAME     U1 G37
 '@S9S_MB_2U_LIB.S9S_MB_2U(SCH_1):PAGE73_I5@PURE_QUANTA.SOCKET4677_AZIF0045P001C01CS(CHIPS)':
 'VSS1585': CDS_PINID='VSS1585';
NODE_NAME     U1 G41
 '@S9S_MB_2U_LIB.S9S_MB_2U(SCH_1):PAGE73_I5@PURE_QUANTA.SOCKET4677_AZIF0045P001C01CS(CHIPS)':
 'VSS1586': CDS_PINID='VSS1586';
NODE_NAME     U1 J64
 '@S9S_MB_2U_LIB.S9S_MB_2U(SCH_1):PAGE73_I5@PURE_QUANTA.SOCKET4677_AZIF0045P001C01CS(CHIPS)':
 'VSS1587': CDS_PINID='VSS1587';
NODE_NAME     U1 G43
 '@S9S_MB_2U_LIB.S9S_MB_2U(SCH_1):PAGE73_I5@PURE_QUANTA.SOCKET4677_AZIF0045P001C01CS(CHIPS)':
 'VSS1588': CDS_PINID='VSS1588';
NODE_NAME     U1 J70
 '@S9S_MB_2U_LIB.S9S_MB_2U(SCH_1):PAGE73_I5@PURE_QUANTA.SOCKET4677_AZIF0045P001C01CS(CHIPS)':
 'VSS1589': CDS_PINID='VSS1589';
NODE_NAME     U1 G50
 '@S9S_MB_2U_LIB.S9S_MB_2U(SCH_1):PAGE73_I5@PURE_QUANTA.SOCKET4677_AZIF0045P001C01CS(CHIPS)':
 'VSS1590': CDS_PINID='VSS1590';
NODE_NAME     U1 G54
 '@S9S_MB_2U_LIB.S9S_MB_2U(SCH_1):PAGE73_I5@PURE_QUANTA.SOCKET4677_AZIF0045P001C01CS(CHIPS)':
 'VSS1591': CDS_PINID='VSS1591';
NODE_NAME     U1 G56
 '@S9S_MB_2U_LIB.S9S_MB_2U(SCH_1):PAGE73_I5@PURE_QUANTA.SOCKET4677_AZIF0045P001C01CS(CHIPS)':
 'VSS1592': CDS_PINID='VSS1592';
NODE_NAME     U1 G62
 '@S9S_MB_2U_LIB.S9S_MB_2U(SCH_1):PAGE73_I5@PURE_QUANTA.SOCKET4677_AZIF0045P001C01CS(CHIPS)':
 'VSS1593': CDS_PINID='VSS1593';
NODE_NAME     U1 G72
 '@S9S_MB_2U_LIB.S9S_MB_2U(SCH_1):PAGE73_I5@PURE_QUANTA.SOCKET4677_AZIF0045P001C01CS(CHIPS)':
 'VSS1594': CDS_PINID='VSS1594';
NODE_NAME     U1 J88
 '@S9S_MB_2U_LIB.S9S_MB_2U(SCH_1):PAGE73_I5@PURE_QUANTA.SOCKET4677_AZIF0045P001C01CS(CHIPS)':
 'VSS1595': CDS_PINID='VSS1595';
NODE_NAME     U1 J9
 '@S9S_MB_2U_LIB.S9S_MB_2U(SCH_1):PAGE73_I5@PURE_QUANTA.SOCKET4677_AZIF0045P001C01CS(CHIPS)':
 'VSS1596': CDS_PINID='VSS1596';
NODE_NAME     U1 K12
 '@S9S_MB_2U_LIB.S9S_MB_2U(SCH_1):PAGE73_I5@PURE_QUANTA.SOCKET4677_AZIF0045P001C01CS(CHIPS)':
 'VSS1597': CDS_PINID='VSS1597';
NODE_NAME     U1 K14
 '@S9S_MB_2U_LIB.S9S_MB_2U(SCH_1):PAGE73_I5@PURE_QUANTA.SOCKET4677_AZIF0045P001C01CS(CHIPS)':
 'VSS1598': CDS_PINID='VSS1598';
NODE_NAME     U1 K2
 '@S9S_MB_2U_LIB.S9S_MB_2U(SCH_1):PAGE73_I5@PURE_QUANTA.SOCKET4677_AZIF0045P001C01CS(CHIPS)':
 'VSS1599': CDS_PINID='VSS1599';
NODE_NAME     U1 G84
 '@S9S_MB_2U_LIB.S9S_MB_2U(SCH_1):PAGE73_I5@PURE_QUANTA.SOCKET4677_AZIF0045P001C01CS(CHIPS)':
 'VSS1600': CDS_PINID='VSS1600';
NODE_NAME     U1 G88
 '@S9S_MB_2U_LIB.S9S_MB_2U(SCH_1):PAGE73_I5@PURE_QUANTA.SOCKET4677_AZIF0045P001C01CS(CHIPS)':
 'VSS1601': CDS_PINID='VSS1601';
NODE_NAME     U1 K42
 '@S9S_MB_2U_LIB.S9S_MB_2U(SCH_1):PAGE73_I5@PURE_QUANTA.SOCKET4677_AZIF0045P001C01CS(CHIPS)':
 'VSS1602': CDS_PINID='VSS1602';
NODE_NAME     U1 K49
 '@S9S_MB_2U_LIB.S9S_MB_2U(SCH_1):PAGE73_I5@PURE_QUANTA.SOCKET4677_AZIF0045P001C01CS(CHIPS)':
 'VSS1603': CDS_PINID='VSS1603';
NODE_NAME     U1 G90
 '@S9S_MB_2U_LIB.S9S_MB_2U(SCH_1):PAGE73_I5@PURE_QUANTA.SOCKET4677_AZIF0045P001C01CS(CHIPS)':
 'VSS1604': CDS_PINID='VSS1604';
NODE_NAME     U1 H10
 '@S9S_MB_2U_LIB.S9S_MB_2U(SCH_1):PAGE73_I5@PURE_QUANTA.SOCKET4677_AZIF0045P001C01CS(CHIPS)':
 'VSS1605': CDS_PINID='VSS1605';
NODE_NAME     U1 H16
 '@S9S_MB_2U_LIB.S9S_MB_2U(SCH_1):PAGE73_I5@PURE_QUANTA.SOCKET4677_AZIF0045P001C01CS(CHIPS)':
 'VSS1606': CDS_PINID='VSS1606';
NODE_NAME     U1 H20
 '@S9S_MB_2U_LIB.S9S_MB_2U(SCH_1):PAGE73_I5@PURE_QUANTA.SOCKET4677_AZIF0045P001C01CS(CHIPS)':
 'VSS1607': CDS_PINID='VSS1607';
NODE_NAME     U1 H22
 '@S9S_MB_2U_LIB.S9S_MB_2U(SCH_1):PAGE73_I5@PURE_QUANTA.SOCKET4677_AZIF0045P001C01CS(CHIPS)':
 'VSS1608': CDS_PINID='VSS1608';
NODE_NAME     U1 H26
 '@S9S_MB_2U_LIB.S9S_MB_2U(SCH_1):PAGE73_I5@PURE_QUANTA.SOCKET4677_AZIF0045P001C01CS(CHIPS)':
 'VSS1609': CDS_PINID='VSS1609';
NODE_NAME     U1 H28
 '@S9S_MB_2U_LIB.S9S_MB_2U(SCH_1):PAGE73_I5@PURE_QUANTA.SOCKET4677_AZIF0045P001C01CS(CHIPS)':
 'VSS1610': CDS_PINID='VSS1610';
NODE_NAME     U1 H32
 '@S9S_MB_2U_LIB.S9S_MB_2U(SCH_1):PAGE73_I5@PURE_QUANTA.SOCKET4677_AZIF0045P001C01CS(CHIPS)':
 'VSS1611': CDS_PINID='VSS1611';
NODE_NAME     U1 H34
 '@S9S_MB_2U_LIB.S9S_MB_2U(SCH_1):PAGE73_I5@PURE_QUANTA.SOCKET4677_AZIF0045P001C01CS(CHIPS)':
 'VSS1612': CDS_PINID='VSS1612';
NODE_NAME     U1 H38
 '@S9S_MB_2U_LIB.S9S_MB_2U(SCH_1):PAGE73_I5@PURE_QUANTA.SOCKET4677_AZIF0045P001C01CS(CHIPS)':
 'VSS1613': CDS_PINID='VSS1613';
NODE_NAME     U1 L19
 '@S9S_MB_2U_LIB.S9S_MB_2U(SCH_1):PAGE73_I5@PURE_QUANTA.SOCKET4677_AZIF0045P001C01CS(CHIPS)':
 'VSS1614': CDS_PINID='VSS1614';
NODE_NAME     U1 H4
 '@S9S_MB_2U_LIB.S9S_MB_2U(SCH_1):PAGE73_I5@PURE_QUANTA.SOCKET4677_AZIF0045P001C01CS(CHIPS)':
 'VSS1615': CDS_PINID='VSS1615';
NODE_NAME     U1 H40
 '@S9S_MB_2U_LIB.S9S_MB_2U(SCH_1):PAGE73_I5@PURE_QUANTA.SOCKET4677_AZIF0045P001C01CS(CHIPS)':
 'VSS1616': CDS_PINID='VSS1616';
NODE_NAME     U1 H44
 '@S9S_MB_2U_LIB.S9S_MB_2U(SCH_1):PAGE73_I5@PURE_QUANTA.SOCKET4677_AZIF0045P001C01CS(CHIPS)':
 'VSS1617': CDS_PINID='VSS1617';
NODE_NAME     U1 H47
 '@S9S_MB_2U_LIB.S9S_MB_2U(SCH_1):PAGE73_I5@PURE_QUANTA.SOCKET4677_AZIF0045P001C01CS(CHIPS)':
 'VSS1618': CDS_PINID='VSS1618';
NODE_NAME     U1 H53
 '@S9S_MB_2U_LIB.S9S_MB_2U(SCH_1):PAGE73_I5@PURE_QUANTA.SOCKET4677_AZIF0045P001C01CS(CHIPS)':
 'VSS1619': CDS_PINID='VSS1619';
NODE_NAME     U1 H59
 '@S9S_MB_2U_LIB.S9S_MB_2U(SCH_1):PAGE73_I5@PURE_QUANTA.SOCKET4677_AZIF0045P001C01CS(CHIPS)':
 'VSS1620': CDS_PINID='VSS1620';
NODE_NAME     U1 H6
 '@S9S_MB_2U_LIB.S9S_MB_2U(SCH_1):PAGE73_I5@PURE_QUANTA.SOCKET4677_AZIF0045P001C01CS(CHIPS)':
 'VSS1621': CDS_PINID='VSS1621';
NODE_NAME     U1 H63
 '@S9S_MB_2U_LIB.S9S_MB_2U(SCH_1):PAGE73_I5@PURE_QUANTA.SOCKET4677_AZIF0045P001C01CS(CHIPS)':
 'VSS1622': CDS_PINID='VSS1622';
NODE_NAME     U1 H69
 '@S9S_MB_2U_LIB.S9S_MB_2U(SCH_1):PAGE73_I5@PURE_QUANTA.SOCKET4677_AZIF0045P001C01CS(CHIPS)':
 'VSS1623': CDS_PINID='VSS1623';
NODE_NAME     U1 H71
 '@S9S_MB_2U_LIB.S9S_MB_2U(SCH_1):PAGE73_I5@PURE_QUANTA.SOCKET4677_AZIF0045P001C01CS(CHIPS)':
 'VSS1624': CDS_PINID='VSS1624';
NODE_NAME     U1 H79
 '@S9S_MB_2U_LIB.S9S_MB_2U(SCH_1):PAGE73_I5@PURE_QUANTA.SOCKET4677_AZIF0045P001C01CS(CHIPS)':
 'VSS1625': CDS_PINID='VSS1625';
NODE_NAME     U1 H8
 '@S9S_MB_2U_LIB.S9S_MB_2U(SCH_1):PAGE73_I5@PURE_QUANTA.SOCKET4677_AZIF0045P001C01CS(CHIPS)':
 'VSS1626': CDS_PINID='VSS1626';
NODE_NAME     U1 H81
 '@S9S_MB_2U_LIB.S9S_MB_2U(SCH_1):PAGE73_I5@PURE_QUANTA.SOCKET4677_AZIF0045P001C01CS(CHIPS)':
 'VSS1627': CDS_PINID='VSS1627';
NODE_NAME     U1 J15
 '@S9S_MB_2U_LIB.S9S_MB_2U(SCH_1):PAGE73_I5@PURE_QUANTA.SOCKET4677_AZIF0045P001C01CS(CHIPS)':
 'VSS1628': CDS_PINID='VSS1628';
NODE_NAME     U1 J27
 '@S9S_MB_2U_LIB.S9S_MB_2U(SCH_1):PAGE73_I5@PURE_QUANTA.SOCKET4677_AZIF0045P001C01CS(CHIPS)':
 'VSS1629': CDS_PINID='VSS1629';
NODE_NAME     U1 J33
 '@S9S_MB_2U_LIB.S9S_MB_2U(SCH_1):PAGE73_I5@PURE_QUANTA.SOCKET4677_AZIF0045P001C01CS(CHIPS)':
 'VSS1630': CDS_PINID='VSS1630';
NODE_NAME     U1 J45
 '@S9S_MB_2U_LIB.S9S_MB_2U(SCH_1):PAGE73_I5@PURE_QUANTA.SOCKET4677_AZIF0045P001C01CS(CHIPS)':
 'VSS1631': CDS_PINID='VSS1631';
NODE_NAME     U1 J52
 '@S9S_MB_2U_LIB.S9S_MB_2U(SCH_1):PAGE73_I5@PURE_QUANTA.SOCKET4677_AZIF0045P001C01CS(CHIPS)':
 'VSS1632': CDS_PINID='VSS1632';
NODE_NAME     U1 J58
 '@S9S_MB_2U_LIB.S9S_MB_2U(SCH_1):PAGE73_I5@PURE_QUANTA.SOCKET4677_AZIF0045P001C01CS(CHIPS)':
 'VSS1633': CDS_PINID='VSS1633';
NODE_NAME     U1 L58
 '@S9S_MB_2U_LIB.S9S_MB_2U(SCH_1):PAGE73_I5@PURE_QUANTA.SOCKET4677_AZIF0045P001C01CS(CHIPS)':
 'VSS1634': CDS_PINID='VSS1634';
NODE_NAME     U1 J76
 '@S9S_MB_2U_LIB.S9S_MB_2U(SCH_1):PAGE73_I5@PURE_QUANTA.SOCKET4677_AZIF0045P001C01CS(CHIPS)':
 'VSS1635': CDS_PINID='VSS1635';
NODE_NAME     U1 J78
 '@S9S_MB_2U_LIB.S9S_MB_2U(SCH_1):PAGE73_I5@PURE_QUANTA.SOCKET4677_AZIF0045P001C01CS(CHIPS)':
 'VSS1636': CDS_PINID='VSS1636';
NODE_NAME     U1 J84
 '@S9S_MB_2U_LIB.S9S_MB_2U(SCH_1):PAGE73_I5@PURE_QUANTA.SOCKET4677_AZIF0045P001C01CS(CHIPS)':
 'VSS1637': CDS_PINID='VSS1637';
NODE_NAME     U1 J86
 '@S9S_MB_2U_LIB.S9S_MB_2U(SCH_1):PAGE73_I5@PURE_QUANTA.SOCKET4677_AZIF0045P001C01CS(CHIPS)':
 'VSS1638': CDS_PINID='VSS1638';
NODE_NAME     U1 K77
 '@S9S_MB_2U_LIB.S9S_MB_2U(SCH_1):PAGE73_I5@PURE_QUANTA.SOCKET4677_AZIF0045P001C01CS(CHIPS)':
 'VSS1639': CDS_PINID='VSS1639';
NODE_NAME     U1 L70
 '@S9S_MB_2U_LIB.S9S_MB_2U(SCH_1):PAGE73_I5@PURE_QUANTA.SOCKET4677_AZIF0045P001C01CS(CHIPS)':
 'VSS1640': CDS_PINID='VSS1640';
NODE_NAME     U1 K8
 '@S9S_MB_2U_LIB.S9S_MB_2U(SCH_1):PAGE73_I5@PURE_QUANTA.SOCKET4677_AZIF0045P001C01CS(CHIPS)':
 'VSS1641': CDS_PINID='VSS1641';
NODE_NAME     U1 K83
 '@S9S_MB_2U_LIB.S9S_MB_2U(SCH_1):PAGE73_I5@PURE_QUANTA.SOCKET4677_AZIF0045P001C01CS(CHIPS)':
 'VSS1642': CDS_PINID='VSS1642';
NODE_NAME     U1 K85
 '@S9S_MB_2U_LIB.S9S_MB_2U(SCH_1):PAGE73_I5@PURE_QUANTA.SOCKET4677_AZIF0045P001C01CS(CHIPS)':
 'VSS1643': CDS_PINID='VSS1643';
NODE_NAME     U1 L13
 '@S9S_MB_2U_LIB.S9S_MB_2U(SCH_1):PAGE73_I5@PURE_QUANTA.SOCKET4677_AZIF0045P001C01CS(CHIPS)':
 'VSS1644': CDS_PINID='VSS1644';
NODE_NAME     U1 L15
 '@S9S_MB_2U_LIB.S9S_MB_2U(SCH_1):PAGE73_I5@PURE_QUANTA.SOCKET4677_AZIF0045P001C01CS(CHIPS)':
 'VSS1645': CDS_PINID='VSS1645';
NODE_NAME     U1 L88
 '@S9S_MB_2U_LIB.S9S_MB_2U(SCH_1):PAGE73_I5@PURE_QUANTA.SOCKET4677_AZIF0045P001C01CS(CHIPS)':
 'VSS1646': CDS_PINID='VSS1646';
NODE_NAME     U1 L9
 '@S9S_MB_2U_LIB.S9S_MB_2U(SCH_1):PAGE73_I5@PURE_QUANTA.SOCKET4677_AZIF0045P001C01CS(CHIPS)':
 'VSS1647': CDS_PINID='VSS1647';
NODE_NAME     U1 L90
 '@S9S_MB_2U_LIB.S9S_MB_2U(SCH_1):PAGE73_I5@PURE_QUANTA.SOCKET4677_AZIF0045P001C01CS(CHIPS)':
 'VSS1648': CDS_PINID='VSS1648';
NODE_NAME     U1 M12
 '@S9S_MB_2U_LIB.S9S_MB_2U(SCH_1):PAGE73_I5@PURE_QUANTA.SOCKET4677_AZIF0045P001C01CS(CHIPS)':
 'VSS1649': CDS_PINID='VSS1649';
NODE_NAME     U1 L17
 '@S9S_MB_2U_LIB.S9S_MB_2U(SCH_1):PAGE73_I5@PURE_QUANTA.SOCKET4677_AZIF0045P001C01CS(CHIPS)':
 'VSS1650': CDS_PINID='VSS1650';
NODE_NAME     U1 L21
 '@S9S_MB_2U_LIB.S9S_MB_2U(SCH_1):PAGE73_I5@PURE_QUANTA.SOCKET4677_AZIF0045P001C01CS(CHIPS)':
 'VSS1651': CDS_PINID='VSS1651';
NODE_NAME     U1 M4
 '@S9S_MB_2U_LIB.S9S_MB_2U(SCH_1):PAGE73_I5@PURE_QUANTA.SOCKET4677_AZIF0045P001C01CS(CHIPS)':
 'VSS1652': CDS_PINID='VSS1652';
NODE_NAME     U1 M42
 '@S9S_MB_2U_LIB.S9S_MB_2U(SCH_1):PAGE73_I5@PURE_QUANTA.SOCKET4677_AZIF0045P001C01CS(CHIPS)':
 'VSS1653': CDS_PINID='VSS1653';
NODE_NAME     U1 M49
 '@S9S_MB_2U_LIB.S9S_MB_2U(SCH_1):PAGE73_I5@PURE_QUANTA.SOCKET4677_AZIF0045P001C01CS(CHIPS)':
 'VSS1654': CDS_PINID='VSS1654';
NODE_NAME     U1 L23
 '@S9S_MB_2U_LIB.S9S_MB_2U(SCH_1):PAGE73_I5@PURE_QUANTA.SOCKET4677_AZIF0045P001C01CS(CHIPS)':
 'VSS1655': CDS_PINID='VSS1655';
NODE_NAME     U1 L25
 '@S9S_MB_2U_LIB.S9S_MB_2U(SCH_1):PAGE73_I5@PURE_QUANTA.SOCKET4677_AZIF0045P001C01CS(CHIPS)':
 'VSS1656': CDS_PINID='VSS1656';
NODE_NAME     U1 M8
 '@S9S_MB_2U_LIB.S9S_MB_2U(SCH_1):PAGE73_I5@PURE_QUANTA.SOCKET4677_AZIF0045P001C01CS(CHIPS)':
 'VSS1657': CDS_PINID='VSS1657';
NODE_NAME     U1 L27
 '@S9S_MB_2U_LIB.S9S_MB_2U(SCH_1):PAGE73_I5@PURE_QUANTA.SOCKET4677_AZIF0045P001C01CS(CHIPS)':
 'VSS1658': CDS_PINID='VSS1658';
NODE_NAME     U1 L29
 '@S9S_MB_2U_LIB.S9S_MB_2U(SCH_1):PAGE73_I5@PURE_QUANTA.SOCKET4677_AZIF0045P001C01CS(CHIPS)':
 'VSS1659': CDS_PINID='VSS1659';
NODE_NAME     U1 L31
 '@S9S_MB_2U_LIB.S9S_MB_2U(SCH_1):PAGE73_I5@PURE_QUANTA.SOCKET4677_AZIF0045P001C01CS(CHIPS)':
 'VSS1660': CDS_PINID='VSS1660';
NODE_NAME     U1 L33
 '@S9S_MB_2U_LIB.S9S_MB_2U(SCH_1):PAGE73_I5@PURE_QUANTA.SOCKET4677_AZIF0045P001C01CS(CHIPS)':
 'VSS1661': CDS_PINID='VSS1661';
NODE_NAME     U1 L35
 '@S9S_MB_2U_LIB.S9S_MB_2U(SCH_1):PAGE73_I5@PURE_QUANTA.SOCKET4677_AZIF0045P001C01CS(CHIPS)':
 'VSS1662': CDS_PINID='VSS1662';
NODE_NAME     U1 L37
 '@S9S_MB_2U_LIB.S9S_MB_2U(SCH_1):PAGE73_I5@PURE_QUANTA.SOCKET4677_AZIF0045P001C01CS(CHIPS)':
 'VSS1663': CDS_PINID='VSS1663';
NODE_NAME     U1 N21
 '@S9S_MB_2U_LIB.S9S_MB_2U(SCH_1):PAGE73_I5@PURE_QUANTA.SOCKET4677_AZIF0045P001C01CS(CHIPS)':
 'VSS1664': CDS_PINID='VSS1664';
NODE_NAME     U1 L39
 '@S9S_MB_2U_LIB.S9S_MB_2U(SCH_1):PAGE73_I5@PURE_QUANTA.SOCKET4677_AZIF0045P001C01CS(CHIPS)':
 'VSS1665': CDS_PINID='VSS1665';
NODE_NAME     U1 L41
 '@S9S_MB_2U_LIB.S9S_MB_2U(SCH_1):PAGE73_I5@PURE_QUANTA.SOCKET4677_AZIF0045P001C01CS(CHIPS)':
 'VSS1666': CDS_PINID='VSS1666';
NODE_NAME     U1 L43
 '@S9S_MB_2U_LIB.S9S_MB_2U(SCH_1):PAGE73_I5@PURE_QUANTA.SOCKET4677_AZIF0045P001C01CS(CHIPS)':
 'VSS1667': CDS_PINID='VSS1667';
NODE_NAME     U1 L45
 '@S9S_MB_2U_LIB.S9S_MB_2U(SCH_1):PAGE73_I5@PURE_QUANTA.SOCKET4677_AZIF0045P001C01CS(CHIPS)':
 'VSS1668': CDS_PINID='VSS1668';
NODE_NAME     U1 N39
 '@S9S_MB_2U_LIB.S9S_MB_2U(SCH_1):PAGE73_I5@PURE_QUANTA.SOCKET4677_AZIF0045P001C01CS(CHIPS)':
 'VSS1669': CDS_PINID='VSS1669';
NODE_NAME     U1 L48
 '@S9S_MB_2U_LIB.S9S_MB_2U(SCH_1):PAGE73_I5@PURE_QUANTA.SOCKET4677_AZIF0045P001C01CS(CHIPS)':
 'VSS1670': CDS_PINID='VSS1670';
NODE_NAME     U1 L5
 '@S9S_MB_2U_LIB.S9S_MB_2U(SCH_1):PAGE73_I5@PURE_QUANTA.SOCKET4677_AZIF0045P001C01CS(CHIPS)':
 'VSS1671': CDS_PINID='VSS1671';
NODE_NAME     U1 L50
 '@S9S_MB_2U_LIB.S9S_MB_2U(SCH_1):PAGE73_I5@PURE_QUANTA.SOCKET4677_AZIF0045P001C01CS(CHIPS)':
 'VSS1672': CDS_PINID='VSS1672';
NODE_NAME     U1 L52
 '@S9S_MB_2U_LIB.S9S_MB_2U(SCH_1):PAGE73_I5@PURE_QUANTA.SOCKET4677_AZIF0045P001C01CS(CHIPS)':
 'VSS1673': CDS_PINID='VSS1673';
NODE_NAME     U1 L54
 '@S9S_MB_2U_LIB.S9S_MB_2U(SCH_1):PAGE73_I5@PURE_QUANTA.SOCKET4677_AZIF0045P001C01CS(CHIPS)':
 'VSS1674': CDS_PINID='VSS1674';
NODE_NAME     U1 N64
 '@S9S_MB_2U_LIB.S9S_MB_2U(SCH_1):PAGE73_I5@PURE_QUANTA.SOCKET4677_AZIF0045P001C01CS(CHIPS)':
 'VSS1675': CDS_PINID='VSS1675';
NODE_NAME     U1 L56
 '@S9S_MB_2U_LIB.S9S_MB_2U(SCH_1):PAGE73_I5@PURE_QUANTA.SOCKET4677_AZIF0045P001C01CS(CHIPS)':
 'VSS1676': CDS_PINID='VSS1676';
NODE_NAME     U1 L60
 '@S9S_MB_2U_LIB.S9S_MB_2U(SCH_1):PAGE73_I5@PURE_QUANTA.SOCKET4677_AZIF0045P001C01CS(CHIPS)':
 'VSS1677': CDS_PINID='VSS1677';
NODE_NAME     U1 L62
 '@S9S_MB_2U_LIB.S9S_MB_2U(SCH_1):PAGE73_I5@PURE_QUANTA.SOCKET4677_AZIF0045P001C01CS(CHIPS)':
 'VSS1678': CDS_PINID='VSS1678';
NODE_NAME     U1 L64
 '@S9S_MB_2U_LIB.S9S_MB_2U(SCH_1):PAGE73_I5@PURE_QUANTA.SOCKET4677_AZIF0045P001C01CS(CHIPS)':
 'VSS1679': CDS_PINID='VSS1679';
NODE_NAME     U1 L66
 '@S9S_MB_2U_LIB.S9S_MB_2U(SCH_1):PAGE73_I5@PURE_QUANTA.SOCKET4677_AZIF0045P001C01CS(CHIPS)':
 'VSS1680': CDS_PINID='VSS1680';
NODE_NAME     U1 L68
 '@S9S_MB_2U_LIB.S9S_MB_2U(SCH_1):PAGE73_I5@PURE_QUANTA.SOCKET4677_AZIF0045P001C01CS(CHIPS)':
 'VSS1681': CDS_PINID='VSS1681';
NODE_NAME     U1 L72
 '@S9S_MB_2U_LIB.S9S_MB_2U(SCH_1):PAGE73_I5@PURE_QUANTA.SOCKET4677_AZIF0045P001C01CS(CHIPS)':
 'VSS1682': CDS_PINID='VSS1682';
NODE_NAME     U1 L74
 '@S9S_MB_2U_LIB.S9S_MB_2U(SCH_1):PAGE73_I5@PURE_QUANTA.SOCKET4677_AZIF0045P001C01CS(CHIPS)':
 'VSS1683': CDS_PINID='VSS1683';
NODE_NAME     U1 L76
 '@S9S_MB_2U_LIB.S9S_MB_2U(SCH_1):PAGE73_I5@PURE_QUANTA.SOCKET4677_AZIF0045P001C01CS(CHIPS)':
 'VSS1684': CDS_PINID='VSS1684';
NODE_NAME     U1 L78
 '@S9S_MB_2U_LIB.S9S_MB_2U(SCH_1):PAGE73_I5@PURE_QUANTA.SOCKET4677_AZIF0045P001C01CS(CHIPS)':
 'VSS1685': CDS_PINID='VSS1685';
NODE_NAME     U1 M81
 '@S9S_MB_2U_LIB.S9S_MB_2U(SCH_1):PAGE73_I5@PURE_QUANTA.SOCKET4677_AZIF0045P001C01CS(CHIPS)':
 'VSS1686': CDS_PINID='VSS1686';
NODE_NAME     U1 M83
 '@S9S_MB_2U_LIB.S9S_MB_2U(SCH_1):PAGE73_I5@PURE_QUANTA.SOCKET4677_AZIF0045P001C01CS(CHIPS)':
 'VSS1687': CDS_PINID='VSS1687';
NODE_NAME     U1 N15
 '@S9S_MB_2U_LIB.S9S_MB_2U(SCH_1):PAGE73_I5@PURE_QUANTA.SOCKET4677_AZIF0045P001C01CS(CHIPS)':
 'VSS1688': CDS_PINID='VSS1688';
NODE_NAME     U1 N27
 '@S9S_MB_2U_LIB.S9S_MB_2U(SCH_1):PAGE73_I5@PURE_QUANTA.SOCKET4677_AZIF0045P001C01CS(CHIPS)':
 'VSS1689': CDS_PINID='VSS1689';
NODE_NAME     U1 N33
 '@S9S_MB_2U_LIB.S9S_MB_2U(SCH_1):PAGE73_I5@PURE_QUANTA.SOCKET4677_AZIF0045P001C01CS(CHIPS)':
 'VSS1691': CDS_PINID='VSS1691';
NODE_NAME     U1 N45
 '@S9S_MB_2U_LIB.S9S_MB_2U(SCH_1):PAGE73_I5@PURE_QUANTA.SOCKET4677_AZIF0045P001C01CS(CHIPS)':
 'VSS1692': CDS_PINID='VSS1692';
NODE_NAME     U1 N52
 '@S9S_MB_2U_LIB.S9S_MB_2U(SCH_1):PAGE73_I5@PURE_QUANTA.SOCKET4677_AZIF0045P001C01CS(CHIPS)':
 'VSS1693': CDS_PINID='VSS1693';
NODE_NAME     U1 N58
 '@S9S_MB_2U_LIB.S9S_MB_2U(SCH_1):PAGE73_I5@PURE_QUANTA.SOCKET4677_AZIF0045P001C01CS(CHIPS)':
 'VSS1694': CDS_PINID='VSS1694';
NODE_NAME     U1 N70
 '@S9S_MB_2U_LIB.S9S_MB_2U(SCH_1):PAGE73_I5@PURE_QUANTA.SOCKET4677_AZIF0045P001C01CS(CHIPS)':
 'VSS1695': CDS_PINID='VSS1695';
NODE_NAME     U1 A11
 '@S9S_MB_2U_LIB.S9S_MB_2U(SCH_1):PAGE73_I8@PURE_QUANTA.SOCKET4677_AZIF0045P001C01CS(CHIPS)':
 'VSS1': CDS_PINID='VSS1';
NODE_NAME     U1 A13
 '@S9S_MB_2U_LIB.S9S_MB_2U(SCH_1):PAGE73_I8@PURE_QUANTA.SOCKET4677_AZIF0045P001C01CS(CHIPS)':
 'VSS2': CDS_PINID='VSS2';
NODE_NAME     U1 A17
 '@S9S_MB_2U_LIB.S9S_MB_2U(SCH_1):PAGE73_I8@PURE_QUANTA.SOCKET4677_AZIF0045P001C01CS(CHIPS)':
 'VSS3': CDS_PINID='VSS3';
NODE_NAME     U1 A19
 '@S9S_MB_2U_LIB.S9S_MB_2U(SCH_1):PAGE73_I8@PURE_QUANTA.SOCKET4677_AZIF0045P001C01CS(CHIPS)':
 'VSS4': CDS_PINID='VSS4';
NODE_NAME     U1 A23
 '@S9S_MB_2U_LIB.S9S_MB_2U(SCH_1):PAGE73_I8@PURE_QUANTA.SOCKET4677_AZIF0045P001C01CS(CHIPS)':
 'VSS5': CDS_PINID='VSS5';
NODE_NAME     U1 A25
 '@S9S_MB_2U_LIB.S9S_MB_2U(SCH_1):PAGE73_I8@PURE_QUANTA.SOCKET4677_AZIF0045P001C01CS(CHIPS)':
 'VSS6': CDS_PINID='VSS6';
NODE_NAME     U1 A29
 '@S9S_MB_2U_LIB.S9S_MB_2U(SCH_1):PAGE73_I8@PURE_QUANTA.SOCKET4677_AZIF0045P001C01CS(CHIPS)':
 'VSS7': CDS_PINID='VSS7';
NODE_NAME     U1 A31
 '@S9S_MB_2U_LIB.S9S_MB_2U(SCH_1):PAGE73_I8@PURE_QUANTA.SOCKET4677_AZIF0045P001C01CS(CHIPS)':
 'VSS8': CDS_PINID='VSS8';
NODE_NAME     U1 A35
 '@S9S_MB_2U_LIB.S9S_MB_2U(SCH_1):PAGE73_I8@PURE_QUANTA.SOCKET4677_AZIF0045P001C01CS(CHIPS)':
 'VSS9': CDS_PINID='VSS9';
NODE_NAME     U1 A37
 '@S9S_MB_2U_LIB.S9S_MB_2U(SCH_1):PAGE73_I8@PURE_QUANTA.SOCKET4677_AZIF0045P001C01CS(CHIPS)':
 'VSS10': CDS_PINID='VSS10';
NODE_NAME     U1 A41
 '@S9S_MB_2U_LIB.S9S_MB_2U(SCH_1):PAGE73_I8@PURE_QUANTA.SOCKET4677_AZIF0045P001C01CS(CHIPS)':
 'VSS11': CDS_PINID='VSS11';
NODE_NAME     U1 A50
 '@S9S_MB_2U_LIB.S9S_MB_2U(SCH_1):PAGE73_I8@PURE_QUANTA.SOCKET4677_AZIF0045P001C01CS(CHIPS)':
 'VSS12': CDS_PINID='VSS12';
NODE_NAME     U1 A54
 '@S9S_MB_2U_LIB.S9S_MB_2U(SCH_1):PAGE73_I8@PURE_QUANTA.SOCKET4677_AZIF0045P001C01CS(CHIPS)':
 'VSS13': CDS_PINID='VSS13';
NODE_NAME     U1 A56
 '@S9S_MB_2U_LIB.S9S_MB_2U(SCH_1):PAGE73_I8@PURE_QUANTA.SOCKET4677_AZIF0045P001C01CS(CHIPS)':
 'VSS14': CDS_PINID='VSS14';
NODE_NAME     U1 A60
 '@S9S_MB_2U_LIB.S9S_MB_2U(SCH_1):PAGE73_I8@PURE_QUANTA.SOCKET4677_AZIF0045P001C01CS(CHIPS)':
 'VSS15': CDS_PINID='VSS15';
NODE_NAME     U1 A62
 '@S9S_MB_2U_LIB.S9S_MB_2U(SCH_1):PAGE73_I8@PURE_QUANTA.SOCKET4677_AZIF0045P001C01CS(CHIPS)':
 'VSS16': CDS_PINID='VSS16';
NODE_NAME     U1 B12
 '@S9S_MB_2U_LIB.S9S_MB_2U(SCH_1):PAGE73_I8@PURE_QUANTA.SOCKET4677_AZIF0045P001C01CS(CHIPS)':
 'VSS378': CDS_PINID='VSS378';
NODE_NAME     U1 B18
 '@S9S_MB_2U_LIB.S9S_MB_2U(SCH_1):PAGE73_I8@PURE_QUANTA.SOCKET4677_AZIF0045P001C01CS(CHIPS)':
 'VSS379': CDS_PINID='VSS379';
NODE_NAME     U1 B24
 '@S9S_MB_2U_LIB.S9S_MB_2U(SCH_1):PAGE73_I8@PURE_QUANTA.SOCKET4677_AZIF0045P001C01CS(CHIPS)':
 'VSS380': CDS_PINID='VSS380';
NODE_NAME     U1 B30
 '@S9S_MB_2U_LIB.S9S_MB_2U(SCH_1):PAGE73_I8@PURE_QUANTA.SOCKET4677_AZIF0045P001C01CS(CHIPS)':
 'VSS381': CDS_PINID='VSS381';
NODE_NAME     U1 B36
 '@S9S_MB_2U_LIB.S9S_MB_2U(SCH_1):PAGE73_I8@PURE_QUANTA.SOCKET4677_AZIF0045P001C01CS(CHIPS)':
 'VSS382': CDS_PINID='VSS382';
NODE_NAME     U1 B42
 '@S9S_MB_2U_LIB.S9S_MB_2U(SCH_1):PAGE73_I8@PURE_QUANTA.SOCKET4677_AZIF0045P001C01CS(CHIPS)':
 'VSS384': CDS_PINID='VSS384';
NODE_NAME     U1 B49
 '@S9S_MB_2U_LIB.S9S_MB_2U(SCH_1):PAGE73_I8@PURE_QUANTA.SOCKET4677_AZIF0045P001C01CS(CHIPS)':
 'VSS385': CDS_PINID='VSS385';
NODE_NAME     U1 B55
 '@S9S_MB_2U_LIB.S9S_MB_2U(SCH_1):PAGE73_I8@PURE_QUANTA.SOCKET4677_AZIF0045P001C01CS(CHIPS)':
 'VSS386': CDS_PINID='VSS386';
NODE_NAME     U1 B6
 '@S9S_MB_2U_LIB.S9S_MB_2U(SCH_1):PAGE73_I8@PURE_QUANTA.SOCKET4677_AZIF0045P001C01CS(CHIPS)':
 'VSS387': CDS_PINID='VSS387';
NODE_NAME     U1 B61
 '@S9S_MB_2U_LIB.S9S_MB_2U(SCH_1):PAGE73_I8@PURE_QUANTA.SOCKET4677_AZIF0045P001C01CS(CHIPS)':
 'VSS388': CDS_PINID='VSS388';
NODE_NAME     U1 B67
 '@S9S_MB_2U_LIB.S9S_MB_2U(SCH_1):PAGE73_I8@PURE_QUANTA.SOCKET4677_AZIF0045P001C01CS(CHIPS)':
 'VSS389': CDS_PINID='VSS389';
NODE_NAME     U1 B75
 '@S9S_MB_2U_LIB.S9S_MB_2U(SCH_1):PAGE73_I8@PURE_QUANTA.SOCKET4677_AZIF0045P001C01CS(CHIPS)':
 'VSS390': CDS_PINID='VSS390';
NODE_NAME     U1 B83
 '@S9S_MB_2U_LIB.S9S_MB_2U(SCH_1):PAGE73_I8@PURE_QUANTA.SOCKET4677_AZIF0045P001C01CS(CHIPS)':
 'VSS391': CDS_PINID='VSS391';
NODE_NAME     U1 B87
 '@S9S_MB_2U_LIB.S9S_MB_2U(SCH_1):PAGE73_I8@PURE_QUANTA.SOCKET4677_AZIF0045P001C01CS(CHIPS)':
 'VSS392': CDS_PINID='VSS392';
NODE_NAME     U1 C39
 '@S9S_MB_2U_LIB.S9S_MB_2U(SCH_1):PAGE73_I8@PURE_QUANTA.SOCKET4677_AZIF0045P001C01CS(CHIPS)':
 'VSS609': CDS_PINID='VSS609';
NODE_NAME     U1 C45
 '@S9S_MB_2U_LIB.S9S_MB_2U(SCH_1):PAGE73_I8@PURE_QUANTA.SOCKET4677_AZIF0045P001C01CS(CHIPS)':
 'VSS610': CDS_PINID='VSS610';
NODE_NAME     U1 C5
 '@S9S_MB_2U_LIB.S9S_MB_2U(SCH_1):PAGE73_I8@PURE_QUANTA.SOCKET4677_AZIF0045P001C01CS(CHIPS)':
 'VSS612': CDS_PINID='VSS612';
NODE_NAME     U1 C52
 '@S9S_MB_2U_LIB.S9S_MB_2U(SCH_1):PAGE73_I8@PURE_QUANTA.SOCKET4677_AZIF0045P001C01CS(CHIPS)':
 'VSS613': CDS_PINID='VSS613';
NODE_NAME     U1 C72
 '@S9S_MB_2U_LIB.S9S_MB_2U(SCH_1):PAGE73_I8@PURE_QUANTA.SOCKET4677_AZIF0045P001C01CS(CHIPS)':
 'VSS614': CDS_PINID='VSS614';
NODE_NAME     U1 C74
 '@S9S_MB_2U_LIB.S9S_MB_2U(SCH_1):PAGE73_I8@PURE_QUANTA.SOCKET4677_AZIF0045P001C01CS(CHIPS)':
 'VSS615': CDS_PINID='VSS615';
NODE_NAME     U1 C78
 '@S9S_MB_2U_LIB.S9S_MB_2U(SCH_1):PAGE73_I8@PURE_QUANTA.SOCKET4677_AZIF0045P001C01CS(CHIPS)':
 'VSS616': CDS_PINID='VSS616';
NODE_NAME     U1 C80
 '@S9S_MB_2U_LIB.S9S_MB_2U(SCH_1):PAGE73_I8@PURE_QUANTA.SOCKET4677_AZIF0045P001C01CS(CHIPS)':
 'VSS617': CDS_PINID='VSS617';
NODE_NAME     U1 C82
 '@S9S_MB_2U_LIB.S9S_MB_2U(SCH_1):PAGE73_I8@PURE_QUANTA.SOCKET4677_AZIF0045P001C01CS(CHIPS)':
 'VSS618': CDS_PINID='VSS618';
NODE_NAME     U1 C86
 '@S9S_MB_2U_LIB.S9S_MB_2U(SCH_1):PAGE73_I8@PURE_QUANTA.SOCKET4677_AZIF0045P001C01CS(CHIPS)':
 'VSS619': CDS_PINID='VSS619';
NODE_NAME     U1 D63
 '@S9S_MB_2U_LIB.S9S_MB_2U(SCH_1):PAGE73_I8@PURE_QUANTA.SOCKET4677_AZIF0045P001C01CS(CHIPS)':
 'VSS657': CDS_PINID='VSS657';
NODE_NAME     U1 D65
 '@S9S_MB_2U_LIB.S9S_MB_2U(SCH_1):PAGE73_I8@PURE_QUANTA.SOCKET4677_AZIF0045P001C01CS(CHIPS)':
 'VSS658': CDS_PINID='VSS658';
NODE_NAME     U1 D67
 '@S9S_MB_2U_LIB.S9S_MB_2U(SCH_1):PAGE73_I8@PURE_QUANTA.SOCKET4677_AZIF0045P001C01CS(CHIPS)':
 'VSS659': CDS_PINID='VSS659';
NODE_NAME     U1 D79
 '@S9S_MB_2U_LIB.S9S_MB_2U(SCH_1):PAGE73_I8@PURE_QUANTA.SOCKET4677_AZIF0045P001C01CS(CHIPS)':
 'VSS662': CDS_PINID='VSS662';
NODE_NAME     U1 D8
 '@S9S_MB_2U_LIB.S9S_MB_2U(SCH_1):PAGE73_I8@PURE_QUANTA.SOCKET4677_AZIF0045P001C01CS(CHIPS)':
 'VSS663': CDS_PINID='VSS663';
NODE_NAME     U1 D10
 '@S9S_MB_2U_LIB.S9S_MB_2U(SCH_1):PAGE73_I8@PURE_QUANTA.SOCKET4677_AZIF0045P001C01CS(CHIPS)':
 'VSS864': CDS_PINID='VSS864';
NODE_NAME     U1 D12
 '@S9S_MB_2U_LIB.S9S_MB_2U(SCH_1):PAGE73_I8@PURE_QUANTA.SOCKET4677_AZIF0045P001C01CS(CHIPS)':
 'VSS865': CDS_PINID='VSS865';
NODE_NAME     U1 D14
 '@S9S_MB_2U_LIB.S9S_MB_2U(SCH_1):PAGE73_I8@PURE_QUANTA.SOCKET4677_AZIF0045P001C01CS(CHIPS)':
 'VSS866': CDS_PINID='VSS866';
NODE_NAME     U1 D16
 '@S9S_MB_2U_LIB.S9S_MB_2U(SCH_1):PAGE73_I8@PURE_QUANTA.SOCKET4677_AZIF0045P001C01CS(CHIPS)':
 'VSS868': CDS_PINID='VSS868';
NODE_NAME     U1 D18
 '@S9S_MB_2U_LIB.S9S_MB_2U(SCH_1):PAGE73_I8@PURE_QUANTA.SOCKET4677_AZIF0045P001C01CS(CHIPS)':
 'VSS869': CDS_PINID='VSS869';
NODE_NAME     U1 D20
 '@S9S_MB_2U_LIB.S9S_MB_2U(SCH_1):PAGE73_I8@PURE_QUANTA.SOCKET4677_AZIF0045P001C01CS(CHIPS)':
 'VSS871': CDS_PINID='VSS871';
NODE_NAME     U1 D22
 '@S9S_MB_2U_LIB.S9S_MB_2U(SCH_1):PAGE73_I8@PURE_QUANTA.SOCKET4677_AZIF0045P001C01CS(CHIPS)':
 'VSS873': CDS_PINID='VSS873';
NODE_NAME     U1 D24
 '@S9S_MB_2U_LIB.S9S_MB_2U(SCH_1):PAGE73_I8@PURE_QUANTA.SOCKET4677_AZIF0045P001C01CS(CHIPS)':
 'VSS874': CDS_PINID='VSS874';
NODE_NAME     U1 D26
 '@S9S_MB_2U_LIB.S9S_MB_2U(SCH_1):PAGE73_I8@PURE_QUANTA.SOCKET4677_AZIF0045P001C01CS(CHIPS)':
 'VSS875': CDS_PINID='VSS875';
NODE_NAME     U1 D28
 '@S9S_MB_2U_LIB.S9S_MB_2U(SCH_1):PAGE73_I8@PURE_QUANTA.SOCKET4677_AZIF0045P001C01CS(CHIPS)':
 'VSS876': CDS_PINID='VSS876';
NODE_NAME     U1 D30
 '@S9S_MB_2U_LIB.S9S_MB_2U(SCH_1):PAGE73_I8@PURE_QUANTA.SOCKET4677_AZIF0045P001C01CS(CHIPS)':
 'VSS877': CDS_PINID='VSS877';
NODE_NAME     U1 D32
 '@S9S_MB_2U_LIB.S9S_MB_2U(SCH_1):PAGE73_I8@PURE_QUANTA.SOCKET4677_AZIF0045P001C01CS(CHIPS)':
 'VSS878': CDS_PINID='VSS878';
NODE_NAME     U1 D34
 '@S9S_MB_2U_LIB.S9S_MB_2U(SCH_1):PAGE73_I8@PURE_QUANTA.SOCKET4677_AZIF0045P001C01CS(CHIPS)':
 'VSS879': CDS_PINID='VSS879';
NODE_NAME     U1 D36
 '@S9S_MB_2U_LIB.S9S_MB_2U(SCH_1):PAGE73_I8@PURE_QUANTA.SOCKET4677_AZIF0045P001C01CS(CHIPS)':
 'VSS881': CDS_PINID='VSS881';
NODE_NAME     U1 D38
 '@S9S_MB_2U_LIB.S9S_MB_2U(SCH_1):PAGE73_I8@PURE_QUANTA.SOCKET4677_AZIF0045P001C01CS(CHIPS)':
 'VSS884': CDS_PINID='VSS884';
NODE_NAME     U1 D40
 '@S9S_MB_2U_LIB.S9S_MB_2U(SCH_1):PAGE73_I8@PURE_QUANTA.SOCKET4677_AZIF0045P001C01CS(CHIPS)':
 'VSS885': CDS_PINID='VSS885';
NODE_NAME     U1 D42
 '@S9S_MB_2U_LIB.S9S_MB_2U(SCH_1):PAGE73_I8@PURE_QUANTA.SOCKET4677_AZIF0045P001C01CS(CHIPS)':
 'VSS886': CDS_PINID='VSS886';
NODE_NAME     U1 D44
 '@S9S_MB_2U_LIB.S9S_MB_2U(SCH_1):PAGE73_I8@PURE_QUANTA.SOCKET4677_AZIF0045P001C01CS(CHIPS)':
 'VSS888': CDS_PINID='VSS888';
NODE_NAME     U1 D47
 '@S9S_MB_2U_LIB.S9S_MB_2U(SCH_1):PAGE73_I8@PURE_QUANTA.SOCKET4677_AZIF0045P001C01CS(CHIPS)':
 'VSS889': CDS_PINID='VSS889';
NODE_NAME     U1 D49
 '@S9S_MB_2U_LIB.S9S_MB_2U(SCH_1):PAGE73_I8@PURE_QUANTA.SOCKET4677_AZIF0045P001C01CS(CHIPS)':
 'VSS891': CDS_PINID='VSS891';
NODE_NAME     U1 D51
 '@S9S_MB_2U_LIB.S9S_MB_2U(SCH_1):PAGE73_I8@PURE_QUANTA.SOCKET4677_AZIF0045P001C01CS(CHIPS)':
 'VSS892': CDS_PINID='VSS892';
NODE_NAME     U1 D53
 '@S9S_MB_2U_LIB.S9S_MB_2U(SCH_1):PAGE73_I8@PURE_QUANTA.SOCKET4677_AZIF0045P001C01CS(CHIPS)':
 'VSS895': CDS_PINID='VSS895';
NODE_NAME     U1 D55
 '@S9S_MB_2U_LIB.S9S_MB_2U(SCH_1):PAGE73_I8@PURE_QUANTA.SOCKET4677_AZIF0045P001C01CS(CHIPS)':
 'VSS896': CDS_PINID='VSS896';
NODE_NAME     U1 D57
 '@S9S_MB_2U_LIB.S9S_MB_2U(SCH_1):PAGE73_I8@PURE_QUANTA.SOCKET4677_AZIF0045P001C01CS(CHIPS)':
 'VSS897': CDS_PINID='VSS897';
NODE_NAME     U1 D59
 '@S9S_MB_2U_LIB.S9S_MB_2U(SCH_1):PAGE73_I8@PURE_QUANTA.SOCKET4677_AZIF0045P001C01CS(CHIPS)':
 'VSS898': CDS_PINID='VSS898';
NODE_NAME     U1 D6
 '@S9S_MB_2U_LIB.S9S_MB_2U(SCH_1):PAGE73_I8@PURE_QUANTA.SOCKET4677_AZIF0045P001C01CS(CHIPS)':
 'VSS899': CDS_PINID='VSS899';
NODE_NAME     U1 D61
 '@S9S_MB_2U_LIB.S9S_MB_2U(SCH_1):PAGE73_I8@PURE_QUANTA.SOCKET4677_AZIF0045P001C01CS(CHIPS)':
 'VSS900': CDS_PINID='VSS900';
NODE_NAME     U1 D69
 '@S9S_MB_2U_LIB.S9S_MB_2U(SCH_1):PAGE73_I8@PURE_QUANTA.SOCKET4677_AZIF0045P001C01CS(CHIPS)':
 'VSS901': CDS_PINID='VSS901';
NODE_NAME     U1 D71
 '@S9S_MB_2U_LIB.S9S_MB_2U(SCH_1):PAGE73_I8@PURE_QUANTA.SOCKET4677_AZIF0045P001C01CS(CHIPS)':
 'VSS902': CDS_PINID='VSS902';
NODE_NAME     U1 D81
 '@S9S_MB_2U_LIB.S9S_MB_2U(SCH_1):PAGE73_I8@PURE_QUANTA.SOCKET4677_AZIF0045P001C01CS(CHIPS)':
 'VSS906': CDS_PINID='VSS906';
NODE_NAME     U1 D83
 '@S9S_MB_2U_LIB.S9S_MB_2U(SCH_1):PAGE73_I8@PURE_QUANTA.SOCKET4677_AZIF0045P001C01CS(CHIPS)':
 'VSS907': CDS_PINID='VSS907';
NODE_NAME     U1 E5
 '@S9S_MB_2U_LIB.S9S_MB_2U(SCH_1):PAGE73_I8@PURE_QUANTA.SOCKET4677_AZIF0045P001C01CS(CHIPS)':
 'VSS1125': CDS_PINID='VSS1125';
NODE_NAME     U1 E39
 '@S9S_MB_2U_LIB.S9S_MB_2U(SCH_1):PAGE73_I8@PURE_QUANTA.SOCKET4677_AZIF0045P001C01CS(CHIPS)':
 'VSS1271': CDS_PINID='VSS1271';
NODE_NAME     C407 2
 '@S9S_MB_2U_LIB.S9S_MB_2U(SCH_1):PAGE74_I7@PURE_QUANTA.Q_CAP(CHIPS)':
 'B': CDS_PINID='B';
NODE_NAME     C409 2
 '@S9S_MB_2U_LIB.S9S_MB_2U(SCH_1):PAGE74_I8@PURE_QUANTA.Q_CAP(CHIPS)':
 'B': CDS_PINID='B';
NODE_NAME     C411 2
 '@S9S_MB_2U_LIB.S9S_MB_2U(SCH_1):PAGE74_I9@PURE_QUANTA.Q_CAP(CHIPS)':
 'B': CDS_PINID='B';
NODE_NAME     C413 2
 '@S9S_MB_2U_LIB.S9S_MB_2U(SCH_1):PAGE74_I10@PURE_QUANTA.Q_CAP(CHIPS)':
 'B': CDS_PINID='B';
NODE_NAME     C101 2
 '@S9S_MB_2U_LIB.S9S_MB_2U(SCH_1):PAGE74_I13@PURE_QUANTA.Q_CAP(CHIPS)':
 'B': CDS_PINID='B';
NODE_NAME     C969 2
 '@S9S_MB_2U_LIB.S9S_MB_2U(SCH_1):PAGE74_I15@PURE_QUANTA.Q_CAP(CHIPS)':
 'B': CDS_PINID='B';
NODE_NAME     C401 2
 '@S9S_MB_2U_LIB.S9S_MB_2U(SCH_1):PAGE74_I17@PURE_QUANTA.Q_CAP(CHIPS)':
 'B': CDS_PINID='B';
NODE_NAME     C212 2
 '@S9S_MB_2U_LIB.S9S_MB_2U(SCH_1):PAGE74_I18@PURE_QUANTA.Q_CAP(CHIPS)':
 'B': CDS_PINID='B';
NODE_NAME     C403 2
 '@S9S_MB_2U_LIB.S9S_MB_2U(SCH_1):PAGE74_I19@PURE_QUANTA.Q_CAP(CHIPS)':
 'B': CDS_PINID='B';
NODE_NAME     C213 2
 '@S9S_MB_2U_LIB.S9S_MB_2U(SCH_1):PAGE74_I20@PURE_QUANTA.Q_CAP(CHIPS)':
 'B': CDS_PINID='B';
NODE_NAME     C973 2
 '@S9S_MB_2U_LIB.S9S_MB_2U(SCH_1):PAGE74_I21@PURE_QUANTA.Q_CAP(CHIPS)':
 'B': CDS_PINID='B';
NODE_NAME     C977 2
 '@S9S_MB_2U_LIB.S9S_MB_2U(SCH_1):PAGE74_I22@PURE_QUANTA.Q_CAP(CHIPS)':
 'B': CDS_PINID='B';
NODE_NAME     C968 2
 '@S9S_MB_2U_LIB.S9S_MB_2U(SCH_1):PAGE74_I23@PURE_QUANTA.Q_CAP(CHIPS)':
 'B': CDS_PINID='B';
NODE_NAME     C976 2
 '@S9S_MB_2U_LIB.S9S_MB_2U(SCH_1):PAGE74_I29@PURE_QUANTA.Q_CAP(CHIPS)':
 'B': CDS_PINID='B';
NODE_NAME     C971 2
 '@S9S_MB_2U_LIB.S9S_MB_2U(SCH_1):PAGE74_I30@PURE_QUANTA.Q_CAP(CHIPS)':
 'B': CDS_PINID='B';
NODE_NAME     C975 2
 '@S9S_MB_2U_LIB.S9S_MB_2U(SCH_1):PAGE74_I32@PURE_QUANTA.Q_CAP(CHIPS)':
 'B': CDS_PINID='B';
NODE_NAME     C974 2
 '@S9S_MB_2U_LIB.S9S_MB_2U(SCH_1):PAGE74_I33@PURE_QUANTA.Q_CAP(CHIPS)':
 'B': CDS_PINID='B';
NODE_NAME     C214 2
 '@S9S_MB_2U_LIB.S9S_MB_2U(SCH_1):PAGE74_I35@PURE_QUANTA.Q_CAP(CHIPS)':
 'B': CDS_PINID='B';
NODE_NAME     C215 2
 '@S9S_MB_2U_LIB.S9S_MB_2U(SCH_1):PAGE74_I36@PURE_QUANTA.Q_CAP(CHIPS)':
 'B': CDS_PINID='B';
NODE_NAME     C981 2
 '@S9S_MB_2U_LIB.S9S_MB_2U(SCH_1):PAGE74_I37@PURE_QUANTA.Q_CAP(CHIPS)':
 'B': CDS_PINID='B';
NODE_NAME     C985 2
 '@S9S_MB_2U_LIB.S9S_MB_2U(SCH_1):PAGE74_I38@PURE_QUANTA.Q_CAP(CHIPS)':
 'B': CDS_PINID='B';
NODE_NAME     C216 2
 '@S9S_MB_2U_LIB.S9S_MB_2U(SCH_1):PAGE74_I40@PURE_QUANTA.Q_CAP(CHIPS)':
 'B': CDS_PINID='B';
NODE_NAME     C410 2
 '@S9S_MB_2U_LIB.S9S_MB_2U(SCH_1):PAGE74_I41@PURE_QUANTA.Q_CAP(CHIPS)':
 'B': CDS_PINID='B';
NODE_NAME     C412 2
 '@S9S_MB_2U_LIB.S9S_MB_2U(SCH_1):PAGE74_I42@PURE_QUANTA.Q_CAP(CHIPS)':
 'B': CDS_PINID='B';
NODE_NAME     C218 2
 '@S9S_MB_2U_LIB.S9S_MB_2U(SCH_1):PAGE74_I44@PURE_QUANTA.Q_CAP(CHIPS)':
 'B': CDS_PINID='B';
NODE_NAME     C993 2
 '@S9S_MB_2U_LIB.S9S_MB_2U(SCH_1):PAGE74_I46@PURE_QUANTA.Q_CAP(CHIPS)':
 'B': CDS_PINID='B';
NODE_NAME     C997 2
 '@S9S_MB_2U_LIB.S9S_MB_2U(SCH_1):PAGE74_I47@PURE_QUANTA.Q_CAP(CHIPS)':
 'B': CDS_PINID='B';
NODE_NAME     C980 2
 '@S9S_MB_2U_LIB.S9S_MB_2U(SCH_1):PAGE74_I48@PURE_QUANTA.Q_CAP(CHIPS)':
 'B': CDS_PINID='B';
NODE_NAME     C984 2
 '@S9S_MB_2U_LIB.S9S_MB_2U(SCH_1):PAGE74_I49@PURE_QUANTA.Q_CAP(CHIPS)':
 'B': CDS_PINID='B';
NODE_NAME     C979 2
 '@S9S_MB_2U_LIB.S9S_MB_2U(SCH_1):PAGE74_I50@PURE_QUANTA.Q_CAP(CHIPS)':
 'B': CDS_PINID='B';
NODE_NAME     C978 2
 '@S9S_MB_2U_LIB.S9S_MB_2U(SCH_1):PAGE74_I51@PURE_QUANTA.Q_CAP(CHIPS)':
 'B': CDS_PINID='B';
NODE_NAME     C983 2
 '@S9S_MB_2U_LIB.S9S_MB_2U(SCH_1):PAGE74_I52@PURE_QUANTA.Q_CAP(CHIPS)':
 'B': CDS_PINID='B';
NODE_NAME     C982 2
 '@S9S_MB_2U_LIB.S9S_MB_2U(SCH_1):PAGE74_I53@PURE_QUANTA.Q_CAP(CHIPS)':
 'B': CDS_PINID='B';
NODE_NAME     C988 2
 '@S9S_MB_2U_LIB.S9S_MB_2U(SCH_1):PAGE74_I54@PURE_QUANTA.Q_CAP(CHIPS)':
 'B': CDS_PINID='B';
NODE_NAME     C996 2
 '@S9S_MB_2U_LIB.S9S_MB_2U(SCH_1):PAGE74_I56@PURE_QUANTA.Q_CAP(CHIPS)':
 'B': CDS_PINID='B';
NODE_NAME     C986 2
 '@S9S_MB_2U_LIB.S9S_MB_2U(SCH_1):PAGE74_I58@PURE_QUANTA.Q_CAP(CHIPS)':
 'B': CDS_PINID='B';
NODE_NAME     C991 2
 '@S9S_MB_2U_LIB.S9S_MB_2U(SCH_1):PAGE74_I59@PURE_QUANTA.Q_CAP(CHIPS)':
 'B': CDS_PINID='B';
NODE_NAME     C990 2
 '@S9S_MB_2U_LIB.S9S_MB_2U(SCH_1):PAGE74_I60@PURE_QUANTA.Q_CAP(CHIPS)':
 'B': CDS_PINID='B';
NODE_NAME     C995 2
 '@S9S_MB_2U_LIB.S9S_MB_2U(SCH_1):PAGE74_I61@PURE_QUANTA.Q_CAP(CHIPS)':
 'B': CDS_PINID='B';
NODE_NAME     C415 2
 '@S9S_MB_2U_LIB.S9S_MB_2U(SCH_1):PAGE74_I64@PURE_QUANTA.Q_CAP(CHIPS)':
 'B': CDS_PINID='B';
NODE_NAME     C417 2
 '@S9S_MB_2U_LIB.S9S_MB_2U(SCH_1):PAGE74_I65@PURE_QUANTA.Q_CAP(CHIPS)':
 'B': CDS_PINID='B';
NODE_NAME     C418 2
 '@S9S_MB_2U_LIB.S9S_MB_2U(SCH_1):PAGE74_I68@PURE_QUANTA.Q_CAP(CHIPS)':
 'B': CDS_PINID='B';
NODE_NAME     C414 2
 '@S9S_MB_2U_LIB.S9S_MB_2U(SCH_1):PAGE74_I70@PURE_QUANTA.Q_CAP(CHIPS)':
 'B': CDS_PINID='B';
NODE_NAME     C219 2
 '@S9S_MB_2U_LIB.S9S_MB_2U(SCH_1):PAGE74_I71@PURE_QUANTA.Q_CAP(CHIPS)':
 'B': CDS_PINID='B';
NODE_NAME     C416 2
 '@S9S_MB_2U_LIB.S9S_MB_2U(SCH_1):PAGE74_I72@PURE_QUANTA.Q_CAP(CHIPS)':
 'B': CDS_PINID='B';
NODE_NAME     C220 2
 '@S9S_MB_2U_LIB.S9S_MB_2U(SCH_1):PAGE74_I74@PURE_QUANTA.Q_CAP(CHIPS)':
 'B': CDS_PINID='B';
NODE_NAME     C1001 2
 '@S9S_MB_2U_LIB.S9S_MB_2U(SCH_1):PAGE74_I75@PURE_QUANTA.Q_CAP(CHIPS)':
 'B': CDS_PINID='B';
NODE_NAME     C1005 2
 '@S9S_MB_2U_LIB.S9S_MB_2U(SCH_1):PAGE74_I77@PURE_QUANTA.Q_CAP(CHIPS)':
 'B': CDS_PINID='B';
NODE_NAME     C1009 2
 '@S9S_MB_2U_LIB.S9S_MB_2U(SCH_1):PAGE74_I78@PURE_QUANTA.Q_CAP(CHIPS)':
 'B': CDS_PINID='B';
NODE_NAME     C1013 2
 '@S9S_MB_2U_LIB.S9S_MB_2U(SCH_1):PAGE74_I80@PURE_QUANTA.Q_CAP(CHIPS)':
 'B': CDS_PINID='B';
NODE_NAME     C1000 2
 '@S9S_MB_2U_LIB.S9S_MB_2U(SCH_1):PAGE74_I81@PURE_QUANTA.Q_CAP(CHIPS)':
 'B': CDS_PINID='B';
NODE_NAME     C999 2
 '@S9S_MB_2U_LIB.S9S_MB_2U(SCH_1):PAGE74_I85@PURE_QUANTA.Q_CAP(CHIPS)':
 'B': CDS_PINID='B';
NODE_NAME     C998 2
 '@S9S_MB_2U_LIB.S9S_MB_2U(SCH_1):PAGE74_I86@PURE_QUANTA.Q_CAP(CHIPS)':
 'B': CDS_PINID='B';
NODE_NAME     C1003 2
 '@S9S_MB_2U_LIB.S9S_MB_2U(SCH_1):PAGE74_I87@PURE_QUANTA.Q_CAP(CHIPS)':
 'B': CDS_PINID='B';
NODE_NAME     C1002 2
 '@S9S_MB_2U_LIB.S9S_MB_2U(SCH_1):PAGE74_I89@PURE_QUANTA.Q_CAP(CHIPS)':
 'B': CDS_PINID='B';
NODE_NAME     C1008 2
 '@S9S_MB_2U_LIB.S9S_MB_2U(SCH_1):PAGE74_I90@PURE_QUANTA.Q_CAP(CHIPS)':
 'B': CDS_PINID='B';
NODE_NAME     C1012 2
 '@S9S_MB_2U_LIB.S9S_MB_2U(SCH_1):PAGE74_I92@PURE_QUANTA.Q_CAP(CHIPS)':
 'B': CDS_PINID='B';
NODE_NAME     C1007 2
 '@S9S_MB_2U_LIB.S9S_MB_2U(SCH_1):PAGE74_I93@PURE_QUANTA.Q_CAP(CHIPS)':
 'B': CDS_PINID='B';
NODE_NAME     C1006 2
 '@S9S_MB_2U_LIB.S9S_MB_2U(SCH_1):PAGE74_I95@PURE_QUANTA.Q_CAP(CHIPS)':
 'B': CDS_PINID='B';
NODE_NAME     C1011 2
 '@S9S_MB_2U_LIB.S9S_MB_2U(SCH_1):PAGE74_I96@PURE_QUANTA.Q_CAP(CHIPS)':
 'B': CDS_PINID='B';
NODE_NAME     C1010 2
 '@S9S_MB_2U_LIB.S9S_MB_2U(SCH_1):PAGE74_I97@PURE_QUANTA.Q_CAP(CHIPS)':
 'B': CDS_PINID='B';
NODE_NAME     C419 2
 '@S9S_MB_2U_LIB.S9S_MB_2U(SCH_1):PAGE74_I98@PURE_QUANTA.Q_CAP(CHIPS)':
 'B': CDS_PINID='B';
NODE_NAME     C590 2
 '@S9S_MB_2U_LIB.S9S_MB_2U(SCH_1):PAGE74_I102@PURE_QUANTA.Q_CAP(CHIPS)':
 'B': CDS_PINID='B';
NODE_NAME     C421 2
 '@S9S_MB_2U_LIB.S9S_MB_2U(SCH_1):PAGE74_I103@PURE_QUANTA.Q_CAP(CHIPS)':
 'B': CDS_PINID='B';
NODE_NAME     C1017 2
 '@S9S_MB_2U_LIB.S9S_MB_2U(SCH_1):PAGE74_I105@PURE_QUANTA.Q_CAP(CHIPS)':
 'B': CDS_PINID='B';
NODE_NAME     C1016 2
 '@S9S_MB_2U_LIB.S9S_MB_2U(SCH_1):PAGE74_I111@PURE_QUANTA.Q_CAP(CHIPS)':
 'B': CDS_PINID='B';
NODE_NAME     C1020 2
 '@S9S_MB_2U_LIB.S9S_MB_2U(SCH_1):PAGE74_I112@PURE_QUANTA.Q_CAP(CHIPS)':
 'B': CDS_PINID='B';
NODE_NAME     C1015 2
 '@S9S_MB_2U_LIB.S9S_MB_2U(SCH_1):PAGE74_I113@PURE_QUANTA.Q_CAP(CHIPS)':
 'B': CDS_PINID='B';
NODE_NAME     C1014 2
 '@S9S_MB_2U_LIB.S9S_MB_2U(SCH_1):PAGE74_I114@PURE_QUANTA.Q_CAP(CHIPS)':
 'B': CDS_PINID='B';
NODE_NAME     C1019 2
 '@S9S_MB_2U_LIB.S9S_MB_2U(SCH_1):PAGE74_I115@PURE_QUANTA.Q_CAP(CHIPS)':
 'B': CDS_PINID='B';
NODE_NAME     C1036 2
 '@S9S_MB_2U_LIB.S9S_MB_2U(SCH_1):PAGE74_I131@PURE_QUANTA.Q_CAP(CHIPS)':
 'B': CDS_PINID='B';
NODE_NAME     C1040 2
 '@S9S_MB_2U_LIB.S9S_MB_2U(SCH_1):PAGE74_I132@PURE_QUANTA.Q_CAP(CHIPS)':
 'B': CDS_PINID='B';
NODE_NAME     C1035 2
 '@S9S_MB_2U_LIB.S9S_MB_2U(SCH_1):PAGE74_I133@PURE_QUANTA.Q_CAP(CHIPS)':
 'B': CDS_PINID='B';
NODE_NAME     C1034 2
 '@S9S_MB_2U_LIB.S9S_MB_2U(SCH_1):PAGE74_I134@PURE_QUANTA.Q_CAP(CHIPS)':
 'B': CDS_PINID='B';
NODE_NAME     C1039 2
 '@S9S_MB_2U_LIB.S9S_MB_2U(SCH_1):PAGE74_I135@PURE_QUANTA.Q_CAP(CHIPS)':
 'B': CDS_PINID='B';
NODE_NAME     C1038 2
 '@S9S_MB_2U_LIB.S9S_MB_2U(SCH_1):PAGE74_I137@PURE_QUANTA.Q_CAP(CHIPS)':
 'B': CDS_PINID='B';
NODE_NAME     C1044 2
 '@S9S_MB_2U_LIB.S9S_MB_2U(SCH_1):PAGE74_I139@PURE_QUANTA.Q_CAP(CHIPS)':
 'B': CDS_PINID='B';
NODE_NAME     C1043 2
 '@S9S_MB_2U_LIB.S9S_MB_2U(SCH_1):PAGE74_I141@PURE_QUANTA.Q_CAP(CHIPS)':
 'B': CDS_PINID='B';
NODE_NAME     C408 2
 '@S9S_MB_2U_LIB.S9S_MB_2U(SCH_1):PAGE74_I142@PURE_QUANTA.Q_CAP(CHIPS)':
 'B': CDS_PINID='B';
NODE_NAME     C493 2
 '@S9S_MB_2U_LIB.S9S_MB_2U(SCH_1):PAGE75_I1@PURE_QUANTA.Q_CAP(CHIPS)':
 'B': CDS_PINID='B';
NODE_NAME     C497 2
 '@S9S_MB_2U_LIB.S9S_MB_2U(SCH_1):PAGE75_I3@PURE_QUANTA.Q_CAP(CHIPS)':
 'B': CDS_PINID='B';
NODE_NAME     C501 2
 '@S9S_MB_2U_LIB.S9S_MB_2U(SCH_1):PAGE75_I4@PURE_QUANTA.Q_CAP(CHIPS)':
 'B': CDS_PINID='B';
NODE_NAME     C532 2
 '@S9S_MB_2U_LIB.S9S_MB_2U(SCH_1):PAGE75_I14@PURE_QUANTA.Q_CAP(CHIPS)':
 'B': CDS_PINID='B';
NODE_NAME     C359 2
 '@S9S_MB_2U_LIB.S9S_MB_2U(SCH_1):PAGE75_I25@PURE_QUANTA.Q_CAP(CHIPS)':
 'B': CDS_PINID='B';
NODE_NAME     C362 2
 '@S9S_MB_2U_LIB.S9S_MB_2U(SCH_1):PAGE75_I26@PURE_QUANTA.Q_CAP(CHIPS)':
 'B': CDS_PINID='B';
NODE_NAME     C358 2
 '@S9S_MB_2U_LIB.S9S_MB_2U(SCH_1):PAGE75_I27@PURE_QUANTA.Q_CAP(CHIPS)':
 'B': CDS_PINID='B';
NODE_NAME     C361 2
 '@S9S_MB_2U_LIB.S9S_MB_2U(SCH_1):PAGE75_I28@PURE_QUANTA.Q_CAP(CHIPS)':
 'B': CDS_PINID='B';
NODE_NAME     C368 2
 '@S9S_MB_2U_LIB.S9S_MB_2U(SCH_1):PAGE75_I33@PURE_QUANTA.Q_CAP(CHIPS)':
 'B': CDS_PINID='B';
NODE_NAME     C1396 2
 '@S9S_MB_2U_LIB.S9S_MB_2U(SCH_1):PAGE75_I43@PURE_QUANTA.Q_CAP(CHIPS)':
 'B': CDS_PINID='B';
NODE_NAME     C1397 2
 '@S9S_MB_2U_LIB.S9S_MB_2U(SCH_1):PAGE75_I44@PURE_QUANTA.Q_CAP(CHIPS)':
 'B': CDS_PINID='B';
NODE_NAME     C391 2
 '@S9S_MB_2U_LIB.S9S_MB_2U(SCH_1):PAGE75_I49@PURE_QUANTA.Q_CAP(CHIPS)':
 'B': CDS_PINID='B';
NODE_NAME     C379 2
 '@S9S_MB_2U_LIB.S9S_MB_2U(SCH_1):PAGE75_I50@PURE_QUANTA.Q_CAP(CHIPS)':
 'B': CDS_PINID='B';
NODE_NAME     C393 2
 '@S9S_MB_2U_LIB.S9S_MB_2U(SCH_1):PAGE75_I52@PURE_QUANTA.Q_CAP(CHIPS)':
 'B': CDS_PINID='B';
NODE_NAME     C360 2
 '@S9S_MB_2U_LIB.S9S_MB_2U(SCH_1):PAGE75_I54@PURE_QUANTA.Q_CAP(CHIPS)':
 'B': CDS_PINID='B';
NODE_NAME     C381 2
 '@S9S_MB_2U_LIB.S9S_MB_2U(SCH_1):PAGE75_I67@PURE_QUANTA.Q_CAP(CHIPS)':
 'B': CDS_PINID='B';
NODE_NAME     C494 2
 '@S9S_MB_2U_LIB.S9S_MB_2U(SCH_1):PAGE76_I1@PURE_QUANTA.Q_CAP(CHIPS)':
 'B': CDS_PINID='B';
NODE_NAME     C528 2
 '@S9S_MB_2U_LIB.S9S_MB_2U(SCH_1):PAGE76_I6@PURE_QUANTA.Q_CAP(CHIPS)':
 'B': CDS_PINID='B';
NODE_NAME     C530 2
 '@S9S_MB_2U_LIB.S9S_MB_2U(SCH_1):PAGE76_I7@PURE_QUANTA.Q_CAP(CHIPS)':
 'B': CDS_PINID='B';
NODE_NAME     C1399 2
 '@S9S_MB_2U_LIB.S9S_MB_2U(SCH_1):PAGE76_I13@PURE_QUANTA.Q_CAP(CHIPS)':
 'B': CDS_PINID='B';
NODE_NAME     C499 2
 '@S9S_MB_2U_LIB.S9S_MB_2U(SCH_1):PAGE76_I18@PURE_QUANTA.Q_CAP(CHIPS)':
 'B': CDS_PINID='B';
NODE_NAME     C503 2
 '@S9S_MB_2U_LIB.S9S_MB_2U(SCH_1):PAGE76_I20@PURE_QUANTA.Q_CAP(CHIPS)':
 'B': CDS_PINID='B';
NODE_NAME     C510 2
 '@S9S_MB_2U_LIB.S9S_MB_2U(SCH_1):PAGE76_I27@PURE_QUANTA.Q_CAP(CHIPS)':
 'B': CDS_PINID='B';
NODE_NAME     C514 2
 '@S9S_MB_2U_LIB.S9S_MB_2U(SCH_1):PAGE76_I28@PURE_QUANTA.Q_CAP(CHIPS)':
 'B': CDS_PINID='B';
NODE_NAME     C517 2
 '@S9S_MB_2U_LIB.S9S_MB_2U(SCH_1):PAGE76_I29@PURE_QUANTA.Q_CAP(CHIPS)':
 'B': CDS_PINID='B';
NODE_NAME     C531 2
 '@S9S_MB_2U_LIB.S9S_MB_2U(SCH_1):PAGE76_I31@PURE_QUANTA.Q_CAP(CHIPS)':
 'B': CDS_PINID='B';
NODE_NAME     C529 2
 '@S9S_MB_2U_LIB.S9S_MB_2U(SCH_1):PAGE76_I41@PURE_QUANTA.Q_CAP(CHIPS)':
 'B': CDS_PINID='B';
NODE_NAME     C396 2
 '@S9S_MB_2U_LIB.S9S_MB_2U(SCH_1):PAGE76_I46@PURE_QUANTA.Q_CAP(CHIPS)':
 'B': CDS_PINID='B';
NODE_NAME     C398 2
 '@S9S_MB_2U_LIB.S9S_MB_2U(SCH_1):PAGE76_I47@PURE_QUANTA.Q_CAP(CHIPS)':
 'B': CDS_PINID='B';
NODE_NAME     C424 2
 '@S9S_MB_2U_LIB.S9S_MB_2U(SCH_1):PAGE77_I1@PURE_QUANTA.Q_CAP(CHIPS)':
 'B': CDS_PINID='B';
NODE_NAME     C428 2
 '@S9S_MB_2U_LIB.S9S_MB_2U(SCH_1):PAGE77_I4@PURE_QUANTA.Q_CAP(CHIPS)':
 'B': CDS_PINID='B';
NODE_NAME     C430 2
 '@S9S_MB_2U_LIB.S9S_MB_2U(SCH_1):PAGE77_I5@PURE_QUANTA.Q_CAP(CHIPS)':
 'B': CDS_PINID='B';
NODE_NAME     C423 2
 '@S9S_MB_2U_LIB.S9S_MB_2U(SCH_1):PAGE77_I7@PURE_QUANTA.Q_CAP(CHIPS)':
 'B': CDS_PINID='B';
NODE_NAME     C425 2
 '@S9S_MB_2U_LIB.S9S_MB_2U(SCH_1):PAGE77_I8@PURE_QUANTA.Q_CAP(CHIPS)':
 'B': CDS_PINID='B';
NODE_NAME     C225 2
 '@S9S_MB_2U_LIB.S9S_MB_2U(SCH_1):PAGE77_I10@PURE_QUANTA.Q_CAP(CHIPS)':
 'B': CDS_PINID='B';
NODE_NAME     C230 2
 '@S9S_MB_2U_LIB.S9S_MB_2U(SCH_1):PAGE77_I11@PURE_QUANTA.Q_CAP(CHIPS)':
 'B': CDS_PINID='B';
NODE_NAME     C224 2
 '@S9S_MB_2U_LIB.S9S_MB_2U(SCH_1):PAGE77_I13@PURE_QUANTA.Q_CAP(CHIPS)':
 'B': CDS_PINID='B';
NODE_NAME     C427 2
 '@S9S_MB_2U_LIB.S9S_MB_2U(SCH_1):PAGE77_I15@PURE_QUANTA.Q_CAP(CHIPS)':
 'B': CDS_PINID='B';
NODE_NAME     C429 2
 '@S9S_MB_2U_LIB.S9S_MB_2U(SCH_1):PAGE77_I17@PURE_QUANTA.Q_CAP(CHIPS)':
 'B': CDS_PINID='B';
NODE_NAME     C240 2
 '@S9S_MB_2U_LIB.S9S_MB_2U(SCH_1):PAGE77_I18@PURE_QUANTA.Q_CAP(CHIPS)':
 'B': CDS_PINID='B';
NODE_NAME     C234 2
 '@S9S_MB_2U_LIB.S9S_MB_2U(SCH_1):PAGE77_I19@PURE_QUANTA.Q_CAP(CHIPS)':
 'B': CDS_PINID='B';
NODE_NAME     C239 2
 '@S9S_MB_2U_LIB.S9S_MB_2U(SCH_1):PAGE77_I20@PURE_QUANTA.Q_CAP(CHIPS)':
 'B': CDS_PINID='B';
NODE_NAME     C223 2
 '@S9S_MB_2U_LIB.S9S_MB_2U(SCH_1):PAGE77_I22@PURE_QUANTA.Q_CAP(CHIPS)':
 'B': CDS_PINID='B';
NODE_NAME     C228 2
 '@S9S_MB_2U_LIB.S9S_MB_2U(SCH_1):PAGE77_I23@PURE_QUANTA.Q_CAP(CHIPS)':
 'B': CDS_PINID='B';
NODE_NAME     C222 2
 '@S9S_MB_2U_LIB.S9S_MB_2U(SCH_1):PAGE77_I25@PURE_QUANTA.Q_CAP(CHIPS)':
 'B': CDS_PINID='B';
NODE_NAME     C221 2
 '@S9S_MB_2U_LIB.S9S_MB_2U(SCH_1):PAGE77_I28@PURE_QUANTA.Q_CAP(CHIPS)':
 'B': CDS_PINID='B';
NODE_NAME     C226 2
 '@S9S_MB_2U_LIB.S9S_MB_2U(SCH_1):PAGE77_I29@PURE_QUANTA.Q_CAP(CHIPS)':
 'B': CDS_PINID='B';
NODE_NAME     C233 2
 '@S9S_MB_2U_LIB.S9S_MB_2U(SCH_1):PAGE77_I30@PURE_QUANTA.Q_CAP(CHIPS)':
 'B': CDS_PINID='B';
NODE_NAME     C238 2
 '@S9S_MB_2U_LIB.S9S_MB_2U(SCH_1):PAGE77_I31@PURE_QUANTA.Q_CAP(CHIPS)':
 'B': CDS_PINID='B';
NODE_NAME     C232 2
 '@S9S_MB_2U_LIB.S9S_MB_2U(SCH_1):PAGE77_I32@PURE_QUANTA.Q_CAP(CHIPS)':
 'B': CDS_PINID='B';
NODE_NAME     C231 2
 '@S9S_MB_2U_LIB.S9S_MB_2U(SCH_1):PAGE77_I33@PURE_QUANTA.Q_CAP(CHIPS)':
 'B': CDS_PINID='B';
NODE_NAME     C237 2
 '@S9S_MB_2U_LIB.S9S_MB_2U(SCH_1):PAGE77_I34@PURE_QUANTA.Q_CAP(CHIPS)':
 'B': CDS_PINID='B';
NODE_NAME     C236 2
 '@S9S_MB_2U_LIB.S9S_MB_2U(SCH_1):PAGE77_I35@PURE_QUANTA.Q_CAP(CHIPS)':
 'B': CDS_PINID='B';
NODE_NAME     C431 2
 '@S9S_MB_2U_LIB.S9S_MB_2U(SCH_1):PAGE77_I37@PURE_QUANTA.Q_CAP(CHIPS)':
 'B': CDS_PINID='B';
NODE_NAME     C433 2
 '@S9S_MB_2U_LIB.S9S_MB_2U(SCH_1):PAGE77_I38@PURE_QUANTA.Q_CAP(CHIPS)':
 'B': CDS_PINID='B';
NODE_NAME     C435 2
 '@S9S_MB_2U_LIB.S9S_MB_2U(SCH_1):PAGE77_I39@PURE_QUANTA.Q_CAP(CHIPS)':
 'B': CDS_PINID='B';
NODE_NAME     C245 2
 '@S9S_MB_2U_LIB.S9S_MB_2U(SCH_1):PAGE77_I41@PURE_QUANTA.Q_CAP(CHIPS)':
 'B': CDS_PINID='B';
NODE_NAME     C432 2
 '@S9S_MB_2U_LIB.S9S_MB_2U(SCH_1):PAGE77_I42@PURE_QUANTA.Q_CAP(CHIPS)':
 'B': CDS_PINID='B';
NODE_NAME     C250 2
 '@S9S_MB_2U_LIB.S9S_MB_2U(SCH_1):PAGE77_I44@PURE_QUANTA.Q_CAP(CHIPS)':
 'B': CDS_PINID='B';
NODE_NAME     C244 2
 '@S9S_MB_2U_LIB.S9S_MB_2U(SCH_1):PAGE77_I45@PURE_QUANTA.Q_CAP(CHIPS)':
 'B': CDS_PINID='B';
NODE_NAME     C249 2
 '@S9S_MB_2U_LIB.S9S_MB_2U(SCH_1):PAGE77_I46@PURE_QUANTA.Q_CAP(CHIPS)':
 'B': CDS_PINID='B';
NODE_NAME     C434 2
 '@S9S_MB_2U_LIB.S9S_MB_2U(SCH_1):PAGE77_I47@PURE_QUANTA.Q_CAP(CHIPS)':
 'B': CDS_PINID='B';
NODE_NAME     C255 2
 '@S9S_MB_2U_LIB.S9S_MB_2U(SCH_1):PAGE77_I48@PURE_QUANTA.Q_CAP(CHIPS)':
 'B': CDS_PINID='B';
NODE_NAME     C436 2
 '@S9S_MB_2U_LIB.S9S_MB_2U(SCH_1):PAGE77_I49@PURE_QUANTA.Q_CAP(CHIPS)':
 'B': CDS_PINID='B';
NODE_NAME     C260 2
 '@S9S_MB_2U_LIB.S9S_MB_2U(SCH_1):PAGE77_I50@PURE_QUANTA.Q_CAP(CHIPS)':
 'B': CDS_PINID='B';
NODE_NAME     C254 2
 '@S9S_MB_2U_LIB.S9S_MB_2U(SCH_1):PAGE77_I51@PURE_QUANTA.Q_CAP(CHIPS)':
 'B': CDS_PINID='B';
NODE_NAME     C259 2
 '@S9S_MB_2U_LIB.S9S_MB_2U(SCH_1):PAGE77_I52@PURE_QUANTA.Q_CAP(CHIPS)':
 'B': CDS_PINID='B';
NODE_NAME     C439 2
 '@S9S_MB_2U_LIB.S9S_MB_2U(SCH_1):PAGE77_I53@PURE_QUANTA.Q_CAP(CHIPS)':
 'B': CDS_PINID='B';
NODE_NAME     C441 2
 '@S9S_MB_2U_LIB.S9S_MB_2U(SCH_1):PAGE77_I55@PURE_QUANTA.Q_CAP(CHIPS)':
 'B': CDS_PINID='B';
NODE_NAME     C442 2
 '@S9S_MB_2U_LIB.S9S_MB_2U(SCH_1):PAGE77_I57@PURE_QUANTA.Q_CAP(CHIPS)':
 'B': CDS_PINID='B';
NODE_NAME     C438 2
 '@S9S_MB_2U_LIB.S9S_MB_2U(SCH_1):PAGE77_I58@PURE_QUANTA.Q_CAP(CHIPS)':
 'B': CDS_PINID='B';
NODE_NAME     C265 2
 '@S9S_MB_2U_LIB.S9S_MB_2U(SCH_1):PAGE77_I59@PURE_QUANTA.Q_CAP(CHIPS)':
 'B': CDS_PINID='B';
NODE_NAME     C440 2
 '@S9S_MB_2U_LIB.S9S_MB_2U(SCH_1):PAGE77_I61@PURE_QUANTA.Q_CAP(CHIPS)':
 'B': CDS_PINID='B';
NODE_NAME     C270 2
 '@S9S_MB_2U_LIB.S9S_MB_2U(SCH_1):PAGE77_I62@PURE_QUANTA.Q_CAP(CHIPS)':
 'B': CDS_PINID='B';
NODE_NAME     C264 2
 '@S9S_MB_2U_LIB.S9S_MB_2U(SCH_1):PAGE77_I63@PURE_QUANTA.Q_CAP(CHIPS)':
 'B': CDS_PINID='B';
NODE_NAME     C274 2
 '@S9S_MB_2U_LIB.S9S_MB_2U(SCH_1):PAGE77_I66@PURE_QUANTA.Q_CAP(CHIPS)':
 'B': CDS_PINID='B';
NODE_NAME     C278 2
 '@S9S_MB_2U_LIB.S9S_MB_2U(SCH_1):PAGE77_I71@PURE_QUANTA.Q_CAP(CHIPS)':
 'B': CDS_PINID='B';
NODE_NAME     C282 2
 '@S9S_MB_2U_LIB.S9S_MB_2U(SCH_1):PAGE77_I73@PURE_QUANTA.Q_CAP(CHIPS)':
 'B': CDS_PINID='B';
NODE_NAME     C248 2
 '@S9S_MB_2U_LIB.S9S_MB_2U(SCH_1):PAGE77_I75@PURE_QUANTA.Q_CAP(CHIPS)':
 'B': CDS_PINID='B';
NODE_NAME     C242 2
 '@S9S_MB_2U_LIB.S9S_MB_2U(SCH_1):PAGE77_I76@PURE_QUANTA.Q_CAP(CHIPS)':
 'B': CDS_PINID='B';
NODE_NAME     C247 2
 '@S9S_MB_2U_LIB.S9S_MB_2U(SCH_1):PAGE77_I78@PURE_QUANTA.Q_CAP(CHIPS)':
 'B': CDS_PINID='B';
NODE_NAME     C246 2
 '@S9S_MB_2U_LIB.S9S_MB_2U(SCH_1):PAGE77_I79@PURE_QUANTA.Q_CAP(CHIPS)':
 'B': CDS_PINID='B';
NODE_NAME     C258 2
 '@S9S_MB_2U_LIB.S9S_MB_2U(SCH_1):PAGE77_I81@PURE_QUANTA.Q_CAP(CHIPS)':
 'B': CDS_PINID='B';
NODE_NAME     C251 2
 '@S9S_MB_2U_LIB.S9S_MB_2U(SCH_1):PAGE77_I83@PURE_QUANTA.Q_CAP(CHIPS)':
 'B': CDS_PINID='B';
NODE_NAME     C257 2
 '@S9S_MB_2U_LIB.S9S_MB_2U(SCH_1):PAGE77_I84@PURE_QUANTA.Q_CAP(CHIPS)':
 'B': CDS_PINID='B';
NODE_NAME     C263 2
 '@S9S_MB_2U_LIB.S9S_MB_2U(SCH_1):PAGE77_I86@PURE_QUANTA.Q_CAP(CHIPS)':
 'B': CDS_PINID='B';
NODE_NAME     C268 2
 '@S9S_MB_2U_LIB.S9S_MB_2U(SCH_1):PAGE77_I88@PURE_QUANTA.Q_CAP(CHIPS)':
 'B': CDS_PINID='B';
NODE_NAME     C262 2
 '@S9S_MB_2U_LIB.S9S_MB_2U(SCH_1):PAGE77_I93@PURE_QUANTA.Q_CAP(CHIPS)':
 'B': CDS_PINID='B';
NODE_NAME     C261 2
 '@S9S_MB_2U_LIB.S9S_MB_2U(SCH_1):PAGE77_I95@PURE_QUANTA.Q_CAP(CHIPS)':
 'B': CDS_PINID='B';
NODE_NAME     C272 2
 '@S9S_MB_2U_LIB.S9S_MB_2U(SCH_1):PAGE77_I98@PURE_QUANTA.Q_CAP(CHIPS)':
 'B': CDS_PINID='B';
NODE_NAME     C271 2
 '@S9S_MB_2U_LIB.S9S_MB_2U(SCH_1):PAGE77_I100@PURE_QUANTA.Q_CAP(CHIPS)':
 'B': CDS_PINID='B';
NODE_NAME     C277 2
 '@S9S_MB_2U_LIB.S9S_MB_2U(SCH_1):PAGE77_I101@PURE_QUANTA.Q_CAP(CHIPS)':
 'B': CDS_PINID='B';
NODE_NAME     C281 2
 '@S9S_MB_2U_LIB.S9S_MB_2U(SCH_1):PAGE77_I102@PURE_QUANTA.Q_CAP(CHIPS)':
 'B': CDS_PINID='B';
NODE_NAME     C276 2
 '@S9S_MB_2U_LIB.S9S_MB_2U(SCH_1):PAGE77_I103@PURE_QUANTA.Q_CAP(CHIPS)':
 'B': CDS_PINID='B';
NODE_NAME     C275 2
 '@S9S_MB_2U_LIB.S9S_MB_2U(SCH_1):PAGE77_I104@PURE_QUANTA.Q_CAP(CHIPS)':
 'B': CDS_PINID='B';
NODE_NAME     C280 2
 '@S9S_MB_2U_LIB.S9S_MB_2U(SCH_1):PAGE77_I105@PURE_QUANTA.Q_CAP(CHIPS)':
 'B': CDS_PINID='B';
NODE_NAME     C279 2
 '@S9S_MB_2U_LIB.S9S_MB_2U(SCH_1):PAGE77_I106@PURE_QUANTA.Q_CAP(CHIPS)':
 'B': CDS_PINID='B';
NODE_NAME     C444 2
 '@S9S_MB_2U_LIB.S9S_MB_2U(SCH_1):PAGE77_I109@PURE_QUANTA.Q_CAP(CHIPS)':
 'B': CDS_PINID='B';
NODE_NAME     C445 2
 '@S9S_MB_2U_LIB.S9S_MB_2U(SCH_1):PAGE77_I110@PURE_QUANTA.Q_CAP(CHIPS)':
 'B': CDS_PINID='B';
NODE_NAME     C286 2
 '@S9S_MB_2U_LIB.S9S_MB_2U(SCH_1):PAGE77_I111@PURE_QUANTA.Q_CAP(CHIPS)':
 'B': CDS_PINID='B';
NODE_NAME     C290 2
 '@S9S_MB_2U_LIB.S9S_MB_2U(SCH_1):PAGE77_I112@PURE_QUANTA.Q_CAP(CHIPS)':
 'B': CDS_PINID='B';
NODE_NAME     C446 2
 '@S9S_MB_2U_LIB.S9S_MB_2U(SCH_1):PAGE77_I113@PURE_QUANTA.Q_CAP(CHIPS)':
 'B': CDS_PINID='B';
NODE_NAME     C294 2
 '@S9S_MB_2U_LIB.S9S_MB_2U(SCH_1):PAGE77_I114@PURE_QUANTA.Q_CAP(CHIPS)':
 'B': CDS_PINID='B';
NODE_NAME     C298 2
 '@S9S_MB_2U_LIB.S9S_MB_2U(SCH_1):PAGE77_I115@PURE_QUANTA.Q_CAP(CHIPS)':
 'B': CDS_PINID='B';
NODE_NAME     C302 2
 '@S9S_MB_2U_LIB.S9S_MB_2U(SCH_1):PAGE77_I117@PURE_QUANTA.Q_CAP(CHIPS)':
 'B': CDS_PINID='B';
NODE_NAME     C306 2
 '@S9S_MB_2U_LIB.S9S_MB_2U(SCH_1):PAGE77_I118@PURE_QUANTA.Q_CAP(CHIPS)':
 'B': CDS_PINID='B';
NODE_NAME     C285 2
 '@S9S_MB_2U_LIB.S9S_MB_2U(SCH_1):PAGE77_I119@PURE_QUANTA.Q_CAP(CHIPS)':
 'B': CDS_PINID='B';
NODE_NAME     C289 2
 '@S9S_MB_2U_LIB.S9S_MB_2U(SCH_1):PAGE77_I120@PURE_QUANTA.Q_CAP(CHIPS)':
 'B': CDS_PINID='B';
NODE_NAME     C284 2
 '@S9S_MB_2U_LIB.S9S_MB_2U(SCH_1):PAGE77_I121@PURE_QUANTA.Q_CAP(CHIPS)':
 'B': CDS_PINID='B';
NODE_NAME     C283 2
 '@S9S_MB_2U_LIB.S9S_MB_2U(SCH_1):PAGE77_I122@PURE_QUANTA.Q_CAP(CHIPS)':
 'B': CDS_PINID='B';
NODE_NAME     C288 2
 '@S9S_MB_2U_LIB.S9S_MB_2U(SCH_1):PAGE77_I123@PURE_QUANTA.Q_CAP(CHIPS)':
 'B': CDS_PINID='B';
NODE_NAME     C293 2
 '@S9S_MB_2U_LIB.S9S_MB_2U(SCH_1):PAGE77_I125@PURE_QUANTA.Q_CAP(CHIPS)':
 'B': CDS_PINID='B';
NODE_NAME     C297 2
 '@S9S_MB_2U_LIB.S9S_MB_2U(SCH_1):PAGE77_I126@PURE_QUANTA.Q_CAP(CHIPS)':
 'B': CDS_PINID='B';
NODE_NAME     C296 2
 '@S9S_MB_2U_LIB.S9S_MB_2U(SCH_1):PAGE77_I129@PURE_QUANTA.Q_CAP(CHIPS)':
 'B': CDS_PINID='B';
NODE_NAME     C295 2
 '@S9S_MB_2U_LIB.S9S_MB_2U(SCH_1):PAGE77_I130@PURE_QUANTA.Q_CAP(CHIPS)':
 'B': CDS_PINID='B';
NODE_NAME     C299 2
 '@S9S_MB_2U_LIB.S9S_MB_2U(SCH_1):PAGE77_I131@PURE_QUANTA.Q_CAP(CHIPS)':
 'B': CDS_PINID='B';
NODE_NAME     C300 2
 '@S9S_MB_2U_LIB.S9S_MB_2U(SCH_1):PAGE77_I132@PURE_QUANTA.Q_CAP(CHIPS)':
 'B': CDS_PINID='B';
NODE_NAME     C301 2
 '@S9S_MB_2U_LIB.S9S_MB_2U(SCH_1):PAGE77_I133@PURE_QUANTA.Q_CAP(CHIPS)':
 'B': CDS_PINID='B';
NODE_NAME     C305 2
 '@S9S_MB_2U_LIB.S9S_MB_2U(SCH_1):PAGE77_I134@PURE_QUANTA.Q_CAP(CHIPS)':
 'B': CDS_PINID='B';
NODE_NAME     C309 2
 '@S9S_MB_2U_LIB.S9S_MB_2U(SCH_1):PAGE77_I136@PURE_QUANTA.Q_CAP(CHIPS)':
 'B': CDS_PINID='B';
NODE_NAME     C304 2
 '@S9S_MB_2U_LIB.S9S_MB_2U(SCH_1):PAGE77_I138@PURE_QUANTA.Q_CAP(CHIPS)':
 'B': CDS_PINID='B';
NODE_NAME     C308 2
 '@S9S_MB_2U_LIB.S9S_MB_2U(SCH_1):PAGE77_I140@PURE_QUANTA.Q_CAP(CHIPS)':
 'B': CDS_PINID='B';
NODE_NAME     C453 2
 '@S9S_MB_2U_LIB.S9S_MB_2U(SCH_1):PAGE78_I3@PURE_QUANTA.Q_CAP(CHIPS)':
 'B': CDS_PINID='B';
NODE_NAME     C461 2
 '@S9S_MB_2U_LIB.S9S_MB_2U(SCH_1):PAGE78_I5@PURE_QUANTA.Q_CAP(CHIPS)':
 'B': CDS_PINID='B';
NODE_NAME     C465 2
 '@S9S_MB_2U_LIB.S9S_MB_2U(SCH_1):PAGE78_I7@PURE_QUANTA.Q_CAP(CHIPS)':
 'B': CDS_PINID='B';
NODE_NAME     C490 2
 '@S9S_MB_2U_LIB.S9S_MB_2U(SCH_1):PAGE78_I23@PURE_QUANTA.Q_CAP(CHIPS)':
 'B': CDS_PINID='B';
NODE_NAME     C451 2
 '@S9S_MB_2U_LIB.S9S_MB_2U(SCH_1):PAGE78_I24@PURE_QUANTA.Q_CAP(CHIPS)':
 'B': CDS_PINID='B';
NODE_NAME     C318 2
 '@S9S_MB_2U_LIB.S9S_MB_2U(SCH_1):PAGE78_I27@PURE_QUANTA.Q_CAP(CHIPS)':
 'B': CDS_PINID='B';
NODE_NAME     C474 2
 '@S9S_MB_2U_LIB.S9S_MB_2U(SCH_1):PAGE78_I29@PURE_QUANTA.Q_CAP(CHIPS)':
 'B': CDS_PINID='B';
NODE_NAME     C327 2
 '@S9S_MB_2U_LIB.S9S_MB_2U(SCH_1):PAGE78_I32@PURE_QUANTA.Q_CAP(CHIPS)':
 'B': CDS_PINID='B';
NODE_NAME     C336 2
 '@S9S_MB_2U_LIB.S9S_MB_2U(SCH_1):PAGE78_I35@PURE_QUANTA.Q_CAP(CHIPS)':
 'B': CDS_PINID='B';
NODE_NAME     C314 2
 '@S9S_MB_2U_LIB.S9S_MB_2U(SCH_1):PAGE78_I37@PURE_QUANTA.Q_CAP(CHIPS)':
 'B': CDS_PINID='B';
NODE_NAME     C320 2
 '@S9S_MB_2U_LIB.S9S_MB_2U(SCH_1):PAGE78_I39@PURE_QUANTA.Q_CAP(CHIPS)':
 'B': CDS_PINID='B';
NODE_NAME     C323 2
 '@S9S_MB_2U_LIB.S9S_MB_2U(SCH_1):PAGE78_I40@PURE_QUANTA.Q_CAP(CHIPS)':
 'B': CDS_PINID='B';
NODE_NAME     C326 2
 '@S9S_MB_2U_LIB.S9S_MB_2U(SCH_1):PAGE78_I41@PURE_QUANTA.Q_CAP(CHIPS)':
 'B': CDS_PINID='B';
NODE_NAME     C1391 2
 '@S9S_MB_2U_LIB.S9S_MB_2U(SCH_1):PAGE78_I52@PURE_QUANTA.Q_CAP(CHIPS)':
 'B': CDS_PINID='B';
NODE_NAME     C313 2
 '@S9S_MB_2U_LIB.S9S_MB_2U(SCH_1):PAGE78_I58@PURE_QUANTA.Q_CAP(CHIPS)':
 'B': CDS_PINID='B';
NODE_NAME     C316 2
 '@S9S_MB_2U_LIB.S9S_MB_2U(SCH_1):PAGE78_I60@PURE_QUANTA.Q_CAP(CHIPS)':
 'B': CDS_PINID='B';
NODE_NAME     C353 2
 '@S9S_MB_2U_LIB.S9S_MB_2U(SCH_1):PAGE78_I65@PURE_QUANTA.Q_CAP(CHIPS)':
 'B': CDS_PINID='B';
NODE_NAME     C337 2
 '@S9S_MB_2U_LIB.S9S_MB_2U(SCH_1):PAGE78_I66@PURE_QUANTA.Q_CAP(CHIPS)':
 'B': CDS_PINID='B';
NODE_NAME     C483 2
 '@S9S_MB_2U_LIB.S9S_MB_2U(SCH_1):PAGE78_I68@PURE_QUANTA.Q_CAP(CHIPS)':
 'B': CDS_PINID='B';
NODE_NAME     C450 2
 '@S9S_MB_2U_LIB.S9S_MB_2U(SCH_1):PAGE79_I1@PURE_QUANTA.Q_CAP(CHIPS)':
 'B': CDS_PINID='B';
NODE_NAME     C454 2
 '@S9S_MB_2U_LIB.S9S_MB_2U(SCH_1):PAGE79_I3@PURE_QUANTA.Q_CAP(CHIPS)':
 'B': CDS_PINID='B';
NODE_NAME     C458 2
 '@S9S_MB_2U_LIB.S9S_MB_2U(SCH_1):PAGE79_I4@PURE_QUANTA.Q_CAP(CHIPS)':
 'B': CDS_PINID='B';
NODE_NAME     C462 2
 '@S9S_MB_2U_LIB.S9S_MB_2U(SCH_1):PAGE79_I5@PURE_QUANTA.Q_CAP(CHIPS)':
 'B': CDS_PINID='B';
NODE_NAME     C466 2
 '@S9S_MB_2U_LIB.S9S_MB_2U(SCH_1):PAGE79_I7@PURE_QUANTA.Q_CAP(CHIPS)':
 'B': CDS_PINID='B';
NODE_NAME     C470 2
 '@S9S_MB_2U_LIB.S9S_MB_2U(SCH_1):PAGE79_I8@PURE_QUANTA.Q_CAP(CHIPS)':
 'B': CDS_PINID='B';
NODE_NAME     C473 2
 '@S9S_MB_2U_LIB.S9S_MB_2U(SCH_1):PAGE79_I9@PURE_QUANTA.Q_CAP(CHIPS)':
 'B': CDS_PINID='B';
NODE_NAME     C487 2
 '@S9S_MB_2U_LIB.S9S_MB_2U(SCH_1):PAGE79_I10@PURE_QUANTA.Q_CAP(CHIPS)':
 'B': CDS_PINID='B';
NODE_NAME     C486 2
 '@S9S_MB_2U_LIB.S9S_MB_2U(SCH_1):PAGE79_I11@PURE_QUANTA.Q_CAP(CHIPS)':
 'B': CDS_PINID='B';
NODE_NAME     C1364 2
 '@S9S_MB_2U_LIB.S9S_MB_2U(SCH_1):PAGE80_I9@PURE_QUANTA.Q_CAP(CHIPS)':
 'B': CDS_PINID='B';
NODE_NAME     C1365 2
 '@S9S_MB_2U_LIB.S9S_MB_2U(SCH_1):PAGE80_I20@PURE_QUANTA.Q_CAP(CHIPS)':
 'B': CDS_PINID='B';
NODE_NAME     C1366 2
 '@S9S_MB_2U_LIB.S9S_MB_2U(SCH_1):PAGE80_I28@PURE_QUANTA.Q_CAP(CHIPS)':
 'B': CDS_PINID='B';
NODE_NAME     C3 2
 '@S9S_MB_2U_LIB.S9S_MB_2U(SCH_1):PAGE82_I188@PURE_QUANTA.Q_CAP(CHIPS)':
 'B': CDS_PINID='B';
NODE_NAME     C4 2
 '@S9S_MB_2U_LIB.S9S_MB_2U(SCH_1):PAGE82_I190@PURE_QUANTA.Q_CAP(CHIPS)':
 'B': CDS_PINID='B';
NODE_NAME     C2 2
 '@S9S_MB_2U_LIB.S9S_MB_2U(SCH_1):PAGE82_I192@PURE_QUANTA.Q_CAP(CHIPS)':
 'B': CDS_PINID='B';
NODE_NAME     R26 2
 '@S9S_MB_2U_LIB.S9S_MB_2U(SCH_1):PAGE82_I196@PURE_QUANTA.Q_RES(CHIPS)':
 'B': CDS_PINID='B';
NODE_NAME     R27 2
 '@S9S_MB_2U_LIB.S9S_MB_2U(SCH_1):PAGE83_I10@PURE_QUANTA.Q_RES(CHIPS)':
 'B': CDS_PINID='B';
NODE_NAME     C5 2
 '@S9S_MB_2U_LIB.S9S_MB_2U(SCH_1):PAGE83_I120@PURE_QUANTA.Q_CAP(CHIPS)':
 'B': CDS_PINID='B';
NODE_NAME     C6 2
 '@S9S_MB_2U_LIB.S9S_MB_2U(SCH_1):PAGE83_I122@PURE_QUANTA.Q_CAP(CHIPS)':
 'B': CDS_PINID='B';
NODE_NAME     C7 2
 '@S9S_MB_2U_LIB.S9S_MB_2U(SCH_1):PAGE83_I144@PURE_QUANTA.Q_CAP(CHIPS)':
 'B': CDS_PINID='B';
NODE_NAME     J2 G1
 '@S9S_MB_2U_LIB.S9S_MB_2U(SCH_1):PAGE83_I179@PURE_QUANTA.SCONN288_ADR50017P087CC(CHIPS)':
 'G1': CDS_PINID='G1';
NODE_NAME     J2 G2
 '@S9S_MB_2U_LIB.S9S_MB_2U(SCH_1):PAGE83_I179@PURE_QUANTA.SCONN288_ADR50017P087CC(CHIPS)':
 'G2': CDS_PINID='G2';
NODE_NAME     J2 G3
 '@S9S_MB_2U_LIB.S9S_MB_2U(SCH_1):PAGE83_I179@PURE_QUANTA.SCONN288_ADR50017P087CC(CHIPS)':
 'G3': CDS_PINID='G3';
NODE_NAME     J2 6
 '@S9S_MB_2U_LIB.S9S_MB_2U(SCH_1):PAGE83_I179@PURE_QUANTA.SCONN288_ADR50017P087CC(CHIPS)':
 'VSS0': CDS_PINID='VSS0';
NODE_NAME     J2 8
 '@S9S_MB_2U_LIB.S9S_MB_2U(SCH_1):PAGE83_I179@PURE_QUANTA.SCONN288_ADR50017P087CC(CHIPS)':
 'VSS1': CDS_PINID='VSS1';
NODE_NAME     J2 10
 '@S9S_MB_2U_LIB.S9S_MB_2U(SCH_1):PAGE83_I179@PURE_QUANTA.SCONN288_ADR50017P087CC(CHIPS)':
 'VSS2': CDS_PINID='VSS2';
NODE_NAME     J2 13
 '@S9S_MB_2U_LIB.S9S_MB_2U(SCH_1):PAGE83_I179@PURE_QUANTA.SCONN288_ADR50017P087CC(CHIPS)':
 'VSS3': CDS_PINID='VSS3';
NODE_NAME     J2 15
 '@S9S_MB_2U_LIB.S9S_MB_2U(SCH_1):PAGE83_I179@PURE_QUANTA.SCONN288_ADR50017P087CC(CHIPS)':
 'VSS4': CDS_PINID='VSS4';
NODE_NAME     J2 17
 '@S9S_MB_2U_LIB.S9S_MB_2U(SCH_1):PAGE83_I179@PURE_QUANTA.SCONN288_ADR50017P087CC(CHIPS)':
 'VSS5': CDS_PINID='VSS5';
NODE_NAME     J2 19
 '@S9S_MB_2U_LIB.S9S_MB_2U(SCH_1):PAGE83_I179@PURE_QUANTA.SCONN288_ADR50017P087CC(CHIPS)':
 'VSS6': CDS_PINID='VSS6';
NODE_NAME     J2 21
 '@S9S_MB_2U_LIB.S9S_MB_2U(SCH_1):PAGE83_I179@PURE_QUANTA.SCONN288_ADR50017P087CC(CHIPS)':
 'VSS7': CDS_PINID='VSS7';
NODE_NAME     J2 24
 '@S9S_MB_2U_LIB.S9S_MB_2U(SCH_1):PAGE83_I179@PURE_QUANTA.SCONN288_ADR50017P087CC(CHIPS)':
 'VSS8': CDS_PINID='VSS8';
NODE_NAME     J2 26
 '@S9S_MB_2U_LIB.S9S_MB_2U(SCH_1):PAGE83_I179@PURE_QUANTA.SCONN288_ADR50017P087CC(CHIPS)':
 'VSS9': CDS_PINID='VSS9';
NODE_NAME     J2 28
 '@S9S_MB_2U_LIB.S9S_MB_2U(SCH_1):PAGE83_I179@PURE_QUANTA.SCONN288_ADR50017P087CC(CHIPS)':
 'VSS10': CDS_PINID='VSS10';
NODE_NAME     J2 30
 '@S9S_MB_2U_LIB.S9S_MB_2U(SCH_1):PAGE83_I179@PURE_QUANTA.SCONN288_ADR50017P087CC(CHIPS)':
 'VSS11': CDS_PINID='VSS11';
NODE_NAME     J2 32
 '@S9S_MB_2U_LIB.S9S_MB_2U(SCH_1):PAGE83_I179@PURE_QUANTA.SCONN288_ADR50017P087CC(CHIPS)':
 'VSS12': CDS_PINID='VSS12';
NODE_NAME     J2 35
 '@S9S_MB_2U_LIB.S9S_MB_2U(SCH_1):PAGE83_I179@PURE_QUANTA.SCONN288_ADR50017P087CC(CHIPS)':
 'VSS13': CDS_PINID='VSS13';
NODE_NAME     J2 37
 '@S9S_MB_2U_LIB.S9S_MB_2U(SCH_1):PAGE83_I179@PURE_QUANTA.SCONN288_ADR50017P087CC(CHIPS)':
 'VSS14': CDS_PINID='VSS14';
NODE_NAME     J2 39
 '@S9S_MB_2U_LIB.S9S_MB_2U(SCH_1):PAGE83_I179@PURE_QUANTA.SCONN288_ADR50017P087CC(CHIPS)':
 'VSS15': CDS_PINID='VSS15';
NODE_NAME     J2 41
 '@S9S_MB_2U_LIB.S9S_MB_2U(SCH_1):PAGE83_I179@PURE_QUANTA.SCONN288_ADR50017P087CC(CHIPS)':
 'VSS16': CDS_PINID='VSS16';
NODE_NAME     J2 43
 '@S9S_MB_2U_LIB.S9S_MB_2U(SCH_1):PAGE83_I179@PURE_QUANTA.SCONN288_ADR50017P087CC(CHIPS)':
 'VSS17': CDS_PINID='VSS17';
NODE_NAME     J2 46
 '@S9S_MB_2U_LIB.S9S_MB_2U(SCH_1):PAGE83_I179@PURE_QUANTA.SCONN288_ADR50017P087CC(CHIPS)':
 'VSS18': CDS_PINID='VSS18';
NODE_NAME     J2 48
 '@S9S_MB_2U_LIB.S9S_MB_2U(SCH_1):PAGE83_I179@PURE_QUANTA.SCONN288_ADR50017P087CC(CHIPS)':
 'VSS19': CDS_PINID='VSS19';
NODE_NAME     J2 50
 '@S9S_MB_2U_LIB.S9S_MB_2U(SCH_1):PAGE83_I179@PURE_QUANTA.SCONN288_ADR50017P087CC(CHIPS)':
 'VSS20': CDS_PINID='VSS20';
NODE_NAME     J2 52
 '@S9S_MB_2U_LIB.S9S_MB_2U(SCH_1):PAGE83_I179@PURE_QUANTA.SCONN288_ADR50017P087CC(CHIPS)':
 'VSS21': CDS_PINID='VSS21';
NODE_NAME     J2 54
 '@S9S_MB_2U_LIB.S9S_MB_2U(SCH_1):PAGE83_I179@PURE_QUANTA.SCONN288_ADR50017P087CC(CHIPS)':
 'VSS22': CDS_PINID='VSS22';
NODE_NAME     J2 57
 '@S9S_MB_2U_LIB.S9S_MB_2U(SCH_1):PAGE83_I179@PURE_QUANTA.SCONN288_ADR50017P087CC(CHIPS)':
 'VSS23': CDS_PINID='VSS23';
NODE_NAME     J2 59
 '@S9S_MB_2U_LIB.S9S_MB_2U(SCH_1):PAGE83_I179@PURE_QUANTA.SCONN288_ADR50017P087CC(CHIPS)':
 'VSS24': CDS_PINID='VSS24';
NODE_NAME     J2 61
 '@S9S_MB_2U_LIB.S9S_MB_2U(SCH_1):PAGE83_I179@PURE_QUANTA.SCONN288_ADR50017P087CC(CHIPS)':
 'VSS25': CDS_PINID='VSS25';
NODE_NAME     J2 63
 '@S9S_MB_2U_LIB.S9S_MB_2U(SCH_1):PAGE83_I179@PURE_QUANTA.SCONN288_ADR50017P087CC(CHIPS)':
 'VSS26': CDS_PINID='VSS26';
NODE_NAME     J2 65
 '@S9S_MB_2U_LIB.S9S_MB_2U(SCH_1):PAGE83_I179@PURE_QUANTA.SCONN288_ADR50017P087CC(CHIPS)':
 'VSS27': CDS_PINID='VSS27';
NODE_NAME     J2 67
 '@S9S_MB_2U_LIB.S9S_MB_2U(SCH_1):PAGE83_I179@PURE_QUANTA.SCONN288_ADR50017P087CC(CHIPS)':
 'VSS28': CDS_PINID='VSS28';
NODE_NAME     J2 69
 '@S9S_MB_2U_LIB.S9S_MB_2U(SCH_1):PAGE83_I179@PURE_QUANTA.SCONN288_ADR50017P087CC(CHIPS)':
 'VSS29': CDS_PINID='VSS29';
NODE_NAME     J2 71
 '@S9S_MB_2U_LIB.S9S_MB_2U(SCH_1):PAGE83_I179@PURE_QUANTA.SCONN288_ADR50017P087CC(CHIPS)':
 'VSS30': CDS_PINID='VSS30';
NODE_NAME     J2 73
 '@S9S_MB_2U_LIB.S9S_MB_2U(SCH_1):PAGE83_I179@PURE_QUANTA.SCONN288_ADR50017P087CC(CHIPS)':
 'VSS31': CDS_PINID='VSS31';
NODE_NAME     J2 75
 '@S9S_MB_2U_LIB.S9S_MB_2U(SCH_1):PAGE83_I179@PURE_QUANTA.SCONN288_ADR50017P087CC(CHIPS)':
 'VSS32': CDS_PINID='VSS32';
NODE_NAME     J2 77
 '@S9S_MB_2U_LIB.S9S_MB_2U(SCH_1):PAGE83_I179@PURE_QUANTA.SCONN288_ADR50017P087CC(CHIPS)':
 'VSS33': CDS_PINID='VSS33';
NODE_NAME     J2 79
 '@S9S_MB_2U_LIB.S9S_MB_2U(SCH_1):PAGE83_I179@PURE_QUANTA.SCONN288_ADR50017P087CC(CHIPS)':
 'VSS34': CDS_PINID='VSS34';
NODE_NAME     J2 81
 '@S9S_MB_2U_LIB.S9S_MB_2U(SCH_1):PAGE83_I179@PURE_QUANTA.SCONN288_ADR50017P087CC(CHIPS)':
 'VSS35': CDS_PINID='VSS35';
NODE_NAME     J2 83
 '@S9S_MB_2U_LIB.S9S_MB_2U(SCH_1):PAGE83_I179@PURE_QUANTA.SCONN288_ADR50017P087CC(CHIPS)':
 'VSS36': CDS_PINID='VSS36';
NODE_NAME     J2 85
 '@S9S_MB_2U_LIB.S9S_MB_2U(SCH_1):PAGE83_I179@PURE_QUANTA.SCONN288_ADR50017P087CC(CHIPS)':
 'VSS37': CDS_PINID='VSS37';
NODE_NAME     J2 88
 '@S9S_MB_2U_LIB.S9S_MB_2U(SCH_1):PAGE83_I179@PURE_QUANTA.SCONN288_ADR50017P087CC(CHIPS)':
 'VSS38': CDS_PINID='VSS38';
NODE_NAME     J2 90
 '@S9S_MB_2U_LIB.S9S_MB_2U(SCH_1):PAGE83_I179@PURE_QUANTA.SCONN288_ADR50017P087CC(CHIPS)':
 'VSS39': CDS_PINID='VSS39';
NODE_NAME     J2 92
 '@S9S_MB_2U_LIB.S9S_MB_2U(SCH_1):PAGE83_I179@PURE_QUANTA.SCONN288_ADR50017P087CC(CHIPS)':
 'VSS40': CDS_PINID='VSS40';
NODE_NAME     J2 95
 '@S9S_MB_2U_LIB.S9S_MB_2U(SCH_1):PAGE83_I179@PURE_QUANTA.SCONN288_ADR50017P087CC(CHIPS)':
 'VSS41': CDS_PINID='VSS41';
NODE_NAME     J2 97
 '@S9S_MB_2U_LIB.S9S_MB_2U(SCH_1):PAGE83_I179@PURE_QUANTA.SCONN288_ADR50017P087CC(CHIPS)':
 'VSS42': CDS_PINID='VSS42';
NODE_NAME     J2 99
 '@S9S_MB_2U_LIB.S9S_MB_2U(SCH_1):PAGE83_I179@PURE_QUANTA.SCONN288_ADR50017P087CC(CHIPS)':
 'VSS43': CDS_PINID='VSS43';
NODE_NAME     J2 101
 '@S9S_MB_2U_LIB.S9S_MB_2U(SCH_1):PAGE83_I179@PURE_QUANTA.SCONN288_ADR50017P087CC(CHIPS)':
 'VSS44': CDS_PINID='VSS44';
NODE_NAME     J2 103
 '@S9S_MB_2U_LIB.S9S_MB_2U(SCH_1):PAGE83_I179@PURE_QUANTA.SCONN288_ADR50017P087CC(CHIPS)':
 'VSS45': CDS_PINID='VSS45';
NODE_NAME     J2 106
 '@S9S_MB_2U_LIB.S9S_MB_2U(SCH_1):PAGE83_I179@PURE_QUANTA.SCONN288_ADR50017P087CC(CHIPS)':
 'VSS46': CDS_PINID='VSS46';
NODE_NAME     J2 108
 '@S9S_MB_2U_LIB.S9S_MB_2U(SCH_1):PAGE83_I179@PURE_QUANTA.SCONN288_ADR50017P087CC(CHIPS)':
 'VSS47': CDS_PINID='VSS47';
NODE_NAME     J2 110
 '@S9S_MB_2U_LIB.S9S_MB_2U(SCH_1):PAGE83_I179@PURE_QUANTA.SCONN288_ADR50017P087CC(CHIPS)':
 'VSS48': CDS_PINID='VSS48';
NODE_NAME     J2 112
 '@S9S_MB_2U_LIB.S9S_MB_2U(SCH_1):PAGE83_I179@PURE_QUANTA.SCONN288_ADR50017P087CC(CHIPS)':
 'VSS49': CDS_PINID='VSS49';
NODE_NAME     J2 114
 '@S9S_MB_2U_LIB.S9S_MB_2U(SCH_1):PAGE83_I179@PURE_QUANTA.SCONN288_ADR50017P087CC(CHIPS)':
 'VSS50': CDS_PINID='VSS50';
NODE_NAME     J2 117
 '@S9S_MB_2U_LIB.S9S_MB_2U(SCH_1):PAGE83_I179@PURE_QUANTA.SCONN288_ADR50017P087CC(CHIPS)':
 'VSS51': CDS_PINID='VSS51';
NODE_NAME     J2 119
 '@S9S_MB_2U_LIB.S9S_MB_2U(SCH_1):PAGE83_I179@PURE_QUANTA.SCONN288_ADR50017P087CC(CHIPS)':
 'VSS52': CDS_PINID='VSS52';
NODE_NAME     J2 121
 '@S9S_MB_2U_LIB.S9S_MB_2U(SCH_1):PAGE83_I179@PURE_QUANTA.SCONN288_ADR50017P087CC(CHIPS)':
 'VSS53': CDS_PINID='VSS53';
NODE_NAME     J2 123
 '@S9S_MB_2U_LIB.S9S_MB_2U(SCH_1):PAGE83_I179@PURE_QUANTA.SCONN288_ADR50017P087CC(CHIPS)':
 'VSS54': CDS_PINID='VSS54';
NODE_NAME     J2 125
 '@S9S_MB_2U_LIB.S9S_MB_2U(SCH_1):PAGE83_I179@PURE_QUANTA.SCONN288_ADR50017P087CC(CHIPS)':
 'VSS55': CDS_PINID='VSS55';
NODE_NAME     J2 128
 '@S9S_MB_2U_LIB.S9S_MB_2U(SCH_1):PAGE83_I179@PURE_QUANTA.SCONN288_ADR50017P087CC(CHIPS)':
 'VSS56': CDS_PINID='VSS56';
NODE_NAME     J2 130
 '@S9S_MB_2U_LIB.S9S_MB_2U(SCH_1):PAGE83_I179@PURE_QUANTA.SCONN288_ADR50017P087CC(CHIPS)':
 'VSS57': CDS_PINID='VSS57';
NODE_NAME     J2 132
 '@S9S_MB_2U_LIB.S9S_MB_2U(SCH_1):PAGE83_I179@PURE_QUANTA.SCONN288_ADR50017P087CC(CHIPS)':
 'VSS58': CDS_PINID='VSS58';
NODE_NAME     J2 134
 '@S9S_MB_2U_LIB.S9S_MB_2U(SCH_1):PAGE83_I179@PURE_QUANTA.SCONN288_ADR50017P087CC(CHIPS)':
 'VSS59': CDS_PINID='VSS59';
NODE_NAME     J2 136
 '@S9S_MB_2U_LIB.S9S_MB_2U(SCH_1):PAGE83_I179@PURE_QUANTA.SCONN288_ADR50017P087CC(CHIPS)':
 'VSS60': CDS_PINID='VSS60';
NODE_NAME     J2 139
 '@S9S_MB_2U_LIB.S9S_MB_2U(SCH_1):PAGE83_I179@PURE_QUANTA.SCONN288_ADR50017P087CC(CHIPS)':
 'VSS61': CDS_PINID='VSS61';
NODE_NAME     J2 141
 '@S9S_MB_2U_LIB.S9S_MB_2U(SCH_1):PAGE83_I179@PURE_QUANTA.SCONN288_ADR50017P087CC(CHIPS)':
 'VSS62': CDS_PINID='VSS62';
NODE_NAME     J2 143
 '@S9S_MB_2U_LIB.S9S_MB_2U(SCH_1):PAGE83_I179@PURE_QUANTA.SCONN288_ADR50017P087CC(CHIPS)':
 'VSS63': CDS_PINID='VSS63';
NODE_NAME     J2 151
 '@S9S_MB_2U_LIB.S9S_MB_2U(SCH_1):PAGE83_I179@PURE_QUANTA.SCONN288_ADR50017P087CC(CHIPS)':
 'VSS64': CDS_PINID='VSS64';
NODE_NAME     J2 153
 '@S9S_MB_2U_LIB.S9S_MB_2U(SCH_1):PAGE83_I179@PURE_QUANTA.SCONN288_ADR50017P087CC(CHIPS)':
 'VSS65': CDS_PINID='VSS65';
NODE_NAME     J2 155
 '@S9S_MB_2U_LIB.S9S_MB_2U(SCH_1):PAGE83_I179@PURE_QUANTA.SCONN288_ADR50017P087CC(CHIPS)':
 'VSS66': CDS_PINID='VSS66';
NODE_NAME     J2 158
 '@S9S_MB_2U_LIB.S9S_MB_2U(SCH_1):PAGE83_I179@PURE_QUANTA.SCONN288_ADR50017P087CC(CHIPS)':
 'VSS67': CDS_PINID='VSS67';
NODE_NAME     J2 160
 '@S9S_MB_2U_LIB.S9S_MB_2U(SCH_1):PAGE83_I179@PURE_QUANTA.SCONN288_ADR50017P087CC(CHIPS)':
 'VSS68': CDS_PINID='VSS68';
NODE_NAME     J2 162
 '@S9S_MB_2U_LIB.S9S_MB_2U(SCH_1):PAGE83_I179@PURE_QUANTA.SCONN288_ADR50017P087CC(CHIPS)':
 'VSS69': CDS_PINID='VSS69';
NODE_NAME     J2 164
 '@S9S_MB_2U_LIB.S9S_MB_2U(SCH_1):PAGE83_I179@PURE_QUANTA.SCONN288_ADR50017P087CC(CHIPS)':
 'VSS70': CDS_PINID='VSS70';
NODE_NAME     J2 166
 '@S9S_MB_2U_LIB.S9S_MB_2U(SCH_1):PAGE83_I179@PURE_QUANTA.SCONN288_ADR50017P087CC(CHIPS)':
 'VSS71': CDS_PINID='VSS71';
NODE_NAME     J2 169
 '@S9S_MB_2U_LIB.S9S_MB_2U(SCH_1):PAGE83_I179@PURE_QUANTA.SCONN288_ADR50017P087CC(CHIPS)':
 'VSS72': CDS_PINID='VSS72';
NODE_NAME     J2 171
 '@S9S_MB_2U_LIB.S9S_MB_2U(SCH_1):PAGE83_I179@PURE_QUANTA.SCONN288_ADR50017P087CC(CHIPS)':
 'VSS73': CDS_PINID='VSS73';
NODE_NAME     J2 173
 '@S9S_MB_2U_LIB.S9S_MB_2U(SCH_1):PAGE83_I179@PURE_QUANTA.SCONN288_ADR50017P087CC(CHIPS)':
 'VSS74': CDS_PINID='VSS74';
NODE_NAME     J2 175
 '@S9S_MB_2U_LIB.S9S_MB_2U(SCH_1):PAGE83_I179@PURE_QUANTA.SCONN288_ADR50017P087CC(CHIPS)':
 'VSS75': CDS_PINID='VSS75';
NODE_NAME     J2 177
 '@S9S_MB_2U_LIB.S9S_MB_2U(SCH_1):PAGE83_I179@PURE_QUANTA.SCONN288_ADR50017P087CC(CHIPS)':
 'VSS76': CDS_PINID='VSS76';
NODE_NAME     J2 180
 '@S9S_MB_2U_LIB.S9S_MB_2U(SCH_1):PAGE83_I179@PURE_QUANTA.SCONN288_ADR50017P087CC(CHIPS)':
 'VSS77': CDS_PINID='VSS77';
NODE_NAME     J2 182
 '@S9S_MB_2U_LIB.S9S_MB_2U(SCH_1):PAGE83_I179@PURE_QUANTA.SCONN288_ADR50017P087CC(CHIPS)':
 'VSS78': CDS_PINID='VSS78';
NODE_NAME     J2 184
 '@S9S_MB_2U_LIB.S9S_MB_2U(SCH_1):PAGE83_I179@PURE_QUANTA.SCONN288_ADR50017P087CC(CHIPS)':
 'VSS79': CDS_PINID='VSS79';
NODE_NAME     J2 186
 '@S9S_MB_2U_LIB.S9S_MB_2U(SCH_1):PAGE83_I179@PURE_QUANTA.SCONN288_ADR50017P087CC(CHIPS)':
 'VSS80': CDS_PINID='VSS80';
NODE_NAME     J2 188
 '@S9S_MB_2U_LIB.S9S_MB_2U(SCH_1):PAGE83_I179@PURE_QUANTA.SCONN288_ADR50017P087CC(CHIPS)':
 'VSS81': CDS_PINID='VSS81';
NODE_NAME     J2 191
 '@S9S_MB_2U_LIB.S9S_MB_2U(SCH_1):PAGE83_I179@PURE_QUANTA.SCONN288_ADR50017P087CC(CHIPS)':
 'VSS82': CDS_PINID='VSS82';
NODE_NAME     J2 193
 '@S9S_MB_2U_LIB.S9S_MB_2U(SCH_1):PAGE83_I179@PURE_QUANTA.SCONN288_ADR50017P087CC(CHIPS)':
 'VSS83': CDS_PINID='VSS83';
NODE_NAME     J2 195
 '@S9S_MB_2U_LIB.S9S_MB_2U(SCH_1):PAGE83_I179@PURE_QUANTA.SCONN288_ADR50017P087CC(CHIPS)':
 'VSS84': CDS_PINID='VSS84';
NODE_NAME     J2 197
 '@S9S_MB_2U_LIB.S9S_MB_2U(SCH_1):PAGE83_I179@PURE_QUANTA.SCONN288_ADR50017P087CC(CHIPS)':
 'VSS85': CDS_PINID='VSS85';
NODE_NAME     J2 199
 '@S9S_MB_2U_LIB.S9S_MB_2U(SCH_1):PAGE83_I179@PURE_QUANTA.SCONN288_ADR50017P087CC(CHIPS)':
 'VSS86': CDS_PINID='VSS86';
NODE_NAME     J2 202
 '@S9S_MB_2U_LIB.S9S_MB_2U(SCH_1):PAGE83_I179@PURE_QUANTA.SCONN288_ADR50017P087CC(CHIPS)':
 'VSS87': CDS_PINID='VSS87';
NODE_NAME     J2 204
 '@S9S_MB_2U_LIB.S9S_MB_2U(SCH_1):PAGE83_I179@PURE_QUANTA.SCONN288_ADR50017P087CC(CHIPS)':
 'VSS88': CDS_PINID='VSS88';
NODE_NAME     J2 206
 '@S9S_MB_2U_LIB.S9S_MB_2U(SCH_1):PAGE83_I179@PURE_QUANTA.SCONN288_ADR50017P087CC(CHIPS)':
 'VSS89': CDS_PINID='VSS89';
NODE_NAME     J2 208
 '@S9S_MB_2U_LIB.S9S_MB_2U(SCH_1):PAGE83_I179@PURE_QUANTA.SCONN288_ADR50017P087CC(CHIPS)':
 'VSS90': CDS_PINID='VSS90';
NODE_NAME     J2 210
 '@S9S_MB_2U_LIB.S9S_MB_2U(SCH_1):PAGE83_I179@PURE_QUANTA.SCONN288_ADR50017P087CC(CHIPS)':
 'VSS91': CDS_PINID='VSS91';
NODE_NAME     J2 212
 '@S9S_MB_2U_LIB.S9S_MB_2U(SCH_1):PAGE83_I179@PURE_QUANTA.SCONN288_ADR50017P087CC(CHIPS)':
 'VSS92': CDS_PINID='VSS92';
NODE_NAME     J2 214
 '@S9S_MB_2U_LIB.S9S_MB_2U(SCH_1):PAGE83_I179@PURE_QUANTA.SCONN288_ADR50017P087CC(CHIPS)':
 'VSS93': CDS_PINID='VSS93';
NODE_NAME     J2 216
 '@S9S_MB_2U_LIB.S9S_MB_2U(SCH_1):PAGE83_I179@PURE_QUANTA.SCONN288_ADR50017P087CC(CHIPS)':
 'VSS94': CDS_PINID='VSS94';
NODE_NAME     J2 219
 '@S9S_MB_2U_LIB.S9S_MB_2U(SCH_1):PAGE83_I179@PURE_QUANTA.SCONN288_ADR50017P087CC(CHIPS)':
 'VSS95': CDS_PINID='VSS95';
NODE_NAME     J2 222
 '@S9S_MB_2U_LIB.S9S_MB_2U(SCH_1):PAGE83_I179@PURE_QUANTA.SCONN288_ADR50017P087CC(CHIPS)':
 'VSS96': CDS_PINID='VSS96';
NODE_NAME     J2 224
 '@S9S_MB_2U_LIB.S9S_MB_2U(SCH_1):PAGE83_I179@PURE_QUANTA.SCONN288_ADR50017P087CC(CHIPS)':
 'VSS97': CDS_PINID='VSS97';
NODE_NAME     J2 226
 '@S9S_MB_2U_LIB.S9S_MB_2U(SCH_1):PAGE83_I179@PURE_QUANTA.SCONN288_ADR50017P087CC(CHIPS)':
 'VSS98': CDS_PINID='VSS98';
NODE_NAME     J2 228
 '@S9S_MB_2U_LIB.S9S_MB_2U(SCH_1):PAGE83_I179@PURE_QUANTA.SCONN288_ADR50017P087CC(CHIPS)':
 'VSS99': CDS_PINID='VSS99';
NODE_NAME     J2 230
 '@S9S_MB_2U_LIB.S9S_MB_2U(SCH_1):PAGE83_I179@PURE_QUANTA.SCONN288_ADR50017P087CC(CHIPS)':
 'VSS100': CDS_PINID='VSS100';
NODE_NAME     J2 233
 '@S9S_MB_2U_LIB.S9S_MB_2U(SCH_1):PAGE83_I179@PURE_QUANTA.SCONN288_ADR50017P087CC(CHIPS)':
 'VSS101': CDS_PINID='VSS101';
NODE_NAME     J2 235
 '@S9S_MB_2U_LIB.S9S_MB_2U(SCH_1):PAGE83_I179@PURE_QUANTA.SCONN288_ADR50017P087CC(CHIPS)':
 'VSS102': CDS_PINID='VSS102';
NODE_NAME     J2 237
 '@S9S_MB_2U_LIB.S9S_MB_2U(SCH_1):PAGE83_I179@PURE_QUANTA.SCONN288_ADR50017P087CC(CHIPS)':
 'VSS103': CDS_PINID='VSS103';
NODE_NAME     J2 240
 '@S9S_MB_2U_LIB.S9S_MB_2U(SCH_1):PAGE83_I179@PURE_QUANTA.SCONN288_ADR50017P087CC(CHIPS)':
 'VSS104': CDS_PINID='VSS104';
NODE_NAME     J2 242
 '@S9S_MB_2U_LIB.S9S_MB_2U(SCH_1):PAGE83_I179@PURE_QUANTA.SCONN288_ADR50017P087CC(CHIPS)':
 'VSS105': CDS_PINID='VSS105';
NODE_NAME     J2 244
 '@S9S_MB_2U_LIB.S9S_MB_2U(SCH_1):PAGE83_I179@PURE_QUANTA.SCONN288_ADR50017P087CC(CHIPS)':
 'VSS106': CDS_PINID='VSS106';
NODE_NAME     J2 246
 '@S9S_MB_2U_LIB.S9S_MB_2U(SCH_1):PAGE83_I179@PURE_QUANTA.SCONN288_ADR50017P087CC(CHIPS)':
 'VSS107': CDS_PINID='VSS107';
NODE_NAME     J2 248
 '@S9S_MB_2U_LIB.S9S_MB_2U(SCH_1):PAGE83_I179@PURE_QUANTA.SCONN288_ADR50017P087CC(CHIPS)':
 'VSS108': CDS_PINID='VSS108';
NODE_NAME     J2 251
 '@S9S_MB_2U_LIB.S9S_MB_2U(SCH_1):PAGE83_I179@PURE_QUANTA.SCONN288_ADR50017P087CC(CHIPS)':
 'VSS109': CDS_PINID='VSS109';
NODE_NAME     J2 253
 '@S9S_MB_2U_LIB.S9S_MB_2U(SCH_1):PAGE83_I179@PURE_QUANTA.SCONN288_ADR50017P087CC(CHIPS)':
 'VSS110': CDS_PINID='VSS110';
NODE_NAME     J2 255
 '@S9S_MB_2U_LIB.S9S_MB_2U(SCH_1):PAGE83_I179@PURE_QUANTA.SCONN288_ADR50017P087CC(CHIPS)':
 'VSS111': CDS_PINID='VSS111';
NODE_NAME     J2 257
 '@S9S_MB_2U_LIB.S9S_MB_2U(SCH_1):PAGE83_I179@PURE_QUANTA.SCONN288_ADR50017P087CC(CHIPS)':
 'VSS112': CDS_PINID='VSS112';
NODE_NAME     J2 259
 '@S9S_MB_2U_LIB.S9S_MB_2U(SCH_1):PAGE83_I179@PURE_QUANTA.SCONN288_ADR50017P087CC(CHIPS)':
 'VSS113': CDS_PINID='VSS113';
NODE_NAME     J2 262
 '@S9S_MB_2U_LIB.S9S_MB_2U(SCH_1):PAGE83_I179@PURE_QUANTA.SCONN288_ADR50017P087CC(CHIPS)':
 'VSS114': CDS_PINID='VSS114';
NODE_NAME     J2 264
 '@S9S_MB_2U_LIB.S9S_MB_2U(SCH_1):PAGE83_I179@PURE_QUANTA.SCONN288_ADR50017P087CC(CHIPS)':
 'VSS115': CDS_PINID='VSS115';
NODE_NAME     J2 266
 '@S9S_MB_2U_LIB.S9S_MB_2U(SCH_1):PAGE83_I179@PURE_QUANTA.SCONN288_ADR50017P087CC(CHIPS)':
 'VSS116': CDS_PINID='VSS116';
NODE_NAME     J2 268
 '@S9S_MB_2U_LIB.S9S_MB_2U(SCH_1):PAGE83_I179@PURE_QUANTA.SCONN288_ADR50017P087CC(CHIPS)':
 'VSS117': CDS_PINID='VSS117';
NODE_NAME     J2 270
 '@S9S_MB_2U_LIB.S9S_MB_2U(SCH_1):PAGE83_I179@PURE_QUANTA.SCONN288_ADR50017P087CC(CHIPS)':
 'VSS118': CDS_PINID='VSS118';
NODE_NAME     J2 273
 '@S9S_MB_2U_LIB.S9S_MB_2U(SCH_1):PAGE83_I179@PURE_QUANTA.SCONN288_ADR50017P087CC(CHIPS)':
 'VSS119': CDS_PINID='VSS119';
NODE_NAME     J2 275
 '@S9S_MB_2U_LIB.S9S_MB_2U(SCH_1):PAGE83_I179@PURE_QUANTA.SCONN288_ADR50017P087CC(CHIPS)':
 'VSS120': CDS_PINID='VSS120';
NODE_NAME     J2 277
 '@S9S_MB_2U_LIB.S9S_MB_2U(SCH_1):PAGE83_I179@PURE_QUANTA.SCONN288_ADR50017P087CC(CHIPS)':
 'VSS121': CDS_PINID='VSS121';
NODE_NAME     J2 279
 '@S9S_MB_2U_LIB.S9S_MB_2U(SCH_1):PAGE83_I179@PURE_QUANTA.SCONN288_ADR50017P087CC(CHIPS)':
 'VSS122': CDS_PINID='VSS122';
NODE_NAME     J2 281
 '@S9S_MB_2U_LIB.S9S_MB_2U(SCH_1):PAGE83_I179@PURE_QUANTA.SCONN288_ADR50017P087CC(CHIPS)':
 'VSS123': CDS_PINID='VSS123';
NODE_NAME     J2 284
 '@S9S_MB_2U_LIB.S9S_MB_2U(SCH_1):PAGE83_I179@PURE_QUANTA.SCONN288_ADR50017P087CC(CHIPS)':
 'VSS124': CDS_PINID='VSS124';
NODE_NAME     J2 286
 '@S9S_MB_2U_LIB.S9S_MB_2U(SCH_1):PAGE83_I179@PURE_QUANTA.SCONN288_ADR50017P087CC(CHIPS)':
 'VSS125': CDS_PINID='VSS125';
NODE_NAME     J2 288
 '@S9S_MB_2U_LIB.S9S_MB_2U(SCH_1):PAGE83_I179@PURE_QUANTA.SCONN288_ADR50017P087CC(CHIPS)':
 'VSS126': CDS_PINID='VSS126';
NODE_NAME     R28 2
 '@S9S_MB_2U_LIB.S9S_MB_2U(SCH_1):PAGE84_I10@PURE_QUANTA.Q_RES(CHIPS)':
 'B': CDS_PINID='B';
NODE_NAME     C8 2
 '@S9S_MB_2U_LIB.S9S_MB_2U(SCH_1):PAGE84_I121@PURE_QUANTA.Q_CAP(CHIPS)':
 'B': CDS_PINID='B';
NODE_NAME     C9 2
 '@S9S_MB_2U_LIB.S9S_MB_2U(SCH_1):PAGE84_I122@PURE_QUANTA.Q_CAP(CHIPS)':
 'B': CDS_PINID='B';
NODE_NAME     C10 2
 '@S9S_MB_2U_LIB.S9S_MB_2U(SCH_1):PAGE84_I144@PURE_QUANTA.Q_CAP(CHIPS)':
 'B': CDS_PINID='B';
NODE_NAME     J3 G1
 '@S9S_MB_2U_LIB.S9S_MB_2U(SCH_1):PAGE84_I178@PURE_QUANTA.SCONN288_ADR50017P130CC(CHIPS)':
 'G1': CDS_PINID='G1';
NODE_NAME     J3 G2
 '@S9S_MB_2U_LIB.S9S_MB_2U(SCH_1):PAGE84_I178@PURE_QUANTA.SCONN288_ADR50017P130CC(CHIPS)':
 'G2': CDS_PINID='G2';
NODE_NAME     J3 G3
 '@S9S_MB_2U_LIB.S9S_MB_2U(SCH_1):PAGE84_I178@PURE_QUANTA.SCONN288_ADR50017P130CC(CHIPS)':
 'G3': CDS_PINID='G3';
NODE_NAME     J3 6
 '@S9S_MB_2U_LIB.S9S_MB_2U(SCH_1):PAGE84_I178@PURE_QUANTA.SCONN288_ADR50017P130CC(CHIPS)':
 'VSS0': CDS_PINID='VSS0';
NODE_NAME     J3 8
 '@S9S_MB_2U_LIB.S9S_MB_2U(SCH_1):PAGE84_I178@PURE_QUANTA.SCONN288_ADR50017P130CC(CHIPS)':
 'VSS1': CDS_PINID='VSS1';
NODE_NAME     J3 10
 '@S9S_MB_2U_LIB.S9S_MB_2U(SCH_1):PAGE84_I178@PURE_QUANTA.SCONN288_ADR50017P130CC(CHIPS)':
 'VSS2': CDS_PINID='VSS2';
NODE_NAME     J3 13
 '@S9S_MB_2U_LIB.S9S_MB_2U(SCH_1):PAGE84_I178@PURE_QUANTA.SCONN288_ADR50017P130CC(CHIPS)':
 'VSS3': CDS_PINID='VSS3';
NODE_NAME     J3 15
 '@S9S_MB_2U_LIB.S9S_MB_2U(SCH_1):PAGE84_I178@PURE_QUANTA.SCONN288_ADR50017P130CC(CHIPS)':
 'VSS4': CDS_PINID='VSS4';
NODE_NAME     J3 17
 '@S9S_MB_2U_LIB.S9S_MB_2U(SCH_1):PAGE84_I178@PURE_QUANTA.SCONN288_ADR50017P130CC(CHIPS)':
 'VSS5': CDS_PINID='VSS5';
NODE_NAME     J3 19
 '@S9S_MB_2U_LIB.S9S_MB_2U(SCH_1):PAGE84_I178@PURE_QUANTA.SCONN288_ADR50017P130CC(CHIPS)':
 'VSS6': CDS_PINID='VSS6';
NODE_NAME     J3 21
 '@S9S_MB_2U_LIB.S9S_MB_2U(SCH_1):PAGE84_I178@PURE_QUANTA.SCONN288_ADR50017P130CC(CHIPS)':
 'VSS7': CDS_PINID='VSS7';
NODE_NAME     J3 24
 '@S9S_MB_2U_LIB.S9S_MB_2U(SCH_1):PAGE84_I178@PURE_QUANTA.SCONN288_ADR50017P130CC(CHIPS)':
 'VSS8': CDS_PINID='VSS8';
NODE_NAME     J3 26
 '@S9S_MB_2U_LIB.S9S_MB_2U(SCH_1):PAGE84_I178@PURE_QUANTA.SCONN288_ADR50017P130CC(CHIPS)':
 'VSS9': CDS_PINID='VSS9';
NODE_NAME     J3 28
 '@S9S_MB_2U_LIB.S9S_MB_2U(SCH_1):PAGE84_I178@PURE_QUANTA.SCONN288_ADR50017P130CC(CHIPS)':
 'VSS10': CDS_PINID='VSS10';
NODE_NAME     J3 30
 '@S9S_MB_2U_LIB.S9S_MB_2U(SCH_1):PAGE84_I178@PURE_QUANTA.SCONN288_ADR50017P130CC(CHIPS)':
 'VSS11': CDS_PINID='VSS11';
NODE_NAME     J3 32
 '@S9S_MB_2U_LIB.S9S_MB_2U(SCH_1):PAGE84_I178@PURE_QUANTA.SCONN288_ADR50017P130CC(CHIPS)':
 'VSS12': CDS_PINID='VSS12';
NODE_NAME     J3 35
 '@S9S_MB_2U_LIB.S9S_MB_2U(SCH_1):PAGE84_I178@PURE_QUANTA.SCONN288_ADR50017P130CC(CHIPS)':
 'VSS13': CDS_PINID='VSS13';
NODE_NAME     J3 37
 '@S9S_MB_2U_LIB.S9S_MB_2U(SCH_1):PAGE84_I178@PURE_QUANTA.SCONN288_ADR50017P130CC(CHIPS)':
 'VSS14': CDS_PINID='VSS14';
NODE_NAME     J3 39
 '@S9S_MB_2U_LIB.S9S_MB_2U(SCH_1):PAGE84_I178@PURE_QUANTA.SCONN288_ADR50017P130CC(CHIPS)':
 'VSS15': CDS_PINID='VSS15';
NODE_NAME     J3 41
 '@S9S_MB_2U_LIB.S9S_MB_2U(SCH_1):PAGE84_I178@PURE_QUANTA.SCONN288_ADR50017P130CC(CHIPS)':
 'VSS16': CDS_PINID='VSS16';
NODE_NAME     J3 43
 '@S9S_MB_2U_LIB.S9S_MB_2U(SCH_1):PAGE84_I178@PURE_QUANTA.SCONN288_ADR50017P130CC(CHIPS)':
 'VSS17': CDS_PINID='VSS17';
NODE_NAME     J3 46
 '@S9S_MB_2U_LIB.S9S_MB_2U(SCH_1):PAGE84_I178@PURE_QUANTA.SCONN288_ADR50017P130CC(CHIPS)':
 'VSS18': CDS_PINID='VSS18';
NODE_NAME     J3 48
 '@S9S_MB_2U_LIB.S9S_MB_2U(SCH_1):PAGE84_I178@PURE_QUANTA.SCONN288_ADR50017P130CC(CHIPS)':
 'VSS19': CDS_PINID='VSS19';
NODE_NAME     J3 50
 '@S9S_MB_2U_LIB.S9S_MB_2U(SCH_1):PAGE84_I178@PURE_QUANTA.SCONN288_ADR50017P130CC(CHIPS)':
 'VSS20': CDS_PINID='VSS20';
NODE_NAME     J3 52
 '@S9S_MB_2U_LIB.S9S_MB_2U(SCH_1):PAGE84_I178@PURE_QUANTA.SCONN288_ADR50017P130CC(CHIPS)':
 'VSS21': CDS_PINID='VSS21';
NODE_NAME     J3 54
 '@S9S_MB_2U_LIB.S9S_MB_2U(SCH_1):PAGE84_I178@PURE_QUANTA.SCONN288_ADR50017P130CC(CHIPS)':
 'VSS22': CDS_PINID='VSS22';
NODE_NAME     J3 57
 '@S9S_MB_2U_LIB.S9S_MB_2U(SCH_1):PAGE84_I178@PURE_QUANTA.SCONN288_ADR50017P130CC(CHIPS)':
 'VSS23': CDS_PINID='VSS23';
NODE_NAME     J3 59
 '@S9S_MB_2U_LIB.S9S_MB_2U(SCH_1):PAGE84_I178@PURE_QUANTA.SCONN288_ADR50017P130CC(CHIPS)':
 'VSS24': CDS_PINID='VSS24';
NODE_NAME     J3 61
 '@S9S_MB_2U_LIB.S9S_MB_2U(SCH_1):PAGE84_I178@PURE_QUANTA.SCONN288_ADR50017P130CC(CHIPS)':
 'VSS25': CDS_PINID='VSS25';
NODE_NAME     J3 63
 '@S9S_MB_2U_LIB.S9S_MB_2U(SCH_1):PAGE84_I178@PURE_QUANTA.SCONN288_ADR50017P130CC(CHIPS)':
 'VSS26': CDS_PINID='VSS26';
NODE_NAME     J3 65
 '@S9S_MB_2U_LIB.S9S_MB_2U(SCH_1):PAGE84_I178@PURE_QUANTA.SCONN288_ADR50017P130CC(CHIPS)':
 'VSS27': CDS_PINID='VSS27';
NODE_NAME     J3 67
 '@S9S_MB_2U_LIB.S9S_MB_2U(SCH_1):PAGE84_I178@PURE_QUANTA.SCONN288_ADR50017P130CC(CHIPS)':
 'VSS28': CDS_PINID='VSS28';
NODE_NAME     J3 69
 '@S9S_MB_2U_LIB.S9S_MB_2U(SCH_1):PAGE84_I178@PURE_QUANTA.SCONN288_ADR50017P130CC(CHIPS)':
 'VSS29': CDS_PINID='VSS29';
NODE_NAME     J3 71
 '@S9S_MB_2U_LIB.S9S_MB_2U(SCH_1):PAGE84_I178@PURE_QUANTA.SCONN288_ADR50017P130CC(CHIPS)':
 'VSS30': CDS_PINID='VSS30';
NODE_NAME     J3 73
 '@S9S_MB_2U_LIB.S9S_MB_2U(SCH_1):PAGE84_I178@PURE_QUANTA.SCONN288_ADR50017P130CC(CHIPS)':
 'VSS31': CDS_PINID='VSS31';
NODE_NAME     J3 75
 '@S9S_MB_2U_LIB.S9S_MB_2U(SCH_1):PAGE84_I178@PURE_QUANTA.SCONN288_ADR50017P130CC(CHIPS)':
 'VSS32': CDS_PINID='VSS32';
NODE_NAME     J3 77
 '@S9S_MB_2U_LIB.S9S_MB_2U(SCH_1):PAGE84_I178@PURE_QUANTA.SCONN288_ADR50017P130CC(CHIPS)':
 'VSS33': CDS_PINID='VSS33';
NODE_NAME     J3 79
 '@S9S_MB_2U_LIB.S9S_MB_2U(SCH_1):PAGE84_I178@PURE_QUANTA.SCONN288_ADR50017P130CC(CHIPS)':
 'VSS34': CDS_PINID='VSS34';
NODE_NAME     J3 81
 '@S9S_MB_2U_LIB.S9S_MB_2U(SCH_1):PAGE84_I178@PURE_QUANTA.SCONN288_ADR50017P130CC(CHIPS)':
 'VSS35': CDS_PINID='VSS35';
NODE_NAME     J3 83
 '@S9S_MB_2U_LIB.S9S_MB_2U(SCH_1):PAGE84_I178@PURE_QUANTA.SCONN288_ADR50017P130CC(CHIPS)':
 'VSS36': CDS_PINID='VSS36';
NODE_NAME     J3 85
 '@S9S_MB_2U_LIB.S9S_MB_2U(SCH_1):PAGE84_I178@PURE_QUANTA.SCONN288_ADR50017P130CC(CHIPS)':
 'VSS37': CDS_PINID='VSS37';
NODE_NAME     J3 88
 '@S9S_MB_2U_LIB.S9S_MB_2U(SCH_1):PAGE84_I178@PURE_QUANTA.SCONN288_ADR50017P130CC(CHIPS)':
 'VSS38': CDS_PINID='VSS38';
NODE_NAME     J3 90
 '@S9S_MB_2U_LIB.S9S_MB_2U(SCH_1):PAGE84_I178@PURE_QUANTA.SCONN288_ADR50017P130CC(CHIPS)':
 'VSS39': CDS_PINID='VSS39';
NODE_NAME     J3 92
 '@S9S_MB_2U_LIB.S9S_MB_2U(SCH_1):PAGE84_I178@PURE_QUANTA.SCONN288_ADR50017P130CC(CHIPS)':
 'VSS40': CDS_PINID='VSS40';
NODE_NAME     J3 95
 '@S9S_MB_2U_LIB.S9S_MB_2U(SCH_1):PAGE84_I178@PURE_QUANTA.SCONN288_ADR50017P130CC(CHIPS)':
 'VSS41': CDS_PINID='VSS41';
NODE_NAME     J3 97
 '@S9S_MB_2U_LIB.S9S_MB_2U(SCH_1):PAGE84_I178@PURE_QUANTA.SCONN288_ADR50017P130CC(CHIPS)':
 'VSS42': CDS_PINID='VSS42';
NODE_NAME     J3 99
 '@S9S_MB_2U_LIB.S9S_MB_2U(SCH_1):PAGE84_I178@PURE_QUANTA.SCONN288_ADR50017P130CC(CHIPS)':
 'VSS43': CDS_PINID='VSS43';
NODE_NAME     J3 101
 '@S9S_MB_2U_LIB.S9S_MB_2U(SCH_1):PAGE84_I178@PURE_QUANTA.SCONN288_ADR50017P130CC(CHIPS)':
 'VSS44': CDS_PINID='VSS44';
NODE_NAME     J3 103
 '@S9S_MB_2U_LIB.S9S_MB_2U(SCH_1):PAGE84_I178@PURE_QUANTA.SCONN288_ADR50017P130CC(CHIPS)':
 'VSS45': CDS_PINID='VSS45';
NODE_NAME     J3 106
 '@S9S_MB_2U_LIB.S9S_MB_2U(SCH_1):PAGE84_I178@PURE_QUANTA.SCONN288_ADR50017P130CC(CHIPS)':
 'VSS46': CDS_PINID='VSS46';
NODE_NAME     J3 108
 '@S9S_MB_2U_LIB.S9S_MB_2U(SCH_1):PAGE84_I178@PURE_QUANTA.SCONN288_ADR50017P130CC(CHIPS)':
 'VSS47': CDS_PINID='VSS47';
NODE_NAME     J3 110
 '@S9S_MB_2U_LIB.S9S_MB_2U(SCH_1):PAGE84_I178@PURE_QUANTA.SCONN288_ADR50017P130CC(CHIPS)':
 'VSS48': CDS_PINID='VSS48';
NODE_NAME     J3 112
 '@S9S_MB_2U_LIB.S9S_MB_2U(SCH_1):PAGE84_I178@PURE_QUANTA.SCONN288_ADR50017P130CC(CHIPS)':
 'VSS49': CDS_PINID='VSS49';
NODE_NAME     J3 114
 '@S9S_MB_2U_LIB.S9S_MB_2U(SCH_1):PAGE84_I178@PURE_QUANTA.SCONN288_ADR50017P130CC(CHIPS)':
 'VSS50': CDS_PINID='VSS50';
NODE_NAME     J3 117
 '@S9S_MB_2U_LIB.S9S_MB_2U(SCH_1):PAGE84_I178@PURE_QUANTA.SCONN288_ADR50017P130CC(CHIPS)':
 'VSS51': CDS_PINID='VSS51';
NODE_NAME     J3 119
 '@S9S_MB_2U_LIB.S9S_MB_2U(SCH_1):PAGE84_I178@PURE_QUANTA.SCONN288_ADR50017P130CC(CHIPS)':
 'VSS52': CDS_PINID='VSS52';
NODE_NAME     J3 121
 '@S9S_MB_2U_LIB.S9S_MB_2U(SCH_1):PAGE84_I178@PURE_QUANTA.SCONN288_ADR50017P130CC(CHIPS)':
 'VSS53': CDS_PINID='VSS53';
NODE_NAME     J3 123
 '@S9S_MB_2U_LIB.S9S_MB_2U(SCH_1):PAGE84_I178@PURE_QUANTA.SCONN288_ADR50017P130CC(CHIPS)':
 'VSS54': CDS_PINID='VSS54';
NODE_NAME     J3 125
 '@S9S_MB_2U_LIB.S9S_MB_2U(SCH_1):PAGE84_I178@PURE_QUANTA.SCONN288_ADR50017P130CC(CHIPS)':
 'VSS55': CDS_PINID='VSS55';
NODE_NAME     J3 128
 '@S9S_MB_2U_LIB.S9S_MB_2U(SCH_1):PAGE84_I178@PURE_QUANTA.SCONN288_ADR50017P130CC(CHIPS)':
 'VSS56': CDS_PINID='VSS56';
NODE_NAME     J3 130
 '@S9S_MB_2U_LIB.S9S_MB_2U(SCH_1):PAGE84_I178@PURE_QUANTA.SCONN288_ADR50017P130CC(CHIPS)':
 'VSS57': CDS_PINID='VSS57';
NODE_NAME     J3 132
 '@S9S_MB_2U_LIB.S9S_MB_2U(SCH_1):PAGE84_I178@PURE_QUANTA.SCONN288_ADR50017P130CC(CHIPS)':
 'VSS58': CDS_PINID='VSS58';
NODE_NAME     J3 134
 '@S9S_MB_2U_LIB.S9S_MB_2U(SCH_1):PAGE84_I178@PURE_QUANTA.SCONN288_ADR50017P130CC(CHIPS)':
 'VSS59': CDS_PINID='VSS59';
NODE_NAME     J3 136
 '@S9S_MB_2U_LIB.S9S_MB_2U(SCH_1):PAGE84_I178@PURE_QUANTA.SCONN288_ADR50017P130CC(CHIPS)':
 'VSS60': CDS_PINID='VSS60';
NODE_NAME     J3 139
 '@S9S_MB_2U_LIB.S9S_MB_2U(SCH_1):PAGE84_I178@PURE_QUANTA.SCONN288_ADR50017P130CC(CHIPS)':
 'VSS61': CDS_PINID='VSS61';
NODE_NAME     J3 141
 '@S9S_MB_2U_LIB.S9S_MB_2U(SCH_1):PAGE84_I178@PURE_QUANTA.SCONN288_ADR50017P130CC(CHIPS)':
 'VSS62': CDS_PINID='VSS62';
NODE_NAME     J3 143
 '@S9S_MB_2U_LIB.S9S_MB_2U(SCH_1):PAGE84_I178@PURE_QUANTA.SCONN288_ADR50017P130CC(CHIPS)':
 'VSS63': CDS_PINID='VSS63';
NODE_NAME     J3 151
 '@S9S_MB_2U_LIB.S9S_MB_2U(SCH_1):PAGE84_I178@PURE_QUANTA.SCONN288_ADR50017P130CC(CHIPS)':
 'VSS64': CDS_PINID='VSS64';
NODE_NAME     J3 153
 '@S9S_MB_2U_LIB.S9S_MB_2U(SCH_1):PAGE84_I178@PURE_QUANTA.SCONN288_ADR50017P130CC(CHIPS)':
 'VSS65': CDS_PINID='VSS65';
NODE_NAME     J3 155
 '@S9S_MB_2U_LIB.S9S_MB_2U(SCH_1):PAGE84_I178@PURE_QUANTA.SCONN288_ADR50017P130CC(CHIPS)':
 'VSS66': CDS_PINID='VSS66';
NODE_NAME     J3 158
 '@S9S_MB_2U_LIB.S9S_MB_2U(SCH_1):PAGE84_I178@PURE_QUANTA.SCONN288_ADR50017P130CC(CHIPS)':
 'VSS67': CDS_PINID='VSS67';
NODE_NAME     J3 160
 '@S9S_MB_2U_LIB.S9S_MB_2U(SCH_1):PAGE84_I178@PURE_QUANTA.SCONN288_ADR50017P130CC(CHIPS)':
 'VSS68': CDS_PINID='VSS68';
NODE_NAME     J3 162
 '@S9S_MB_2U_LIB.S9S_MB_2U(SCH_1):PAGE84_I178@PURE_QUANTA.SCONN288_ADR50017P130CC(CHIPS)':
 'VSS69': CDS_PINID='VSS69';
NODE_NAME     J3 164
 '@S9S_MB_2U_LIB.S9S_MB_2U(SCH_1):PAGE84_I178@PURE_QUANTA.SCONN288_ADR50017P130CC(CHIPS)':
 'VSS70': CDS_PINID='VSS70';
NODE_NAME     J3 166
 '@S9S_MB_2U_LIB.S9S_MB_2U(SCH_1):PAGE84_I178@PURE_QUANTA.SCONN288_ADR50017P130CC(CHIPS)':
 'VSS71': CDS_PINID='VSS71';
NODE_NAME     J3 169
 '@S9S_MB_2U_LIB.S9S_MB_2U(SCH_1):PAGE84_I178@PURE_QUANTA.SCONN288_ADR50017P130CC(CHIPS)':
 'VSS72': CDS_PINID='VSS72';
NODE_NAME     J3 171
 '@S9S_MB_2U_LIB.S9S_MB_2U(SCH_1):PAGE84_I178@PURE_QUANTA.SCONN288_ADR50017P130CC(CHIPS)':
 'VSS73': CDS_PINID='VSS73';
NODE_NAME     J3 173
 '@S9S_MB_2U_LIB.S9S_MB_2U(SCH_1):PAGE84_I178@PURE_QUANTA.SCONN288_ADR50017P130CC(CHIPS)':
 'VSS74': CDS_PINID='VSS74';
NODE_NAME     J3 175
 '@S9S_MB_2U_LIB.S9S_MB_2U(SCH_1):PAGE84_I178@PURE_QUANTA.SCONN288_ADR50017P130CC(CHIPS)':
 'VSS75': CDS_PINID='VSS75';
NODE_NAME     J3 177
 '@S9S_MB_2U_LIB.S9S_MB_2U(SCH_1):PAGE84_I178@PURE_QUANTA.SCONN288_ADR50017P130CC(CHIPS)':
 'VSS76': CDS_PINID='VSS76';
NODE_NAME     J3 180
 '@S9S_MB_2U_LIB.S9S_MB_2U(SCH_1):PAGE84_I178@PURE_QUANTA.SCONN288_ADR50017P130CC(CHIPS)':
 'VSS77': CDS_PINID='VSS77';
NODE_NAME     J3 182
 '@S9S_MB_2U_LIB.S9S_MB_2U(SCH_1):PAGE84_I178@PURE_QUANTA.SCONN288_ADR50017P130CC(CHIPS)':
 'VSS78': CDS_PINID='VSS78';
NODE_NAME     J3 184
 '@S9S_MB_2U_LIB.S9S_MB_2U(SCH_1):PAGE84_I178@PURE_QUANTA.SCONN288_ADR50017P130CC(CHIPS)':
 'VSS79': CDS_PINID='VSS79';
NODE_NAME     J3 186
 '@S9S_MB_2U_LIB.S9S_MB_2U(SCH_1):PAGE84_I178@PURE_QUANTA.SCONN288_ADR50017P130CC(CHIPS)':
 'VSS80': CDS_PINID='VSS80';
NODE_NAME     J3 188
 '@S9S_MB_2U_LIB.S9S_MB_2U(SCH_1):PAGE84_I178@PURE_QUANTA.SCONN288_ADR50017P130CC(CHIPS)':
 'VSS81': CDS_PINID='VSS81';
NODE_NAME     J3 191
 '@S9S_MB_2U_LIB.S9S_MB_2U(SCH_1):PAGE84_I178@PURE_QUANTA.SCONN288_ADR50017P130CC(CHIPS)':
 'VSS82': CDS_PINID='VSS82';
NODE_NAME     J3 193
 '@S9S_MB_2U_LIB.S9S_MB_2U(SCH_1):PAGE84_I178@PURE_QUANTA.SCONN288_ADR50017P130CC(CHIPS)':
 'VSS83': CDS_PINID='VSS83';
NODE_NAME     J3 195
 '@S9S_MB_2U_LIB.S9S_MB_2U(SCH_1):PAGE84_I178@PURE_QUANTA.SCONN288_ADR50017P130CC(CHIPS)':
 'VSS84': CDS_PINID='VSS84';
NODE_NAME     J3 197
 '@S9S_MB_2U_LIB.S9S_MB_2U(SCH_1):PAGE84_I178@PURE_QUANTA.SCONN288_ADR50017P130CC(CHIPS)':
 'VSS85': CDS_PINID='VSS85';
NODE_NAME     J3 199
 '@S9S_MB_2U_LIB.S9S_MB_2U(SCH_1):PAGE84_I178@PURE_QUANTA.SCONN288_ADR50017P130CC(CHIPS)':
 'VSS86': CDS_PINID='VSS86';
NODE_NAME     J3 202
 '@S9S_MB_2U_LIB.S9S_MB_2U(SCH_1):PAGE84_I178@PURE_QUANTA.SCONN288_ADR50017P130CC(CHIPS)':
 'VSS87': CDS_PINID='VSS87';
NODE_NAME     J3 204
 '@S9S_MB_2U_LIB.S9S_MB_2U(SCH_1):PAGE84_I178@PURE_QUANTA.SCONN288_ADR50017P130CC(CHIPS)':
 'VSS88': CDS_PINID='VSS88';
NODE_NAME     J3 206
 '@S9S_MB_2U_LIB.S9S_MB_2U(SCH_1):PAGE84_I178@PURE_QUANTA.SCONN288_ADR50017P130CC(CHIPS)':
 'VSS89': CDS_PINID='VSS89';
NODE_NAME     J3 208
 '@S9S_MB_2U_LIB.S9S_MB_2U(SCH_1):PAGE84_I178@PURE_QUANTA.SCONN288_ADR50017P130CC(CHIPS)':
 'VSS90': CDS_PINID='VSS90';
NODE_NAME     J3 210
 '@S9S_MB_2U_LIB.S9S_MB_2U(SCH_1):PAGE84_I178@PURE_QUANTA.SCONN288_ADR50017P130CC(CHIPS)':
 'VSS91': CDS_PINID='VSS91';
NODE_NAME     J3 212
 '@S9S_MB_2U_LIB.S9S_MB_2U(SCH_1):PAGE84_I178@PURE_QUANTA.SCONN288_ADR50017P130CC(CHIPS)':
 'VSS92': CDS_PINID='VSS92';
NODE_NAME     J3 214
 '@S9S_MB_2U_LIB.S9S_MB_2U(SCH_1):PAGE84_I178@PURE_QUANTA.SCONN288_ADR50017P130CC(CHIPS)':
 'VSS93': CDS_PINID='VSS93';
NODE_NAME     J3 216
 '@S9S_MB_2U_LIB.S9S_MB_2U(SCH_1):PAGE84_I178@PURE_QUANTA.SCONN288_ADR50017P130CC(CHIPS)':
 'VSS94': CDS_PINID='VSS94';
NODE_NAME     J3 219
 '@S9S_MB_2U_LIB.S9S_MB_2U(SCH_1):PAGE84_I178@PURE_QUANTA.SCONN288_ADR50017P130CC(CHIPS)':
 'VSS95': CDS_PINID='VSS95';
NODE_NAME     J3 222
 '@S9S_MB_2U_LIB.S9S_MB_2U(SCH_1):PAGE84_I178@PURE_QUANTA.SCONN288_ADR50017P130CC(CHIPS)':
 'VSS96': CDS_PINID='VSS96';
NODE_NAME     J3 224
 '@S9S_MB_2U_LIB.S9S_MB_2U(SCH_1):PAGE84_I178@PURE_QUANTA.SCONN288_ADR50017P130CC(CHIPS)':
 'VSS97': CDS_PINID='VSS97';
NODE_NAME     J3 226
 '@S9S_MB_2U_LIB.S9S_MB_2U(SCH_1):PAGE84_I178@PURE_QUANTA.SCONN288_ADR50017P130CC(CHIPS)':
 'VSS98': CDS_PINID='VSS98';
NODE_NAME     J3 228
 '@S9S_MB_2U_LIB.S9S_MB_2U(SCH_1):PAGE84_I178@PURE_QUANTA.SCONN288_ADR50017P130CC(CHIPS)':
 'VSS99': CDS_PINID='VSS99';
NODE_NAME     J3 230
 '@S9S_MB_2U_LIB.S9S_MB_2U(SCH_1):PAGE84_I178@PURE_QUANTA.SCONN288_ADR50017P130CC(CHIPS)':
 'VSS100': CDS_PINID='VSS100';
NODE_NAME     J3 233
 '@S9S_MB_2U_LIB.S9S_MB_2U(SCH_1):PAGE84_I178@PURE_QUANTA.SCONN288_ADR50017P130CC(CHIPS)':
 'VSS101': CDS_PINID='VSS101';
NODE_NAME     J3 235
 '@S9S_MB_2U_LIB.S9S_MB_2U(SCH_1):PAGE84_I178@PURE_QUANTA.SCONN288_ADR50017P130CC(CHIPS)':
 'VSS102': CDS_PINID='VSS102';
NODE_NAME     J3 237
 '@S9S_MB_2U_LIB.S9S_MB_2U(SCH_1):PAGE84_I178@PURE_QUANTA.SCONN288_ADR50017P130CC(CHIPS)':
 'VSS103': CDS_PINID='VSS103';
NODE_NAME     J3 240
 '@S9S_MB_2U_LIB.S9S_MB_2U(SCH_1):PAGE84_I178@PURE_QUANTA.SCONN288_ADR50017P130CC(CHIPS)':
 'VSS104': CDS_PINID='VSS104';
NODE_NAME     J3 242
 '@S9S_MB_2U_LIB.S9S_MB_2U(SCH_1):PAGE84_I178@PURE_QUANTA.SCONN288_ADR50017P130CC(CHIPS)':
 'VSS105': CDS_PINID='VSS105';
NODE_NAME     J3 244
 '@S9S_MB_2U_LIB.S9S_MB_2U(SCH_1):PAGE84_I178@PURE_QUANTA.SCONN288_ADR50017P130CC(CHIPS)':
 'VSS106': CDS_PINID='VSS106';
NODE_NAME     J3 246
 '@S9S_MB_2U_LIB.S9S_MB_2U(SCH_1):PAGE84_I178@PURE_QUANTA.SCONN288_ADR50017P130CC(CHIPS)':
 'VSS107': CDS_PINID='VSS107';
NODE_NAME     J3 248
 '@S9S_MB_2U_LIB.S9S_MB_2U(SCH_1):PAGE84_I178@PURE_QUANTA.SCONN288_ADR50017P130CC(CHIPS)':
 'VSS108': CDS_PINID='VSS108';
NODE_NAME     J3 251
 '@S9S_MB_2U_LIB.S9S_MB_2U(SCH_1):PAGE84_I178@PURE_QUANTA.SCONN288_ADR50017P130CC(CHIPS)':
 'VSS109': CDS_PINID='VSS109';
NODE_NAME     J3 253
 '@S9S_MB_2U_LIB.S9S_MB_2U(SCH_1):PAGE84_I178@PURE_QUANTA.SCONN288_ADR50017P130CC(CHIPS)':
 'VSS110': CDS_PINID='VSS110';
NODE_NAME     J3 255
 '@S9S_MB_2U_LIB.S9S_MB_2U(SCH_1):PAGE84_I178@PURE_QUANTA.SCONN288_ADR50017P130CC(CHIPS)':
 'VSS111': CDS_PINID='VSS111';
NODE_NAME     J3 257
 '@S9S_MB_2U_LIB.S9S_MB_2U(SCH_1):PAGE84_I178@PURE_QUANTA.SCONN288_ADR50017P130CC(CHIPS)':
 'VSS112': CDS_PINID='VSS112';
NODE_NAME     J3 259
 '@S9S_MB_2U_LIB.S9S_MB_2U(SCH_1):PAGE84_I178@PURE_QUANTA.SCONN288_ADR50017P130CC(CHIPS)':
 'VSS113': CDS_PINID='VSS113';
NODE_NAME     J3 262
 '@S9S_MB_2U_LIB.S9S_MB_2U(SCH_1):PAGE84_I178@PURE_QUANTA.SCONN288_ADR50017P130CC(CHIPS)':
 'VSS114': CDS_PINID='VSS114';
NODE_NAME     J3 264
 '@S9S_MB_2U_LIB.S9S_MB_2U(SCH_1):PAGE84_I178@PURE_QUANTA.SCONN288_ADR50017P130CC(CHIPS)':
 'VSS115': CDS_PINID='VSS115';
NODE_NAME     J3 266
 '@S9S_MB_2U_LIB.S9S_MB_2U(SCH_1):PAGE84_I178@PURE_QUANTA.SCONN288_ADR50017P130CC(CHIPS)':
 'VSS116': CDS_PINID='VSS116';
NODE_NAME     J3 268
 '@S9S_MB_2U_LIB.S9S_MB_2U(SCH_1):PAGE84_I178@PURE_QUANTA.SCONN288_ADR50017P130CC(CHIPS)':
 'VSS117': CDS_PINID='VSS117';
NODE_NAME     J3 270
 '@S9S_MB_2U_LIB.S9S_MB_2U(SCH_1):PAGE84_I178@PURE_QUANTA.SCONN288_ADR50017P130CC(CHIPS)':
 'VSS118': CDS_PINID='VSS118';
NODE_NAME     J3 273
 '@S9S_MB_2U_LIB.S9S_MB_2U(SCH_1):PAGE84_I178@PURE_QUANTA.SCONN288_ADR50017P130CC(CHIPS)':
 'VSS119': CDS_PINID='VSS119';
NODE_NAME     J3 275
 '@S9S_MB_2U_LIB.S9S_MB_2U(SCH_1):PAGE84_I178@PURE_QUANTA.SCONN288_ADR50017P130CC(CHIPS)':
 'VSS120': CDS_PINID='VSS120';
NODE_NAME     J3 277
 '@S9S_MB_2U_LIB.S9S_MB_2U(SCH_1):PAGE84_I178@PURE_QUANTA.SCONN288_ADR50017P130CC(CHIPS)':
 'VSS121': CDS_PINID='VSS121';
NODE_NAME     J3 279
 '@S9S_MB_2U_LIB.S9S_MB_2U(SCH_1):PAGE84_I178@PURE_QUANTA.SCONN288_ADR50017P130CC(CHIPS)':
 'VSS122': CDS_PINID='VSS122';
NODE_NAME     J3 281
 '@S9S_MB_2U_LIB.S9S_MB_2U(SCH_1):PAGE84_I178@PURE_QUANTA.SCONN288_ADR50017P130CC(CHIPS)':
 'VSS123': CDS_PINID='VSS123';
NODE_NAME     J3 284
 '@S9S_MB_2U_LIB.S9S_MB_2U(SCH_1):PAGE84_I178@PURE_QUANTA.SCONN288_ADR50017P130CC(CHIPS)':
 'VSS124': CDS_PINID='VSS124';
NODE_NAME     J3 286
 '@S9S_MB_2U_LIB.S9S_MB_2U(SCH_1):PAGE84_I178@PURE_QUANTA.SCONN288_ADR50017P130CC(CHIPS)':
 'VSS125': CDS_PINID='VSS125';
NODE_NAME     J3 288
 '@S9S_MB_2U_LIB.S9S_MB_2U(SCH_1):PAGE84_I178@PURE_QUANTA.SCONN288_ADR50017P130CC(CHIPS)':
 'VSS126': CDS_PINID='VSS126';
NODE_NAME     R29 2
 '@S9S_MB_2U_LIB.S9S_MB_2U(SCH_1):PAGE85_I1@PURE_QUANTA.Q_RES(CHIPS)':
 'B': CDS_PINID='B';
NODE_NAME     C11 2
 '@S9S_MB_2U_LIB.S9S_MB_2U(SCH_1):PAGE85_I121@PURE_QUANTA.Q_CAP(CHIPS)':
 'B': CDS_PINID='B';
NODE_NAME     C12 2
 '@S9S_MB_2U_LIB.S9S_MB_2U(SCH_1):PAGE85_I125@PURE_QUANTA.Q_CAP(CHIPS)':
 'B': CDS_PINID='B';
NODE_NAME     C13 2
 '@S9S_MB_2U_LIB.S9S_MB_2U(SCH_1):PAGE85_I127@PURE_QUANTA.Q_CAP(CHIPS)':
 'B': CDS_PINID='B';
NODE_NAME     J4 G1
 '@S9S_MB_2U_LIB.S9S_MB_2U(SCH_1):PAGE85_I174@PURE_QUANTA.SCONN288_ADR50017P087CC(CHIPS)':
 'G1': CDS_PINID='G1';
NODE_NAME     J4 G2
 '@S9S_MB_2U_LIB.S9S_MB_2U(SCH_1):PAGE85_I174@PURE_QUANTA.SCONN288_ADR50017P087CC(CHIPS)':
 'G2': CDS_PINID='G2';
NODE_NAME     J4 G3
 '@S9S_MB_2U_LIB.S9S_MB_2U(SCH_1):PAGE85_I174@PURE_QUANTA.SCONN288_ADR50017P087CC(CHIPS)':
 'G3': CDS_PINID='G3';
NODE_NAME     J4 6
 '@S9S_MB_2U_LIB.S9S_MB_2U(SCH_1):PAGE85_I174@PURE_QUANTA.SCONN288_ADR50017P087CC(CHIPS)':
 'VSS0': CDS_PINID='VSS0';
NODE_NAME     J4 8
 '@S9S_MB_2U_LIB.S9S_MB_2U(SCH_1):PAGE85_I174@PURE_QUANTA.SCONN288_ADR50017P087CC(CHIPS)':
 'VSS1': CDS_PINID='VSS1';
NODE_NAME     J4 10
 '@S9S_MB_2U_LIB.S9S_MB_2U(SCH_1):PAGE85_I174@PURE_QUANTA.SCONN288_ADR50017P087CC(CHIPS)':
 'VSS2': CDS_PINID='VSS2';
NODE_NAME     J4 13
 '@S9S_MB_2U_LIB.S9S_MB_2U(SCH_1):PAGE85_I174@PURE_QUANTA.SCONN288_ADR50017P087CC(CHIPS)':
 'VSS3': CDS_PINID='VSS3';
NODE_NAME     J4 15
 '@S9S_MB_2U_LIB.S9S_MB_2U(SCH_1):PAGE85_I174@PURE_QUANTA.SCONN288_ADR50017P087CC(CHIPS)':
 'VSS4': CDS_PINID='VSS4';
NODE_NAME     J4 17
 '@S9S_MB_2U_LIB.S9S_MB_2U(SCH_1):PAGE85_I174@PURE_QUANTA.SCONN288_ADR50017P087CC(CHIPS)':
 'VSS5': CDS_PINID='VSS5';
NODE_NAME     J4 19
 '@S9S_MB_2U_LIB.S9S_MB_2U(SCH_1):PAGE85_I174@PURE_QUANTA.SCONN288_ADR50017P087CC(CHIPS)':
 'VSS6': CDS_PINID='VSS6';
NODE_NAME     J4 21
 '@S9S_MB_2U_LIB.S9S_MB_2U(SCH_1):PAGE85_I174@PURE_QUANTA.SCONN288_ADR50017P087CC(CHIPS)':
 'VSS7': CDS_PINID='VSS7';
NODE_NAME     J4 24
 '@S9S_MB_2U_LIB.S9S_MB_2U(SCH_1):PAGE85_I174@PURE_QUANTA.SCONN288_ADR50017P087CC(CHIPS)':
 'VSS8': CDS_PINID='VSS8';
NODE_NAME     J4 26
 '@S9S_MB_2U_LIB.S9S_MB_2U(SCH_1):PAGE85_I174@PURE_QUANTA.SCONN288_ADR50017P087CC(CHIPS)':
 'VSS9': CDS_PINID='VSS9';
NODE_NAME     J4 28
 '@S9S_MB_2U_LIB.S9S_MB_2U(SCH_1):PAGE85_I174@PURE_QUANTA.SCONN288_ADR50017P087CC(CHIPS)':
 'VSS10': CDS_PINID='VSS10';
NODE_NAME     J4 30
 '@S9S_MB_2U_LIB.S9S_MB_2U(SCH_1):PAGE85_I174@PURE_QUANTA.SCONN288_ADR50017P087CC(CHIPS)':
 'VSS11': CDS_PINID='VSS11';
NODE_NAME     J4 32
 '@S9S_MB_2U_LIB.S9S_MB_2U(SCH_1):PAGE85_I174@PURE_QUANTA.SCONN288_ADR50017P087CC(CHIPS)':
 'VSS12': CDS_PINID='VSS12';
NODE_NAME     J4 35
 '@S9S_MB_2U_LIB.S9S_MB_2U(SCH_1):PAGE85_I174@PURE_QUANTA.SCONN288_ADR50017P087CC(CHIPS)':
 'VSS13': CDS_PINID='VSS13';
NODE_NAME     J4 37
 '@S9S_MB_2U_LIB.S9S_MB_2U(SCH_1):PAGE85_I174@PURE_QUANTA.SCONN288_ADR50017P087CC(CHIPS)':
 'VSS14': CDS_PINID='VSS14';
NODE_NAME     J4 39
 '@S9S_MB_2U_LIB.S9S_MB_2U(SCH_1):PAGE85_I174@PURE_QUANTA.SCONN288_ADR50017P087CC(CHIPS)':
 'VSS15': CDS_PINID='VSS15';
NODE_NAME     J4 41
 '@S9S_MB_2U_LIB.S9S_MB_2U(SCH_1):PAGE85_I174@PURE_QUANTA.SCONN288_ADR50017P087CC(CHIPS)':
 'VSS16': CDS_PINID='VSS16';
NODE_NAME     J4 43
 '@S9S_MB_2U_LIB.S9S_MB_2U(SCH_1):PAGE85_I174@PURE_QUANTA.SCONN288_ADR50017P087CC(CHIPS)':
 'VSS17': CDS_PINID='VSS17';
NODE_NAME     J4 46
 '@S9S_MB_2U_LIB.S9S_MB_2U(SCH_1):PAGE85_I174@PURE_QUANTA.SCONN288_ADR50017P087CC(CHIPS)':
 'VSS18': CDS_PINID='VSS18';
NODE_NAME     J4 48
 '@S9S_MB_2U_LIB.S9S_MB_2U(SCH_1):PAGE85_I174@PURE_QUANTA.SCONN288_ADR50017P087CC(CHIPS)':
 'VSS19': CDS_PINID='VSS19';
NODE_NAME     J4 50
 '@S9S_MB_2U_LIB.S9S_MB_2U(SCH_1):PAGE85_I174@PURE_QUANTA.SCONN288_ADR50017P087CC(CHIPS)':
 'VSS20': CDS_PINID='VSS20';
NODE_NAME     J4 52
 '@S9S_MB_2U_LIB.S9S_MB_2U(SCH_1):PAGE85_I174@PURE_QUANTA.SCONN288_ADR50017P087CC(CHIPS)':
 'VSS21': CDS_PINID='VSS21';
NODE_NAME     J4 54
 '@S9S_MB_2U_LIB.S9S_MB_2U(SCH_1):PAGE85_I174@PURE_QUANTA.SCONN288_ADR50017P087CC(CHIPS)':
 'VSS22': CDS_PINID='VSS22';
NODE_NAME     J4 57
 '@S9S_MB_2U_LIB.S9S_MB_2U(SCH_1):PAGE85_I174@PURE_QUANTA.SCONN288_ADR50017P087CC(CHIPS)':
 'VSS23': CDS_PINID='VSS23';
NODE_NAME     J4 59
 '@S9S_MB_2U_LIB.S9S_MB_2U(SCH_1):PAGE85_I174@PURE_QUANTA.SCONN288_ADR50017P087CC(CHIPS)':
 'VSS24': CDS_PINID='VSS24';
NODE_NAME     J4 61
 '@S9S_MB_2U_LIB.S9S_MB_2U(SCH_1):PAGE85_I174@PURE_QUANTA.SCONN288_ADR50017P087CC(CHIPS)':
 'VSS25': CDS_PINID='VSS25';
NODE_NAME     J4 63
 '@S9S_MB_2U_LIB.S9S_MB_2U(SCH_1):PAGE85_I174@PURE_QUANTA.SCONN288_ADR50017P087CC(CHIPS)':
 'VSS26': CDS_PINID='VSS26';
NODE_NAME     J4 65
 '@S9S_MB_2U_LIB.S9S_MB_2U(SCH_1):PAGE85_I174@PURE_QUANTA.SCONN288_ADR50017P087CC(CHIPS)':
 'VSS27': CDS_PINID='VSS27';
NODE_NAME     J4 67
 '@S9S_MB_2U_LIB.S9S_MB_2U(SCH_1):PAGE85_I174@PURE_QUANTA.SCONN288_ADR50017P087CC(CHIPS)':
 'VSS28': CDS_PINID='VSS28';
NODE_NAME     J4 69
 '@S9S_MB_2U_LIB.S9S_MB_2U(SCH_1):PAGE85_I174@PURE_QUANTA.SCONN288_ADR50017P087CC(CHIPS)':
 'VSS29': CDS_PINID='VSS29';
NODE_NAME     J4 71
 '@S9S_MB_2U_LIB.S9S_MB_2U(SCH_1):PAGE85_I174@PURE_QUANTA.SCONN288_ADR50017P087CC(CHIPS)':
 'VSS30': CDS_PINID='VSS30';
NODE_NAME     J4 73
 '@S9S_MB_2U_LIB.S9S_MB_2U(SCH_1):PAGE85_I174@PURE_QUANTA.SCONN288_ADR50017P087CC(CHIPS)':
 'VSS31': CDS_PINID='VSS31';
NODE_NAME     J4 75
 '@S9S_MB_2U_LIB.S9S_MB_2U(SCH_1):PAGE85_I174@PURE_QUANTA.SCONN288_ADR50017P087CC(CHIPS)':
 'VSS32': CDS_PINID='VSS32';
NODE_NAME     J4 77
 '@S9S_MB_2U_LIB.S9S_MB_2U(SCH_1):PAGE85_I174@PURE_QUANTA.SCONN288_ADR50017P087CC(CHIPS)':
 'VSS33': CDS_PINID='VSS33';
NODE_NAME     J4 79
 '@S9S_MB_2U_LIB.S9S_MB_2U(SCH_1):PAGE85_I174@PURE_QUANTA.SCONN288_ADR50017P087CC(CHIPS)':
 'VSS34': CDS_PINID='VSS34';
NODE_NAME     J4 81
 '@S9S_MB_2U_LIB.S9S_MB_2U(SCH_1):PAGE85_I174@PURE_QUANTA.SCONN288_ADR50017P087CC(CHIPS)':
 'VSS35': CDS_PINID='VSS35';
NODE_NAME     J4 83
 '@S9S_MB_2U_LIB.S9S_MB_2U(SCH_1):PAGE85_I174@PURE_QUANTA.SCONN288_ADR50017P087CC(CHIPS)':
 'VSS36': CDS_PINID='VSS36';
NODE_NAME     J4 85
 '@S9S_MB_2U_LIB.S9S_MB_2U(SCH_1):PAGE85_I174@PURE_QUANTA.SCONN288_ADR50017P087CC(CHIPS)':
 'VSS37': CDS_PINID='VSS37';
NODE_NAME     J4 88
 '@S9S_MB_2U_LIB.S9S_MB_2U(SCH_1):PAGE85_I174@PURE_QUANTA.SCONN288_ADR50017P087CC(CHIPS)':
 'VSS38': CDS_PINID='VSS38';
NODE_NAME     J4 90
 '@S9S_MB_2U_LIB.S9S_MB_2U(SCH_1):PAGE85_I174@PURE_QUANTA.SCONN288_ADR50017P087CC(CHIPS)':
 'VSS39': CDS_PINID='VSS39';
NODE_NAME     J4 92
 '@S9S_MB_2U_LIB.S9S_MB_2U(SCH_1):PAGE85_I174@PURE_QUANTA.SCONN288_ADR50017P087CC(CHIPS)':
 'VSS40': CDS_PINID='VSS40';
NODE_NAME     J4 95
 '@S9S_MB_2U_LIB.S9S_MB_2U(SCH_1):PAGE85_I174@PURE_QUANTA.SCONN288_ADR50017P087CC(CHIPS)':
 'VSS41': CDS_PINID='VSS41';
NODE_NAME     J4 97
 '@S9S_MB_2U_LIB.S9S_MB_2U(SCH_1):PAGE85_I174@PURE_QUANTA.SCONN288_ADR50017P087CC(CHIPS)':
 'VSS42': CDS_PINID='VSS42';
NODE_NAME     J4 99
 '@S9S_MB_2U_LIB.S9S_MB_2U(SCH_1):PAGE85_I174@PURE_QUANTA.SCONN288_ADR50017P087CC(CHIPS)':
 'VSS43': CDS_PINID='VSS43';
NODE_NAME     J4 101
 '@S9S_MB_2U_LIB.S9S_MB_2U(SCH_1):PAGE85_I174@PURE_QUANTA.SCONN288_ADR50017P087CC(CHIPS)':
 'VSS44': CDS_PINID='VSS44';
NODE_NAME     J4 103
 '@S9S_MB_2U_LIB.S9S_MB_2U(SCH_1):PAGE85_I174@PURE_QUANTA.SCONN288_ADR50017P087CC(CHIPS)':
 'VSS45': CDS_PINID='VSS45';
NODE_NAME     J4 106
 '@S9S_MB_2U_LIB.S9S_MB_2U(SCH_1):PAGE85_I174@PURE_QUANTA.SCONN288_ADR50017P087CC(CHIPS)':
 'VSS46': CDS_PINID='VSS46';
NODE_NAME     J4 108
 '@S9S_MB_2U_LIB.S9S_MB_2U(SCH_1):PAGE85_I174@PURE_QUANTA.SCONN288_ADR50017P087CC(CHIPS)':
 'VSS47': CDS_PINID='VSS47';
NODE_NAME     J4 110
 '@S9S_MB_2U_LIB.S9S_MB_2U(SCH_1):PAGE85_I174@PURE_QUANTA.SCONN288_ADR50017P087CC(CHIPS)':
 'VSS48': CDS_PINID='VSS48';
NODE_NAME     J4 112
 '@S9S_MB_2U_LIB.S9S_MB_2U(SCH_1):PAGE85_I174@PURE_QUANTA.SCONN288_ADR50017P087CC(CHIPS)':
 'VSS49': CDS_PINID='VSS49';
NODE_NAME     J4 114
 '@S9S_MB_2U_LIB.S9S_MB_2U(SCH_1):PAGE85_I174@PURE_QUANTA.SCONN288_ADR50017P087CC(CHIPS)':
 'VSS50': CDS_PINID='VSS50';
NODE_NAME     J4 117
 '@S9S_MB_2U_LIB.S9S_MB_2U(SCH_1):PAGE85_I174@PURE_QUANTA.SCONN288_ADR50017P087CC(CHIPS)':
 'VSS51': CDS_PINID='VSS51';
NODE_NAME     J4 119
 '@S9S_MB_2U_LIB.S9S_MB_2U(SCH_1):PAGE85_I174@PURE_QUANTA.SCONN288_ADR50017P087CC(CHIPS)':
 'VSS52': CDS_PINID='VSS52';
NODE_NAME     J4 121
 '@S9S_MB_2U_LIB.S9S_MB_2U(SCH_1):PAGE85_I174@PURE_QUANTA.SCONN288_ADR50017P087CC(CHIPS)':
 'VSS53': CDS_PINID='VSS53';
NODE_NAME     J4 123
 '@S9S_MB_2U_LIB.S9S_MB_2U(SCH_1):PAGE85_I174@PURE_QUANTA.SCONN288_ADR50017P087CC(CHIPS)':
 'VSS54': CDS_PINID='VSS54';
NODE_NAME     J4 125
 '@S9S_MB_2U_LIB.S9S_MB_2U(SCH_1):PAGE85_I174@PURE_QUANTA.SCONN288_ADR50017P087CC(CHIPS)':
 'VSS55': CDS_PINID='VSS55';
NODE_NAME     J4 128
 '@S9S_MB_2U_LIB.S9S_MB_2U(SCH_1):PAGE85_I174@PURE_QUANTA.SCONN288_ADR50017P087CC(CHIPS)':
 'VSS56': CDS_PINID='VSS56';
NODE_NAME     J4 130
 '@S9S_MB_2U_LIB.S9S_MB_2U(SCH_1):PAGE85_I174@PURE_QUANTA.SCONN288_ADR50017P087CC(CHIPS)':
 'VSS57': CDS_PINID='VSS57';
NODE_NAME     J4 132
 '@S9S_MB_2U_LIB.S9S_MB_2U(SCH_1):PAGE85_I174@PURE_QUANTA.SCONN288_ADR50017P087CC(CHIPS)':
 'VSS58': CDS_PINID='VSS58';
NODE_NAME     J4 134
 '@S9S_MB_2U_LIB.S9S_MB_2U(SCH_1):PAGE85_I174@PURE_QUANTA.SCONN288_ADR50017P087CC(CHIPS)':
 'VSS59': CDS_PINID='VSS59';
NODE_NAME     J4 136
 '@S9S_MB_2U_LIB.S9S_MB_2U(SCH_1):PAGE85_I174@PURE_QUANTA.SCONN288_ADR50017P087CC(CHIPS)':
 'VSS60': CDS_PINID='VSS60';
NODE_NAME     J4 139
 '@S9S_MB_2U_LIB.S9S_MB_2U(SCH_1):PAGE85_I174@PURE_QUANTA.SCONN288_ADR50017P087CC(CHIPS)':
 'VSS61': CDS_PINID='VSS61';
NODE_NAME     J4 141
 '@S9S_MB_2U_LIB.S9S_MB_2U(SCH_1):PAGE85_I174@PURE_QUANTA.SCONN288_ADR50017P087CC(CHIPS)':
 'VSS62': CDS_PINID='VSS62';
NODE_NAME     J4 143
 '@S9S_MB_2U_LIB.S9S_MB_2U(SCH_1):PAGE85_I174@PURE_QUANTA.SCONN288_ADR50017P087CC(CHIPS)':
 'VSS63': CDS_PINID='VSS63';
NODE_NAME     J4 151
 '@S9S_MB_2U_LIB.S9S_MB_2U(SCH_1):PAGE85_I174@PURE_QUANTA.SCONN288_ADR50017P087CC(CHIPS)':
 'VSS64': CDS_PINID='VSS64';
NODE_NAME     J4 153
 '@S9S_MB_2U_LIB.S9S_MB_2U(SCH_1):PAGE85_I174@PURE_QUANTA.SCONN288_ADR50017P087CC(CHIPS)':
 'VSS65': CDS_PINID='VSS65';
NODE_NAME     J4 155
 '@S9S_MB_2U_LIB.S9S_MB_2U(SCH_1):PAGE85_I174@PURE_QUANTA.SCONN288_ADR50017P087CC(CHIPS)':
 'VSS66': CDS_PINID='VSS66';
NODE_NAME     J4 158
 '@S9S_MB_2U_LIB.S9S_MB_2U(SCH_1):PAGE85_I174@PURE_QUANTA.SCONN288_ADR50017P087CC(CHIPS)':
 'VSS67': CDS_PINID='VSS67';
NODE_NAME     J4 160
 '@S9S_MB_2U_LIB.S9S_MB_2U(SCH_1):PAGE85_I174@PURE_QUANTA.SCONN288_ADR50017P087CC(CHIPS)':
 'VSS68': CDS_PINID='VSS68';
NODE_NAME     J4 162
 '@S9S_MB_2U_LIB.S9S_MB_2U(SCH_1):PAGE85_I174@PURE_QUANTA.SCONN288_ADR50017P087CC(CHIPS)':
 'VSS69': CDS_PINID='VSS69';
NODE_NAME     J4 164
 '@S9S_MB_2U_LIB.S9S_MB_2U(SCH_1):PAGE85_I174@PURE_QUANTA.SCONN288_ADR50017P087CC(CHIPS)':
 'VSS70': CDS_PINID='VSS70';
NODE_NAME     J4 166
 '@S9S_MB_2U_LIB.S9S_MB_2U(SCH_1):PAGE85_I174@PURE_QUANTA.SCONN288_ADR50017P087CC(CHIPS)':
 'VSS71': CDS_PINID='VSS71';
NODE_NAME     J4 169
 '@S9S_MB_2U_LIB.S9S_MB_2U(SCH_1):PAGE85_I174@PURE_QUANTA.SCONN288_ADR50017P087CC(CHIPS)':
 'VSS72': CDS_PINID='VSS72';
NODE_NAME     J4 171
 '@S9S_MB_2U_LIB.S9S_MB_2U(SCH_1):PAGE85_I174@PURE_QUANTA.SCONN288_ADR50017P087CC(CHIPS)':
 'VSS73': CDS_PINID='VSS73';
NODE_NAME     J4 173
 '@S9S_MB_2U_LIB.S9S_MB_2U(SCH_1):PAGE85_I174@PURE_QUANTA.SCONN288_ADR50017P087CC(CHIPS)':
 'VSS74': CDS_PINID='VSS74';
NODE_NAME     J4 175
 '@S9S_MB_2U_LIB.S9S_MB_2U(SCH_1):PAGE85_I174@PURE_QUANTA.SCONN288_ADR50017P087CC(CHIPS)':
 'VSS75': CDS_PINID='VSS75';
NODE_NAME     J4 177
 '@S9S_MB_2U_LIB.S9S_MB_2U(SCH_1):PAGE85_I174@PURE_QUANTA.SCONN288_ADR50017P087CC(CHIPS)':
 'VSS76': CDS_PINID='VSS76';
NODE_NAME     J4 180
 '@S9S_MB_2U_LIB.S9S_MB_2U(SCH_1):PAGE85_I174@PURE_QUANTA.SCONN288_ADR50017P087CC(CHIPS)':
 'VSS77': CDS_PINID='VSS77';
NODE_NAME     J4 182
 '@S9S_MB_2U_LIB.S9S_MB_2U(SCH_1):PAGE85_I174@PURE_QUANTA.SCONN288_ADR50017P087CC(CHIPS)':
 'VSS78': CDS_PINID='VSS78';
NODE_NAME     J4 184
 '@S9S_MB_2U_LIB.S9S_MB_2U(SCH_1):PAGE85_I174@PURE_QUANTA.SCONN288_ADR50017P087CC(CHIPS)':
 'VSS79': CDS_PINID='VSS79';
NODE_NAME     J4 186
 '@S9S_MB_2U_LIB.S9S_MB_2U(SCH_1):PAGE85_I174@PURE_QUANTA.SCONN288_ADR50017P087CC(CHIPS)':
 'VSS80': CDS_PINID='VSS80';
NODE_NAME     J4 188
 '@S9S_MB_2U_LIB.S9S_MB_2U(SCH_1):PAGE85_I174@PURE_QUANTA.SCONN288_ADR50017P087CC(CHIPS)':
 'VSS81': CDS_PINID='VSS81';
NODE_NAME     J4 191
 '@S9S_MB_2U_LIB.S9S_MB_2U(SCH_1):PAGE85_I174@PURE_QUANTA.SCONN288_ADR50017P087CC(CHIPS)':
 'VSS82': CDS_PINID='VSS82';
NODE_NAME     J4 193
 '@S9S_MB_2U_LIB.S9S_MB_2U(SCH_1):PAGE85_I174@PURE_QUANTA.SCONN288_ADR50017P087CC(CHIPS)':
 'VSS83': CDS_PINID='VSS83';
NODE_NAME     J4 195
 '@S9S_MB_2U_LIB.S9S_MB_2U(SCH_1):PAGE85_I174@PURE_QUANTA.SCONN288_ADR50017P087CC(CHIPS)':
 'VSS84': CDS_PINID='VSS84';
NODE_NAME     J4 197
 '@S9S_MB_2U_LIB.S9S_MB_2U(SCH_1):PAGE85_I174@PURE_QUANTA.SCONN288_ADR50017P087CC(CHIPS)':
 'VSS85': CDS_PINID='VSS85';
NODE_NAME     J4 199
 '@S9S_MB_2U_LIB.S9S_MB_2U(SCH_1):PAGE85_I174@PURE_QUANTA.SCONN288_ADR50017P087CC(CHIPS)':
 'VSS86': CDS_PINID='VSS86';
NODE_NAME     J4 202
 '@S9S_MB_2U_LIB.S9S_MB_2U(SCH_1):PAGE85_I174@PURE_QUANTA.SCONN288_ADR50017P087CC(CHIPS)':
 'VSS87': CDS_PINID='VSS87';
NODE_NAME     J4 204
 '@S9S_MB_2U_LIB.S9S_MB_2U(SCH_1):PAGE85_I174@PURE_QUANTA.SCONN288_ADR50017P087CC(CHIPS)':
 'VSS88': CDS_PINID='VSS88';
NODE_NAME     J4 206
 '@S9S_MB_2U_LIB.S9S_MB_2U(SCH_1):PAGE85_I174@PURE_QUANTA.SCONN288_ADR50017P087CC(CHIPS)':
 'VSS89': CDS_PINID='VSS89';
NODE_NAME     J4 208
 '@S9S_MB_2U_LIB.S9S_MB_2U(SCH_1):PAGE85_I174@PURE_QUANTA.SCONN288_ADR50017P087CC(CHIPS)':
 'VSS90': CDS_PINID='VSS90';
NODE_NAME     J4 210
 '@S9S_MB_2U_LIB.S9S_MB_2U(SCH_1):PAGE85_I174@PURE_QUANTA.SCONN288_ADR50017P087CC(CHIPS)':
 'VSS91': CDS_PINID='VSS91';
NODE_NAME     J4 212
 '@S9S_MB_2U_LIB.S9S_MB_2U(SCH_1):PAGE85_I174@PURE_QUANTA.SCONN288_ADR50017P087CC(CHIPS)':
 'VSS92': CDS_PINID='VSS92';
NODE_NAME     J4 214
 '@S9S_MB_2U_LIB.S9S_MB_2U(SCH_1):PAGE85_I174@PURE_QUANTA.SCONN288_ADR50017P087CC(CHIPS)':
 'VSS93': CDS_PINID='VSS93';
NODE_NAME     J4 216
 '@S9S_MB_2U_LIB.S9S_MB_2U(SCH_1):PAGE85_I174@PURE_QUANTA.SCONN288_ADR50017P087CC(CHIPS)':
 'VSS94': CDS_PINID='VSS94';
NODE_NAME     J4 219
 '@S9S_MB_2U_LIB.S9S_MB_2U(SCH_1):PAGE85_I174@PURE_QUANTA.SCONN288_ADR50017P087CC(CHIPS)':
 'VSS95': CDS_PINID='VSS95';
NODE_NAME     J4 222
 '@S9S_MB_2U_LIB.S9S_MB_2U(SCH_1):PAGE85_I174@PURE_QUANTA.SCONN288_ADR50017P087CC(CHIPS)':
 'VSS96': CDS_PINID='VSS96';
NODE_NAME     J4 224
 '@S9S_MB_2U_LIB.S9S_MB_2U(SCH_1):PAGE85_I174@PURE_QUANTA.SCONN288_ADR50017P087CC(CHIPS)':
 'VSS97': CDS_PINID='VSS97';
NODE_NAME     J4 226
 '@S9S_MB_2U_LIB.S9S_MB_2U(SCH_1):PAGE85_I174@PURE_QUANTA.SCONN288_ADR50017P087CC(CHIPS)':
 'VSS98': CDS_PINID='VSS98';
NODE_NAME     J4 228
 '@S9S_MB_2U_LIB.S9S_MB_2U(SCH_1):PAGE85_I174@PURE_QUANTA.SCONN288_ADR50017P087CC(CHIPS)':
 'VSS99': CDS_PINID='VSS99';
NODE_NAME     J4 230
 '@S9S_MB_2U_LIB.S9S_MB_2U(SCH_1):PAGE85_I174@PURE_QUANTA.SCONN288_ADR50017P087CC(CHIPS)':
 'VSS100': CDS_PINID='VSS100';
NODE_NAME     J4 233
 '@S9S_MB_2U_LIB.S9S_MB_2U(SCH_1):PAGE85_I174@PURE_QUANTA.SCONN288_ADR50017P087CC(CHIPS)':
 'VSS101': CDS_PINID='VSS101';
NODE_NAME     J4 235
 '@S9S_MB_2U_LIB.S9S_MB_2U(SCH_1):PAGE85_I174@PURE_QUANTA.SCONN288_ADR50017P087CC(CHIPS)':
 'VSS102': CDS_PINID='VSS102';
NODE_NAME     J4 237
 '@S9S_MB_2U_LIB.S9S_MB_2U(SCH_1):PAGE85_I174@PURE_QUANTA.SCONN288_ADR50017P087CC(CHIPS)':
 'VSS103': CDS_PINID='VSS103';
NODE_NAME     J4 240
 '@S9S_MB_2U_LIB.S9S_MB_2U(SCH_1):PAGE85_I174@PURE_QUANTA.SCONN288_ADR50017P087CC(CHIPS)':
 'VSS104': CDS_PINID='VSS104';
NODE_NAME     J4 242
 '@S9S_MB_2U_LIB.S9S_MB_2U(SCH_1):PAGE85_I174@PURE_QUANTA.SCONN288_ADR50017P087CC(CHIPS)':
 'VSS105': CDS_PINID='VSS105';
NODE_NAME     J4 244
 '@S9S_MB_2U_LIB.S9S_MB_2U(SCH_1):PAGE85_I174@PURE_QUANTA.SCONN288_ADR50017P087CC(CHIPS)':
 'VSS106': CDS_PINID='VSS106';
NODE_NAME     J4 246
 '@S9S_MB_2U_LIB.S9S_MB_2U(SCH_1):PAGE85_I174@PURE_QUANTA.SCONN288_ADR50017P087CC(CHIPS)':
 'VSS107': CDS_PINID='VSS107';
NODE_NAME     J4 248
 '@S9S_MB_2U_LIB.S9S_MB_2U(SCH_1):PAGE85_I174@PURE_QUANTA.SCONN288_ADR50017P087CC(CHIPS)':
 'VSS108': CDS_PINID='VSS108';
NODE_NAME     J4 251
 '@S9S_MB_2U_LIB.S9S_MB_2U(SCH_1):PAGE85_I174@PURE_QUANTA.SCONN288_ADR50017P087CC(CHIPS)':
 'VSS109': CDS_PINID='VSS109';
NODE_NAME     J4 253
 '@S9S_MB_2U_LIB.S9S_MB_2U(SCH_1):PAGE85_I174@PURE_QUANTA.SCONN288_ADR50017P087CC(CHIPS)':
 'VSS110': CDS_PINID='VSS110';
NODE_NAME     J4 255
 '@S9S_MB_2U_LIB.S9S_MB_2U(SCH_1):PAGE85_I174@PURE_QUANTA.SCONN288_ADR50017P087CC(CHIPS)':
 'VSS111': CDS_PINID='VSS111';
NODE_NAME     J4 257
 '@S9S_MB_2U_LIB.S9S_MB_2U(SCH_1):PAGE85_I174@PURE_QUANTA.SCONN288_ADR50017P087CC(CHIPS)':
 'VSS112': CDS_PINID='VSS112';
NODE_NAME     J4 259
 '@S9S_MB_2U_LIB.S9S_MB_2U(SCH_1):PAGE85_I174@PURE_QUANTA.SCONN288_ADR50017P087CC(CHIPS)':
 'VSS113': CDS_PINID='VSS113';
NODE_NAME     J4 262
 '@S9S_MB_2U_LIB.S9S_MB_2U(SCH_1):PAGE85_I174@PURE_QUANTA.SCONN288_ADR50017P087CC(CHIPS)':
 'VSS114': CDS_PINID='VSS114';
NODE_NAME     J4 264
 '@S9S_MB_2U_LIB.S9S_MB_2U(SCH_1):PAGE85_I174@PURE_QUANTA.SCONN288_ADR50017P087CC(CHIPS)':
 'VSS115': CDS_PINID='VSS115';
NODE_NAME     J4 266
 '@S9S_MB_2U_LIB.S9S_MB_2U(SCH_1):PAGE85_I174@PURE_QUANTA.SCONN288_ADR50017P087CC(CHIPS)':
 'VSS116': CDS_PINID='VSS116';
NODE_NAME     J4 268
 '@S9S_MB_2U_LIB.S9S_MB_2U(SCH_1):PAGE85_I174@PURE_QUANTA.SCONN288_ADR50017P087CC(CHIPS)':
 'VSS117': CDS_PINID='VSS117';
NODE_NAME     J4 270
 '@S9S_MB_2U_LIB.S9S_MB_2U(SCH_1):PAGE85_I174@PURE_QUANTA.SCONN288_ADR50017P087CC(CHIPS)':
 'VSS118': CDS_PINID='VSS118';
NODE_NAME     J4 273
 '@S9S_MB_2U_LIB.S9S_MB_2U(SCH_1):PAGE85_I174@PURE_QUANTA.SCONN288_ADR50017P087CC(CHIPS)':
 'VSS119': CDS_PINID='VSS119';
NODE_NAME     J4 275
 '@S9S_MB_2U_LIB.S9S_MB_2U(SCH_1):PAGE85_I174@PURE_QUANTA.SCONN288_ADR50017P087CC(CHIPS)':
 'VSS120': CDS_PINID='VSS120';
NODE_NAME     J4 277
 '@S9S_MB_2U_LIB.S9S_MB_2U(SCH_1):PAGE85_I174@PURE_QUANTA.SCONN288_ADR50017P087CC(CHIPS)':
 'VSS121': CDS_PINID='VSS121';
NODE_NAME     J4 279
 '@S9S_MB_2U_LIB.S9S_MB_2U(SCH_1):PAGE85_I174@PURE_QUANTA.SCONN288_ADR50017P087CC(CHIPS)':
 'VSS122': CDS_PINID='VSS122';
NODE_NAME     J4 281
 '@S9S_MB_2U_LIB.S9S_MB_2U(SCH_1):PAGE85_I174@PURE_QUANTA.SCONN288_ADR50017P087CC(CHIPS)':
 'VSS123': CDS_PINID='VSS123';
NODE_NAME     J4 284
 '@S9S_MB_2U_LIB.S9S_MB_2U(SCH_1):PAGE85_I174@PURE_QUANTA.SCONN288_ADR50017P087CC(CHIPS)':
 'VSS124': CDS_PINID='VSS124';
NODE_NAME     J4 286
 '@S9S_MB_2U_LIB.S9S_MB_2U(SCH_1):PAGE85_I174@PURE_QUANTA.SCONN288_ADR50017P087CC(CHIPS)':
 'VSS125': CDS_PINID='VSS125';
NODE_NAME     J4 288
 '@S9S_MB_2U_LIB.S9S_MB_2U(SCH_1):PAGE85_I174@PURE_QUANTA.SCONN288_ADR50017P087CC(CHIPS)':
 'VSS126': CDS_PINID='VSS126';
NODE_NAME     R30 2
 '@S9S_MB_2U_LIB.S9S_MB_2U(SCH_1):PAGE86_I3@PURE_QUANTA.Q_RES(CHIPS)':
 'B': CDS_PINID='B';
NODE_NAME     C14 2
 '@S9S_MB_2U_LIB.S9S_MB_2U(SCH_1):PAGE86_I120@PURE_QUANTA.Q_CAP(CHIPS)':
 'B': CDS_PINID='B';
NODE_NAME     C15 2
 '@S9S_MB_2U_LIB.S9S_MB_2U(SCH_1):PAGE86_I121@PURE_QUANTA.Q_CAP(CHIPS)':
 'B': CDS_PINID='B';
NODE_NAME     C16 2
 '@S9S_MB_2U_LIB.S9S_MB_2U(SCH_1):PAGE86_I123@PURE_QUANTA.Q_CAP(CHIPS)':
 'B': CDS_PINID='B';
NODE_NAME     J5 G1
 '@S9S_MB_2U_LIB.S9S_MB_2U(SCH_1):PAGE86_I174@PURE_QUANTA.SCONN288_ADR50017P130CC(CHIPS)':
 'G1': CDS_PINID='G1';
NODE_NAME     J5 G2
 '@S9S_MB_2U_LIB.S9S_MB_2U(SCH_1):PAGE86_I174@PURE_QUANTA.SCONN288_ADR50017P130CC(CHIPS)':
 'G2': CDS_PINID='G2';
NODE_NAME     J5 G3
 '@S9S_MB_2U_LIB.S9S_MB_2U(SCH_1):PAGE86_I174@PURE_QUANTA.SCONN288_ADR50017P130CC(CHIPS)':
 'G3': CDS_PINID='G3';
NODE_NAME     J5 6
 '@S9S_MB_2U_LIB.S9S_MB_2U(SCH_1):PAGE86_I174@PURE_QUANTA.SCONN288_ADR50017P130CC(CHIPS)':
 'VSS0': CDS_PINID='VSS0';
NODE_NAME     J5 8
 '@S9S_MB_2U_LIB.S9S_MB_2U(SCH_1):PAGE86_I174@PURE_QUANTA.SCONN288_ADR50017P130CC(CHIPS)':
 'VSS1': CDS_PINID='VSS1';
NODE_NAME     J5 10
 '@S9S_MB_2U_LIB.S9S_MB_2U(SCH_1):PAGE86_I174@PURE_QUANTA.SCONN288_ADR50017P130CC(CHIPS)':
 'VSS2': CDS_PINID='VSS2';
NODE_NAME     J5 13
 '@S9S_MB_2U_LIB.S9S_MB_2U(SCH_1):PAGE86_I174@PURE_QUANTA.SCONN288_ADR50017P130CC(CHIPS)':
 'VSS3': CDS_PINID='VSS3';
NODE_NAME     J5 15
 '@S9S_MB_2U_LIB.S9S_MB_2U(SCH_1):PAGE86_I174@PURE_QUANTA.SCONN288_ADR50017P130CC(CHIPS)':
 'VSS4': CDS_PINID='VSS4';
NODE_NAME     J5 17
 '@S9S_MB_2U_LIB.S9S_MB_2U(SCH_1):PAGE86_I174@PURE_QUANTA.SCONN288_ADR50017P130CC(CHIPS)':
 'VSS5': CDS_PINID='VSS5';
NODE_NAME     J5 19
 '@S9S_MB_2U_LIB.S9S_MB_2U(SCH_1):PAGE86_I174@PURE_QUANTA.SCONN288_ADR50017P130CC(CHIPS)':
 'VSS6': CDS_PINID='VSS6';
NODE_NAME     J5 21
 '@S9S_MB_2U_LIB.S9S_MB_2U(SCH_1):PAGE86_I174@PURE_QUANTA.SCONN288_ADR50017P130CC(CHIPS)':
 'VSS7': CDS_PINID='VSS7';
NODE_NAME     J5 24
 '@S9S_MB_2U_LIB.S9S_MB_2U(SCH_1):PAGE86_I174@PURE_QUANTA.SCONN288_ADR50017P130CC(CHIPS)':
 'VSS8': CDS_PINID='VSS8';
NODE_NAME     J5 26
 '@S9S_MB_2U_LIB.S9S_MB_2U(SCH_1):PAGE86_I174@PURE_QUANTA.SCONN288_ADR50017P130CC(CHIPS)':
 'VSS9': CDS_PINID='VSS9';
NODE_NAME     J5 28
 '@S9S_MB_2U_LIB.S9S_MB_2U(SCH_1):PAGE86_I174@PURE_QUANTA.SCONN288_ADR50017P130CC(CHIPS)':
 'VSS10': CDS_PINID='VSS10';
NODE_NAME     J5 30
 '@S9S_MB_2U_LIB.S9S_MB_2U(SCH_1):PAGE86_I174@PURE_QUANTA.SCONN288_ADR50017P130CC(CHIPS)':
 'VSS11': CDS_PINID='VSS11';
NODE_NAME     J5 32
 '@S9S_MB_2U_LIB.S9S_MB_2U(SCH_1):PAGE86_I174@PURE_QUANTA.SCONN288_ADR50017P130CC(CHIPS)':
 'VSS12': CDS_PINID='VSS12';
NODE_NAME     J5 35
 '@S9S_MB_2U_LIB.S9S_MB_2U(SCH_1):PAGE86_I174@PURE_QUANTA.SCONN288_ADR50017P130CC(CHIPS)':
 'VSS13': CDS_PINID='VSS13';
NODE_NAME     J5 37
 '@S9S_MB_2U_LIB.S9S_MB_2U(SCH_1):PAGE86_I174@PURE_QUANTA.SCONN288_ADR50017P130CC(CHIPS)':
 'VSS14': CDS_PINID='VSS14';
NODE_NAME     J5 39
 '@S9S_MB_2U_LIB.S9S_MB_2U(SCH_1):PAGE86_I174@PURE_QUANTA.SCONN288_ADR50017P130CC(CHIPS)':
 'VSS15': CDS_PINID='VSS15';
NODE_NAME     J5 41
 '@S9S_MB_2U_LIB.S9S_MB_2U(SCH_1):PAGE86_I174@PURE_QUANTA.SCONN288_ADR50017P130CC(CHIPS)':
 'VSS16': CDS_PINID='VSS16';
NODE_NAME     J5 43
 '@S9S_MB_2U_LIB.S9S_MB_2U(SCH_1):PAGE86_I174@PURE_QUANTA.SCONN288_ADR50017P130CC(CHIPS)':
 'VSS17': CDS_PINID='VSS17';
NODE_NAME     J5 46
 '@S9S_MB_2U_LIB.S9S_MB_2U(SCH_1):PAGE86_I174@PURE_QUANTA.SCONN288_ADR50017P130CC(CHIPS)':
 'VSS18': CDS_PINID='VSS18';
NODE_NAME     J5 48
 '@S9S_MB_2U_LIB.S9S_MB_2U(SCH_1):PAGE86_I174@PURE_QUANTA.SCONN288_ADR50017P130CC(CHIPS)':
 'VSS19': CDS_PINID='VSS19';
NODE_NAME     J5 50
 '@S9S_MB_2U_LIB.S9S_MB_2U(SCH_1):PAGE86_I174@PURE_QUANTA.SCONN288_ADR50017P130CC(CHIPS)':
 'VSS20': CDS_PINID='VSS20';
NODE_NAME     J5 52
 '@S9S_MB_2U_LIB.S9S_MB_2U(SCH_1):PAGE86_I174@PURE_QUANTA.SCONN288_ADR50017P130CC(CHIPS)':
 'VSS21': CDS_PINID='VSS21';
NODE_NAME     J5 54
 '@S9S_MB_2U_LIB.S9S_MB_2U(SCH_1):PAGE86_I174@PURE_QUANTA.SCONN288_ADR50017P130CC(CHIPS)':
 'VSS22': CDS_PINID='VSS22';
NODE_NAME     J5 57
 '@S9S_MB_2U_LIB.S9S_MB_2U(SCH_1):PAGE86_I174@PURE_QUANTA.SCONN288_ADR50017P130CC(CHIPS)':
 'VSS23': CDS_PINID='VSS23';
NODE_NAME     J5 59
 '@S9S_MB_2U_LIB.S9S_MB_2U(SCH_1):PAGE86_I174@PURE_QUANTA.SCONN288_ADR50017P130CC(CHIPS)':
 'VSS24': CDS_PINID='VSS24';
NODE_NAME     J5 61
 '@S9S_MB_2U_LIB.S9S_MB_2U(SCH_1):PAGE86_I174@PURE_QUANTA.SCONN288_ADR50017P130CC(CHIPS)':
 'VSS25': CDS_PINID='VSS25';
NODE_NAME     J5 63
 '@S9S_MB_2U_LIB.S9S_MB_2U(SCH_1):PAGE86_I174@PURE_QUANTA.SCONN288_ADR50017P130CC(CHIPS)':
 'VSS26': CDS_PINID='VSS26';
NODE_NAME     J5 65
 '@S9S_MB_2U_LIB.S9S_MB_2U(SCH_1):PAGE86_I174@PURE_QUANTA.SCONN288_ADR50017P130CC(CHIPS)':
 'VSS27': CDS_PINID='VSS27';
NODE_NAME     J5 67
 '@S9S_MB_2U_LIB.S9S_MB_2U(SCH_1):PAGE86_I174@PURE_QUANTA.SCONN288_ADR50017P130CC(CHIPS)':
 'VSS28': CDS_PINID='VSS28';
NODE_NAME     J5 69
 '@S9S_MB_2U_LIB.S9S_MB_2U(SCH_1):PAGE86_I174@PURE_QUANTA.SCONN288_ADR50017P130CC(CHIPS)':
 'VSS29': CDS_PINID='VSS29';
NODE_NAME     J5 71
 '@S9S_MB_2U_LIB.S9S_MB_2U(SCH_1):PAGE86_I174@PURE_QUANTA.SCONN288_ADR50017P130CC(CHIPS)':
 'VSS30': CDS_PINID='VSS30';
NODE_NAME     J5 73
 '@S9S_MB_2U_LIB.S9S_MB_2U(SCH_1):PAGE86_I174@PURE_QUANTA.SCONN288_ADR50017P130CC(CHIPS)':
 'VSS31': CDS_PINID='VSS31';
NODE_NAME     J5 75
 '@S9S_MB_2U_LIB.S9S_MB_2U(SCH_1):PAGE86_I174@PURE_QUANTA.SCONN288_ADR50017P130CC(CHIPS)':
 'VSS32': CDS_PINID='VSS32';
NODE_NAME     J5 77
 '@S9S_MB_2U_LIB.S9S_MB_2U(SCH_1):PAGE86_I174@PURE_QUANTA.SCONN288_ADR50017P130CC(CHIPS)':
 'VSS33': CDS_PINID='VSS33';
NODE_NAME     J5 79
 '@S9S_MB_2U_LIB.S9S_MB_2U(SCH_1):PAGE86_I174@PURE_QUANTA.SCONN288_ADR50017P130CC(CHIPS)':
 'VSS34': CDS_PINID='VSS34';
NODE_NAME     J5 81
 '@S9S_MB_2U_LIB.S9S_MB_2U(SCH_1):PAGE86_I174@PURE_QUANTA.SCONN288_ADR50017P130CC(CHIPS)':
 'VSS35': CDS_PINID='VSS35';
NODE_NAME     J5 83
 '@S9S_MB_2U_LIB.S9S_MB_2U(SCH_1):PAGE86_I174@PURE_QUANTA.SCONN288_ADR50017P130CC(CHIPS)':
 'VSS36': CDS_PINID='VSS36';
NODE_NAME     J5 85
 '@S9S_MB_2U_LIB.S9S_MB_2U(SCH_1):PAGE86_I174@PURE_QUANTA.SCONN288_ADR50017P130CC(CHIPS)':
 'VSS37': CDS_PINID='VSS37';
NODE_NAME     J5 88
 '@S9S_MB_2U_LIB.S9S_MB_2U(SCH_1):PAGE86_I174@PURE_QUANTA.SCONN288_ADR50017P130CC(CHIPS)':
 'VSS38': CDS_PINID='VSS38';
NODE_NAME     J5 90
 '@S9S_MB_2U_LIB.S9S_MB_2U(SCH_1):PAGE86_I174@PURE_QUANTA.SCONN288_ADR50017P130CC(CHIPS)':
 'VSS39': CDS_PINID='VSS39';
NODE_NAME     J5 92
 '@S9S_MB_2U_LIB.S9S_MB_2U(SCH_1):PAGE86_I174@PURE_QUANTA.SCONN288_ADR50017P130CC(CHIPS)':
 'VSS40': CDS_PINID='VSS40';
NODE_NAME     J5 95
 '@S9S_MB_2U_LIB.S9S_MB_2U(SCH_1):PAGE86_I174@PURE_QUANTA.SCONN288_ADR50017P130CC(CHIPS)':
 'VSS41': CDS_PINID='VSS41';
NODE_NAME     J5 97
 '@S9S_MB_2U_LIB.S9S_MB_2U(SCH_1):PAGE86_I174@PURE_QUANTA.SCONN288_ADR50017P130CC(CHIPS)':
 'VSS42': CDS_PINID='VSS42';
NODE_NAME     J5 99
 '@S9S_MB_2U_LIB.S9S_MB_2U(SCH_1):PAGE86_I174@PURE_QUANTA.SCONN288_ADR50017P130CC(CHIPS)':
 'VSS43': CDS_PINID='VSS43';
NODE_NAME     J5 101
 '@S9S_MB_2U_LIB.S9S_MB_2U(SCH_1):PAGE86_I174@PURE_QUANTA.SCONN288_ADR50017P130CC(CHIPS)':
 'VSS44': CDS_PINID='VSS44';
NODE_NAME     J5 103
 '@S9S_MB_2U_LIB.S9S_MB_2U(SCH_1):PAGE86_I174@PURE_QUANTA.SCONN288_ADR50017P130CC(CHIPS)':
 'VSS45': CDS_PINID='VSS45';
NODE_NAME     J5 106
 '@S9S_MB_2U_LIB.S9S_MB_2U(SCH_1):PAGE86_I174@PURE_QUANTA.SCONN288_ADR50017P130CC(CHIPS)':
 'VSS46': CDS_PINID='VSS46';
NODE_NAME     J5 108
 '@S9S_MB_2U_LIB.S9S_MB_2U(SCH_1):PAGE86_I174@PURE_QUANTA.SCONN288_ADR50017P130CC(CHIPS)':
 'VSS47': CDS_PINID='VSS47';
NODE_NAME     J5 110
 '@S9S_MB_2U_LIB.S9S_MB_2U(SCH_1):PAGE86_I174@PURE_QUANTA.SCONN288_ADR50017P130CC(CHIPS)':
 'VSS48': CDS_PINID='VSS48';
NODE_NAME     J5 112
 '@S9S_MB_2U_LIB.S9S_MB_2U(SCH_1):PAGE86_I174@PURE_QUANTA.SCONN288_ADR50017P130CC(CHIPS)':
 'VSS49': CDS_PINID='VSS49';
NODE_NAME     J5 114
 '@S9S_MB_2U_LIB.S9S_MB_2U(SCH_1):PAGE86_I174@PURE_QUANTA.SCONN288_ADR50017P130CC(CHIPS)':
 'VSS50': CDS_PINID='VSS50';
NODE_NAME     J5 117
 '@S9S_MB_2U_LIB.S9S_MB_2U(SCH_1):PAGE86_I174@PURE_QUANTA.SCONN288_ADR50017P130CC(CHIPS)':
 'VSS51': CDS_PINID='VSS51';
NODE_NAME     J5 119
 '@S9S_MB_2U_LIB.S9S_MB_2U(SCH_1):PAGE86_I174@PURE_QUANTA.SCONN288_ADR50017P130CC(CHIPS)':
 'VSS52': CDS_PINID='VSS52';
NODE_NAME     J5 121
 '@S9S_MB_2U_LIB.S9S_MB_2U(SCH_1):PAGE86_I174@PURE_QUANTA.SCONN288_ADR50017P130CC(CHIPS)':
 'VSS53': CDS_PINID='VSS53';
NODE_NAME     J5 123
 '@S9S_MB_2U_LIB.S9S_MB_2U(SCH_1):PAGE86_I174@PURE_QUANTA.SCONN288_ADR50017P130CC(CHIPS)':
 'VSS54': CDS_PINID='VSS54';
NODE_NAME     J5 125
 '@S9S_MB_2U_LIB.S9S_MB_2U(SCH_1):PAGE86_I174@PURE_QUANTA.SCONN288_ADR50017P130CC(CHIPS)':
 'VSS55': CDS_PINID='VSS55';
NODE_NAME     J5 128
 '@S9S_MB_2U_LIB.S9S_MB_2U(SCH_1):PAGE86_I174@PURE_QUANTA.SCONN288_ADR50017P130CC(CHIPS)':
 'VSS56': CDS_PINID='VSS56';
NODE_NAME     J5 130
 '@S9S_MB_2U_LIB.S9S_MB_2U(SCH_1):PAGE86_I174@PURE_QUANTA.SCONN288_ADR50017P130CC(CHIPS)':
 'VSS57': CDS_PINID='VSS57';
NODE_NAME     J5 132
 '@S9S_MB_2U_LIB.S9S_MB_2U(SCH_1):PAGE86_I174@PURE_QUANTA.SCONN288_ADR50017P130CC(CHIPS)':
 'VSS58': CDS_PINID='VSS58';
NODE_NAME     J5 134
 '@S9S_MB_2U_LIB.S9S_MB_2U(SCH_1):PAGE86_I174@PURE_QUANTA.SCONN288_ADR50017P130CC(CHIPS)':
 'VSS59': CDS_PINID='VSS59';
NODE_NAME     J5 136
 '@S9S_MB_2U_LIB.S9S_MB_2U(SCH_1):PAGE86_I174@PURE_QUANTA.SCONN288_ADR50017P130CC(CHIPS)':
 'VSS60': CDS_PINID='VSS60';
NODE_NAME     J5 139
 '@S9S_MB_2U_LIB.S9S_MB_2U(SCH_1):PAGE86_I174@PURE_QUANTA.SCONN288_ADR50017P130CC(CHIPS)':
 'VSS61': CDS_PINID='VSS61';
NODE_NAME     J5 141
 '@S9S_MB_2U_LIB.S9S_MB_2U(SCH_1):PAGE86_I174@PURE_QUANTA.SCONN288_ADR50017P130CC(CHIPS)':
 'VSS62': CDS_PINID='VSS62';
NODE_NAME     J5 143
 '@S9S_MB_2U_LIB.S9S_MB_2U(SCH_1):PAGE86_I174@PURE_QUANTA.SCONN288_ADR50017P130CC(CHIPS)':
 'VSS63': CDS_PINID='VSS63';
NODE_NAME     J5 151
 '@S9S_MB_2U_LIB.S9S_MB_2U(SCH_1):PAGE86_I174@PURE_QUANTA.SCONN288_ADR50017P130CC(CHIPS)':
 'VSS64': CDS_PINID='VSS64';
NODE_NAME     J5 153
 '@S9S_MB_2U_LIB.S9S_MB_2U(SCH_1):PAGE86_I174@PURE_QUANTA.SCONN288_ADR50017P130CC(CHIPS)':
 'VSS65': CDS_PINID='VSS65';
NODE_NAME     J5 155
 '@S9S_MB_2U_LIB.S9S_MB_2U(SCH_1):PAGE86_I174@PURE_QUANTA.SCONN288_ADR50017P130CC(CHIPS)':
 'VSS66': CDS_PINID='VSS66';
NODE_NAME     J5 158
 '@S9S_MB_2U_LIB.S9S_MB_2U(SCH_1):PAGE86_I174@PURE_QUANTA.SCONN288_ADR50017P130CC(CHIPS)':
 'VSS67': CDS_PINID='VSS67';
NODE_NAME     J5 160
 '@S9S_MB_2U_LIB.S9S_MB_2U(SCH_1):PAGE86_I174@PURE_QUANTA.SCONN288_ADR50017P130CC(CHIPS)':
 'VSS68': CDS_PINID='VSS68';
NODE_NAME     J5 162
 '@S9S_MB_2U_LIB.S9S_MB_2U(SCH_1):PAGE86_I174@PURE_QUANTA.SCONN288_ADR50017P130CC(CHIPS)':
 'VSS69': CDS_PINID='VSS69';
NODE_NAME     J5 164
 '@S9S_MB_2U_LIB.S9S_MB_2U(SCH_1):PAGE86_I174@PURE_QUANTA.SCONN288_ADR50017P130CC(CHIPS)':
 'VSS70': CDS_PINID='VSS70';
NODE_NAME     J5 166
 '@S9S_MB_2U_LIB.S9S_MB_2U(SCH_1):PAGE86_I174@PURE_QUANTA.SCONN288_ADR50017P130CC(CHIPS)':
 'VSS71': CDS_PINID='VSS71';
NODE_NAME     J5 169
 '@S9S_MB_2U_LIB.S9S_MB_2U(SCH_1):PAGE86_I174@PURE_QUANTA.SCONN288_ADR50017P130CC(CHIPS)':
 'VSS72': CDS_PINID='VSS72';
NODE_NAME     J5 171
 '@S9S_MB_2U_LIB.S9S_MB_2U(SCH_1):PAGE86_I174@PURE_QUANTA.SCONN288_ADR50017P130CC(CHIPS)':
 'VSS73': CDS_PINID='VSS73';
NODE_NAME     J5 173
 '@S9S_MB_2U_LIB.S9S_MB_2U(SCH_1):PAGE86_I174@PURE_QUANTA.SCONN288_ADR50017P130CC(CHIPS)':
 'VSS74': CDS_PINID='VSS74';
NODE_NAME     J5 175
 '@S9S_MB_2U_LIB.S9S_MB_2U(SCH_1):PAGE86_I174@PURE_QUANTA.SCONN288_ADR50017P130CC(CHIPS)':
 'VSS75': CDS_PINID='VSS75';
NODE_NAME     J5 177
 '@S9S_MB_2U_LIB.S9S_MB_2U(SCH_1):PAGE86_I174@PURE_QUANTA.SCONN288_ADR50017P130CC(CHIPS)':
 'VSS76': CDS_PINID='VSS76';
NODE_NAME     J5 180
 '@S9S_MB_2U_LIB.S9S_MB_2U(SCH_1):PAGE86_I174@PURE_QUANTA.SCONN288_ADR50017P130CC(CHIPS)':
 'VSS77': CDS_PINID='VSS77';
NODE_NAME     J5 182
 '@S9S_MB_2U_LIB.S9S_MB_2U(SCH_1):PAGE86_I174@PURE_QUANTA.SCONN288_ADR50017P130CC(CHIPS)':
 'VSS78': CDS_PINID='VSS78';
NODE_NAME     J5 184
 '@S9S_MB_2U_LIB.S9S_MB_2U(SCH_1):PAGE86_I174@PURE_QUANTA.SCONN288_ADR50017P130CC(CHIPS)':
 'VSS79': CDS_PINID='VSS79';
NODE_NAME     J5 186
 '@S9S_MB_2U_LIB.S9S_MB_2U(SCH_1):PAGE86_I174@PURE_QUANTA.SCONN288_ADR50017P130CC(CHIPS)':
 'VSS80': CDS_PINID='VSS80';
NODE_NAME     J5 188
 '@S9S_MB_2U_LIB.S9S_MB_2U(SCH_1):PAGE86_I174@PURE_QUANTA.SCONN288_ADR50017P130CC(CHIPS)':
 'VSS81': CDS_PINID='VSS81';
NODE_NAME     J5 191
 '@S9S_MB_2U_LIB.S9S_MB_2U(SCH_1):PAGE86_I174@PURE_QUANTA.SCONN288_ADR50017P130CC(CHIPS)':
 'VSS82': CDS_PINID='VSS82';
NODE_NAME     J5 193
 '@S9S_MB_2U_LIB.S9S_MB_2U(SCH_1):PAGE86_I174@PURE_QUANTA.SCONN288_ADR50017P130CC(CHIPS)':
 'VSS83': CDS_PINID='VSS83';
NODE_NAME     J5 195
 '@S9S_MB_2U_LIB.S9S_MB_2U(SCH_1):PAGE86_I174@PURE_QUANTA.SCONN288_ADR50017P130CC(CHIPS)':
 'VSS84': CDS_PINID='VSS84';
NODE_NAME     J5 197
 '@S9S_MB_2U_LIB.S9S_MB_2U(SCH_1):PAGE86_I174@PURE_QUANTA.SCONN288_ADR50017P130CC(CHIPS)':
 'VSS85': CDS_PINID='VSS85';
NODE_NAME     J5 199
 '@S9S_MB_2U_LIB.S9S_MB_2U(SCH_1):PAGE86_I174@PURE_QUANTA.SCONN288_ADR50017P130CC(CHIPS)':
 'VSS86': CDS_PINID='VSS86';
NODE_NAME     J5 202
 '@S9S_MB_2U_LIB.S9S_MB_2U(SCH_1):PAGE86_I174@PURE_QUANTA.SCONN288_ADR50017P130CC(CHIPS)':
 'VSS87': CDS_PINID='VSS87';
NODE_NAME     J5 204
 '@S9S_MB_2U_LIB.S9S_MB_2U(SCH_1):PAGE86_I174@PURE_QUANTA.SCONN288_ADR50017P130CC(CHIPS)':
 'VSS88': CDS_PINID='VSS88';
NODE_NAME     J5 206
 '@S9S_MB_2U_LIB.S9S_MB_2U(SCH_1):PAGE86_I174@PURE_QUANTA.SCONN288_ADR50017P130CC(CHIPS)':
 'VSS89': CDS_PINID='VSS89';
NODE_NAME     J5 208
 '@S9S_MB_2U_LIB.S9S_MB_2U(SCH_1):PAGE86_I174@PURE_QUANTA.SCONN288_ADR50017P130CC(CHIPS)':
 'VSS90': CDS_PINID='VSS90';
NODE_NAME     J5 210
 '@S9S_MB_2U_LIB.S9S_MB_2U(SCH_1):PAGE86_I174@PURE_QUANTA.SCONN288_ADR50017P130CC(CHIPS)':
 'VSS91': CDS_PINID='VSS91';
NODE_NAME     J5 212
 '@S9S_MB_2U_LIB.S9S_MB_2U(SCH_1):PAGE86_I174@PURE_QUANTA.SCONN288_ADR50017P130CC(CHIPS)':
 'VSS92': CDS_PINID='VSS92';
NODE_NAME     J5 214
 '@S9S_MB_2U_LIB.S9S_MB_2U(SCH_1):PAGE86_I174@PURE_QUANTA.SCONN288_ADR50017P130CC(CHIPS)':
 'VSS93': CDS_PINID='VSS93';
NODE_NAME     J5 216
 '@S9S_MB_2U_LIB.S9S_MB_2U(SCH_1):PAGE86_I174@PURE_QUANTA.SCONN288_ADR50017P130CC(CHIPS)':
 'VSS94': CDS_PINID='VSS94';
NODE_NAME     J5 219
 '@S9S_MB_2U_LIB.S9S_MB_2U(SCH_1):PAGE86_I174@PURE_QUANTA.SCONN288_ADR50017P130CC(CHIPS)':
 'VSS95': CDS_PINID='VSS95';
NODE_NAME     J5 222
 '@S9S_MB_2U_LIB.S9S_MB_2U(SCH_1):PAGE86_I174@PURE_QUANTA.SCONN288_ADR50017P130CC(CHIPS)':
 'VSS96': CDS_PINID='VSS96';
NODE_NAME     J5 224
 '@S9S_MB_2U_LIB.S9S_MB_2U(SCH_1):PAGE86_I174@PURE_QUANTA.SCONN288_ADR50017P130CC(CHIPS)':
 'VSS97': CDS_PINID='VSS97';
NODE_NAME     J5 226
 '@S9S_MB_2U_LIB.S9S_MB_2U(SCH_1):PAGE86_I174@PURE_QUANTA.SCONN288_ADR50017P130CC(CHIPS)':
 'VSS98': CDS_PINID='VSS98';
NODE_NAME     J5 228
 '@S9S_MB_2U_LIB.S9S_MB_2U(SCH_1):PAGE86_I174@PURE_QUANTA.SCONN288_ADR50017P130CC(CHIPS)':
 'VSS99': CDS_PINID='VSS99';
NODE_NAME     J5 230
 '@S9S_MB_2U_LIB.S9S_MB_2U(SCH_1):PAGE86_I174@PURE_QUANTA.SCONN288_ADR50017P130CC(CHIPS)':
 'VSS100': CDS_PINID='VSS100';
NODE_NAME     J5 233
 '@S9S_MB_2U_LIB.S9S_MB_2U(SCH_1):PAGE86_I174@PURE_QUANTA.SCONN288_ADR50017P130CC(CHIPS)':
 'VSS101': CDS_PINID='VSS101';
NODE_NAME     J5 235
 '@S9S_MB_2U_LIB.S9S_MB_2U(SCH_1):PAGE86_I174@PURE_QUANTA.SCONN288_ADR50017P130CC(CHIPS)':
 'VSS102': CDS_PINID='VSS102';
NODE_NAME     J5 237
 '@S9S_MB_2U_LIB.S9S_MB_2U(SCH_1):PAGE86_I174@PURE_QUANTA.SCONN288_ADR50017P130CC(CHIPS)':
 'VSS103': CDS_PINID='VSS103';
NODE_NAME     J5 240
 '@S9S_MB_2U_LIB.S9S_MB_2U(SCH_1):PAGE86_I174@PURE_QUANTA.SCONN288_ADR50017P130CC(CHIPS)':
 'VSS104': CDS_PINID='VSS104';
NODE_NAME     J5 242
 '@S9S_MB_2U_LIB.S9S_MB_2U(SCH_1):PAGE86_I174@PURE_QUANTA.SCONN288_ADR50017P130CC(CHIPS)':
 'VSS105': CDS_PINID='VSS105';
NODE_NAME     J5 244
 '@S9S_MB_2U_LIB.S9S_MB_2U(SCH_1):PAGE86_I174@PURE_QUANTA.SCONN288_ADR50017P130CC(CHIPS)':
 'VSS106': CDS_PINID='VSS106';
NODE_NAME     J5 246
 '@S9S_MB_2U_LIB.S9S_MB_2U(SCH_1):PAGE86_I174@PURE_QUANTA.SCONN288_ADR50017P130CC(CHIPS)':
 'VSS107': CDS_PINID='VSS107';
NODE_NAME     J5 248
 '@S9S_MB_2U_LIB.S9S_MB_2U(SCH_1):PAGE86_I174@PURE_QUANTA.SCONN288_ADR50017P130CC(CHIPS)':
 'VSS108': CDS_PINID='VSS108';
NODE_NAME     J5 251
 '@S9S_MB_2U_LIB.S9S_MB_2U(SCH_1):PAGE86_I174@PURE_QUANTA.SCONN288_ADR50017P130CC(CHIPS)':
 'VSS109': CDS_PINID='VSS109';
NODE_NAME     J5 253
 '@S9S_MB_2U_LIB.S9S_MB_2U(SCH_1):PAGE86_I174@PURE_QUANTA.SCONN288_ADR50017P130CC(CHIPS)':
 'VSS110': CDS_PINID='VSS110';
NODE_NAME     J5 255
 '@S9S_MB_2U_LIB.S9S_MB_2U(SCH_1):PAGE86_I174@PURE_QUANTA.SCONN288_ADR50017P130CC(CHIPS)':
 'VSS111': CDS_PINID='VSS111';
NODE_NAME     J5 257
 '@S9S_MB_2U_LIB.S9S_MB_2U(SCH_1):PAGE86_I174@PURE_QUANTA.SCONN288_ADR50017P130CC(CHIPS)':
 'VSS112': CDS_PINID='VSS112';
NODE_NAME     J5 259
 '@S9S_MB_2U_LIB.S9S_MB_2U(SCH_1):PAGE86_I174@PURE_QUANTA.SCONN288_ADR50017P130CC(CHIPS)':
 'VSS113': CDS_PINID='VSS113';
NODE_NAME     J5 262
 '@S9S_MB_2U_LIB.S9S_MB_2U(SCH_1):PAGE86_I174@PURE_QUANTA.SCONN288_ADR50017P130CC(CHIPS)':
 'VSS114': CDS_PINID='VSS114';
NODE_NAME     J5 264
 '@S9S_MB_2U_LIB.S9S_MB_2U(SCH_1):PAGE86_I174@PURE_QUANTA.SCONN288_ADR50017P130CC(CHIPS)':
 'VSS115': CDS_PINID='VSS115';
NODE_NAME     J5 266
 '@S9S_MB_2U_LIB.S9S_MB_2U(SCH_1):PAGE86_I174@PURE_QUANTA.SCONN288_ADR50017P130CC(CHIPS)':
 'VSS116': CDS_PINID='VSS116';
NODE_NAME     J5 268
 '@S9S_MB_2U_LIB.S9S_MB_2U(SCH_1):PAGE86_I174@PURE_QUANTA.SCONN288_ADR50017P130CC(CHIPS)':
 'VSS117': CDS_PINID='VSS117';
NODE_NAME     J5 270
 '@S9S_MB_2U_LIB.S9S_MB_2U(SCH_1):PAGE86_I174@PURE_QUANTA.SCONN288_ADR50017P130CC(CHIPS)':
 'VSS118': CDS_PINID='VSS118';
NODE_NAME     J5 273
 '@S9S_MB_2U_LIB.S9S_MB_2U(SCH_1):PAGE86_I174@PURE_QUANTA.SCONN288_ADR50017P130CC(CHIPS)':
 'VSS119': CDS_PINID='VSS119';
NODE_NAME     J5 275
 '@S9S_MB_2U_LIB.S9S_MB_2U(SCH_1):PAGE86_I174@PURE_QUANTA.SCONN288_ADR50017P130CC(CHIPS)':
 'VSS120': CDS_PINID='VSS120';
NODE_NAME     J5 277
 '@S9S_MB_2U_LIB.S9S_MB_2U(SCH_1):PAGE86_I174@PURE_QUANTA.SCONN288_ADR50017P130CC(CHIPS)':
 'VSS121': CDS_PINID='VSS121';
NODE_NAME     J5 279
 '@S9S_MB_2U_LIB.S9S_MB_2U(SCH_1):PAGE86_I174@PURE_QUANTA.SCONN288_ADR50017P130CC(CHIPS)':
 'VSS122': CDS_PINID='VSS122';
NODE_NAME     J5 281
 '@S9S_MB_2U_LIB.S9S_MB_2U(SCH_1):PAGE86_I174@PURE_QUANTA.SCONN288_ADR50017P130CC(CHIPS)':
 'VSS123': CDS_PINID='VSS123';
NODE_NAME     J5 284
 '@S9S_MB_2U_LIB.S9S_MB_2U(SCH_1):PAGE86_I174@PURE_QUANTA.SCONN288_ADR50017P130CC(CHIPS)':
 'VSS124': CDS_PINID='VSS124';
NODE_NAME     J5 286
 '@S9S_MB_2U_LIB.S9S_MB_2U(SCH_1):PAGE86_I174@PURE_QUANTA.SCONN288_ADR50017P130CC(CHIPS)':
 'VSS125': CDS_PINID='VSS125';
NODE_NAME     J5 288
 '@S9S_MB_2U_LIB.S9S_MB_2U(SCH_1):PAGE86_I174@PURE_QUANTA.SCONN288_ADR50017P130CC(CHIPS)':
 'VSS126': CDS_PINID='VSS126';
NODE_NAME     R31 2
 '@S9S_MB_2U_LIB.S9S_MB_2U(SCH_1):PAGE87_I45@PURE_QUANTA.Q_RES(CHIPS)':
 'B': CDS_PINID='B';
NODE_NAME     C17 2
 '@S9S_MB_2U_LIB.S9S_MB_2U(SCH_1):PAGE87_I120@PURE_QUANTA.Q_CAP(CHIPS)':
 'B': CDS_PINID='B';
NODE_NAME     C18 2
 '@S9S_MB_2U_LIB.S9S_MB_2U(SCH_1):PAGE87_I124@PURE_QUANTA.Q_CAP(CHIPS)':
 'B': CDS_PINID='B';
NODE_NAME     C19 2
 '@S9S_MB_2U_LIB.S9S_MB_2U(SCH_1):PAGE87_I127@PURE_QUANTA.Q_CAP(CHIPS)':
 'B': CDS_PINID='B';
NODE_NAME     J6 G1
 '@S9S_MB_2U_LIB.S9S_MB_2U(SCH_1):PAGE87_I175@PURE_QUANTA.SCONN288_ADR50017P087CC(CHIPS)':
 'G1': CDS_PINID='G1';
NODE_NAME     J6 G2
 '@S9S_MB_2U_LIB.S9S_MB_2U(SCH_1):PAGE87_I175@PURE_QUANTA.SCONN288_ADR50017P087CC(CHIPS)':
 'G2': CDS_PINID='G2';
NODE_NAME     J6 G3
 '@S9S_MB_2U_LIB.S9S_MB_2U(SCH_1):PAGE87_I175@PURE_QUANTA.SCONN288_ADR50017P087CC(CHIPS)':
 'G3': CDS_PINID='G3';
NODE_NAME     J6 6
 '@S9S_MB_2U_LIB.S9S_MB_2U(SCH_1):PAGE87_I175@PURE_QUANTA.SCONN288_ADR50017P087CC(CHIPS)':
 'VSS0': CDS_PINID='VSS0';
NODE_NAME     J6 8
 '@S9S_MB_2U_LIB.S9S_MB_2U(SCH_1):PAGE87_I175@PURE_QUANTA.SCONN288_ADR50017P087CC(CHIPS)':
 'VSS1': CDS_PINID='VSS1';
NODE_NAME     J6 10
 '@S9S_MB_2U_LIB.S9S_MB_2U(SCH_1):PAGE87_I175@PURE_QUANTA.SCONN288_ADR50017P087CC(CHIPS)':
 'VSS2': CDS_PINID='VSS2';
NODE_NAME     J6 13
 '@S9S_MB_2U_LIB.S9S_MB_2U(SCH_1):PAGE87_I175@PURE_QUANTA.SCONN288_ADR50017P087CC(CHIPS)':
 'VSS3': CDS_PINID='VSS3';
NODE_NAME     J6 15
 '@S9S_MB_2U_LIB.S9S_MB_2U(SCH_1):PAGE87_I175@PURE_QUANTA.SCONN288_ADR50017P087CC(CHIPS)':
 'VSS4': CDS_PINID='VSS4';
NODE_NAME     J6 17
 '@S9S_MB_2U_LIB.S9S_MB_2U(SCH_1):PAGE87_I175@PURE_QUANTA.SCONN288_ADR50017P087CC(CHIPS)':
 'VSS5': CDS_PINID='VSS5';
NODE_NAME     J6 19
 '@S9S_MB_2U_LIB.S9S_MB_2U(SCH_1):PAGE87_I175@PURE_QUANTA.SCONN288_ADR50017P087CC(CHIPS)':
 'VSS6': CDS_PINID='VSS6';
NODE_NAME     J6 21
 '@S9S_MB_2U_LIB.S9S_MB_2U(SCH_1):PAGE87_I175@PURE_QUANTA.SCONN288_ADR50017P087CC(CHIPS)':
 'VSS7': CDS_PINID='VSS7';
NODE_NAME     J6 24
 '@S9S_MB_2U_LIB.S9S_MB_2U(SCH_1):PAGE87_I175@PURE_QUANTA.SCONN288_ADR50017P087CC(CHIPS)':
 'VSS8': CDS_PINID='VSS8';
NODE_NAME     J6 26
 '@S9S_MB_2U_LIB.S9S_MB_2U(SCH_1):PAGE87_I175@PURE_QUANTA.SCONN288_ADR50017P087CC(CHIPS)':
 'VSS9': CDS_PINID='VSS9';
NODE_NAME     J6 28
 '@S9S_MB_2U_LIB.S9S_MB_2U(SCH_1):PAGE87_I175@PURE_QUANTA.SCONN288_ADR50017P087CC(CHIPS)':
 'VSS10': CDS_PINID='VSS10';
NODE_NAME     J6 30
 '@S9S_MB_2U_LIB.S9S_MB_2U(SCH_1):PAGE87_I175@PURE_QUANTA.SCONN288_ADR50017P087CC(CHIPS)':
 'VSS11': CDS_PINID='VSS11';
NODE_NAME     J6 32
 '@S9S_MB_2U_LIB.S9S_MB_2U(SCH_1):PAGE87_I175@PURE_QUANTA.SCONN288_ADR50017P087CC(CHIPS)':
 'VSS12': CDS_PINID='VSS12';
NODE_NAME     J6 35
 '@S9S_MB_2U_LIB.S9S_MB_2U(SCH_1):PAGE87_I175@PURE_QUANTA.SCONN288_ADR50017P087CC(CHIPS)':
 'VSS13': CDS_PINID='VSS13';
NODE_NAME     J6 37
 '@S9S_MB_2U_LIB.S9S_MB_2U(SCH_1):PAGE87_I175@PURE_QUANTA.SCONN288_ADR50017P087CC(CHIPS)':
 'VSS14': CDS_PINID='VSS14';
NODE_NAME     J6 39
 '@S9S_MB_2U_LIB.S9S_MB_2U(SCH_1):PAGE87_I175@PURE_QUANTA.SCONN288_ADR50017P087CC(CHIPS)':
 'VSS15': CDS_PINID='VSS15';
NODE_NAME     J6 41
 '@S9S_MB_2U_LIB.S9S_MB_2U(SCH_1):PAGE87_I175@PURE_QUANTA.SCONN288_ADR50017P087CC(CHIPS)':
 'VSS16': CDS_PINID='VSS16';
NODE_NAME     J6 43
 '@S9S_MB_2U_LIB.S9S_MB_2U(SCH_1):PAGE87_I175@PURE_QUANTA.SCONN288_ADR50017P087CC(CHIPS)':
 'VSS17': CDS_PINID='VSS17';
NODE_NAME     J6 46
 '@S9S_MB_2U_LIB.S9S_MB_2U(SCH_1):PAGE87_I175@PURE_QUANTA.SCONN288_ADR50017P087CC(CHIPS)':
 'VSS18': CDS_PINID='VSS18';
NODE_NAME     J6 48
 '@S9S_MB_2U_LIB.S9S_MB_2U(SCH_1):PAGE87_I175@PURE_QUANTA.SCONN288_ADR50017P087CC(CHIPS)':
 'VSS19': CDS_PINID='VSS19';
NODE_NAME     J6 50
 '@S9S_MB_2U_LIB.S9S_MB_2U(SCH_1):PAGE87_I175@PURE_QUANTA.SCONN288_ADR50017P087CC(CHIPS)':
 'VSS20': CDS_PINID='VSS20';
NODE_NAME     J6 52
 '@S9S_MB_2U_LIB.S9S_MB_2U(SCH_1):PAGE87_I175@PURE_QUANTA.SCONN288_ADR50017P087CC(CHIPS)':
 'VSS21': CDS_PINID='VSS21';
NODE_NAME     J6 54
 '@S9S_MB_2U_LIB.S9S_MB_2U(SCH_1):PAGE87_I175@PURE_QUANTA.SCONN288_ADR50017P087CC(CHIPS)':
 'VSS22': CDS_PINID='VSS22';
NODE_NAME     J6 57
 '@S9S_MB_2U_LIB.S9S_MB_2U(SCH_1):PAGE87_I175@PURE_QUANTA.SCONN288_ADR50017P087CC(CHIPS)':
 'VSS23': CDS_PINID='VSS23';
NODE_NAME     J6 59
 '@S9S_MB_2U_LIB.S9S_MB_2U(SCH_1):PAGE87_I175@PURE_QUANTA.SCONN288_ADR50017P087CC(CHIPS)':
 'VSS24': CDS_PINID='VSS24';
NODE_NAME     J6 61
 '@S9S_MB_2U_LIB.S9S_MB_2U(SCH_1):PAGE87_I175@PURE_QUANTA.SCONN288_ADR50017P087CC(CHIPS)':
 'VSS25': CDS_PINID='VSS25';
NODE_NAME     J6 63
 '@S9S_MB_2U_LIB.S9S_MB_2U(SCH_1):PAGE87_I175@PURE_QUANTA.SCONN288_ADR50017P087CC(CHIPS)':
 'VSS26': CDS_PINID='VSS26';
NODE_NAME     J6 65
 '@S9S_MB_2U_LIB.S9S_MB_2U(SCH_1):PAGE87_I175@PURE_QUANTA.SCONN288_ADR50017P087CC(CHIPS)':
 'VSS27': CDS_PINID='VSS27';
NODE_NAME     J6 67
 '@S9S_MB_2U_LIB.S9S_MB_2U(SCH_1):PAGE87_I175@PURE_QUANTA.SCONN288_ADR50017P087CC(CHIPS)':
 'VSS28': CDS_PINID='VSS28';
NODE_NAME     J6 69
 '@S9S_MB_2U_LIB.S9S_MB_2U(SCH_1):PAGE87_I175@PURE_QUANTA.SCONN288_ADR50017P087CC(CHIPS)':
 'VSS29': CDS_PINID='VSS29';
NODE_NAME     J6 71
 '@S9S_MB_2U_LIB.S9S_MB_2U(SCH_1):PAGE87_I175@PURE_QUANTA.SCONN288_ADR50017P087CC(CHIPS)':
 'VSS30': CDS_PINID='VSS30';
NODE_NAME     J6 73
 '@S9S_MB_2U_LIB.S9S_MB_2U(SCH_1):PAGE87_I175@PURE_QUANTA.SCONN288_ADR50017P087CC(CHIPS)':
 'VSS31': CDS_PINID='VSS31';
NODE_NAME     J6 75
 '@S9S_MB_2U_LIB.S9S_MB_2U(SCH_1):PAGE87_I175@PURE_QUANTA.SCONN288_ADR50017P087CC(CHIPS)':
 'VSS32': CDS_PINID='VSS32';
NODE_NAME     J6 77
 '@S9S_MB_2U_LIB.S9S_MB_2U(SCH_1):PAGE87_I175@PURE_QUANTA.SCONN288_ADR50017P087CC(CHIPS)':
 'VSS33': CDS_PINID='VSS33';
NODE_NAME     J6 79
 '@S9S_MB_2U_LIB.S9S_MB_2U(SCH_1):PAGE87_I175@PURE_QUANTA.SCONN288_ADR50017P087CC(CHIPS)':
 'VSS34': CDS_PINID='VSS34';
NODE_NAME     J6 81
 '@S9S_MB_2U_LIB.S9S_MB_2U(SCH_1):PAGE87_I175@PURE_QUANTA.SCONN288_ADR50017P087CC(CHIPS)':
 'VSS35': CDS_PINID='VSS35';
NODE_NAME     J6 83
 '@S9S_MB_2U_LIB.S9S_MB_2U(SCH_1):PAGE87_I175@PURE_QUANTA.SCONN288_ADR50017P087CC(CHIPS)':
 'VSS36': CDS_PINID='VSS36';
NODE_NAME     J6 85
 '@S9S_MB_2U_LIB.S9S_MB_2U(SCH_1):PAGE87_I175@PURE_QUANTA.SCONN288_ADR50017P087CC(CHIPS)':
 'VSS37': CDS_PINID='VSS37';
NODE_NAME     J6 88
 '@S9S_MB_2U_LIB.S9S_MB_2U(SCH_1):PAGE87_I175@PURE_QUANTA.SCONN288_ADR50017P087CC(CHIPS)':
 'VSS38': CDS_PINID='VSS38';
NODE_NAME     J6 90
 '@S9S_MB_2U_LIB.S9S_MB_2U(SCH_1):PAGE87_I175@PURE_QUANTA.SCONN288_ADR50017P087CC(CHIPS)':
 'VSS39': CDS_PINID='VSS39';
NODE_NAME     J6 92
 '@S9S_MB_2U_LIB.S9S_MB_2U(SCH_1):PAGE87_I175@PURE_QUANTA.SCONN288_ADR50017P087CC(CHIPS)':
 'VSS40': CDS_PINID='VSS40';
NODE_NAME     J6 95
 '@S9S_MB_2U_LIB.S9S_MB_2U(SCH_1):PAGE87_I175@PURE_QUANTA.SCONN288_ADR50017P087CC(CHIPS)':
 'VSS41': CDS_PINID='VSS41';
NODE_NAME     J6 97
 '@S9S_MB_2U_LIB.S9S_MB_2U(SCH_1):PAGE87_I175@PURE_QUANTA.SCONN288_ADR50017P087CC(CHIPS)':
 'VSS42': CDS_PINID='VSS42';
NODE_NAME     J6 99
 '@S9S_MB_2U_LIB.S9S_MB_2U(SCH_1):PAGE87_I175@PURE_QUANTA.SCONN288_ADR50017P087CC(CHIPS)':
 'VSS43': CDS_PINID='VSS43';
NODE_NAME     J6 101
 '@S9S_MB_2U_LIB.S9S_MB_2U(SCH_1):PAGE87_I175@PURE_QUANTA.SCONN288_ADR50017P087CC(CHIPS)':
 'VSS44': CDS_PINID='VSS44';
NODE_NAME     J6 103
 '@S9S_MB_2U_LIB.S9S_MB_2U(SCH_1):PAGE87_I175@PURE_QUANTA.SCONN288_ADR50017P087CC(CHIPS)':
 'VSS45': CDS_PINID='VSS45';
NODE_NAME     J6 106
 '@S9S_MB_2U_LIB.S9S_MB_2U(SCH_1):PAGE87_I175@PURE_QUANTA.SCONN288_ADR50017P087CC(CHIPS)':
 'VSS46': CDS_PINID='VSS46';
NODE_NAME     J6 108
 '@S9S_MB_2U_LIB.S9S_MB_2U(SCH_1):PAGE87_I175@PURE_QUANTA.SCONN288_ADR50017P087CC(CHIPS)':
 'VSS47': CDS_PINID='VSS47';
NODE_NAME     J6 110
 '@S9S_MB_2U_LIB.S9S_MB_2U(SCH_1):PAGE87_I175@PURE_QUANTA.SCONN288_ADR50017P087CC(CHIPS)':
 'VSS48': CDS_PINID='VSS48';
NODE_NAME     J6 112
 '@S9S_MB_2U_LIB.S9S_MB_2U(SCH_1):PAGE87_I175@PURE_QUANTA.SCONN288_ADR50017P087CC(CHIPS)':
 'VSS49': CDS_PINID='VSS49';
NODE_NAME     J6 114
 '@S9S_MB_2U_LIB.S9S_MB_2U(SCH_1):PAGE87_I175@PURE_QUANTA.SCONN288_ADR50017P087CC(CHIPS)':
 'VSS50': CDS_PINID='VSS50';
NODE_NAME     J6 117
 '@S9S_MB_2U_LIB.S9S_MB_2U(SCH_1):PAGE87_I175@PURE_QUANTA.SCONN288_ADR50017P087CC(CHIPS)':
 'VSS51': CDS_PINID='VSS51';
NODE_NAME     J6 119
 '@S9S_MB_2U_LIB.S9S_MB_2U(SCH_1):PAGE87_I175@PURE_QUANTA.SCONN288_ADR50017P087CC(CHIPS)':
 'VSS52': CDS_PINID='VSS52';
NODE_NAME     J6 121
 '@S9S_MB_2U_LIB.S9S_MB_2U(SCH_1):PAGE87_I175@PURE_QUANTA.SCONN288_ADR50017P087CC(CHIPS)':
 'VSS53': CDS_PINID='VSS53';
NODE_NAME     J6 123
 '@S9S_MB_2U_LIB.S9S_MB_2U(SCH_1):PAGE87_I175@PURE_QUANTA.SCONN288_ADR50017P087CC(CHIPS)':
 'VSS54': CDS_PINID='VSS54';
NODE_NAME     J6 125
 '@S9S_MB_2U_LIB.S9S_MB_2U(SCH_1):PAGE87_I175@PURE_QUANTA.SCONN288_ADR50017P087CC(CHIPS)':
 'VSS55': CDS_PINID='VSS55';
NODE_NAME     J6 128
 '@S9S_MB_2U_LIB.S9S_MB_2U(SCH_1):PAGE87_I175@PURE_QUANTA.SCONN288_ADR50017P087CC(CHIPS)':
 'VSS56': CDS_PINID='VSS56';
NODE_NAME     J6 130
 '@S9S_MB_2U_LIB.S9S_MB_2U(SCH_1):PAGE87_I175@PURE_QUANTA.SCONN288_ADR50017P087CC(CHIPS)':
 'VSS57': CDS_PINID='VSS57';
NODE_NAME     J6 132
 '@S9S_MB_2U_LIB.S9S_MB_2U(SCH_1):PAGE87_I175@PURE_QUANTA.SCONN288_ADR50017P087CC(CHIPS)':
 'VSS58': CDS_PINID='VSS58';
NODE_NAME     J6 134
 '@S9S_MB_2U_LIB.S9S_MB_2U(SCH_1):PAGE87_I175@PURE_QUANTA.SCONN288_ADR50017P087CC(CHIPS)':
 'VSS59': CDS_PINID='VSS59';
NODE_NAME     J6 136
 '@S9S_MB_2U_LIB.S9S_MB_2U(SCH_1):PAGE87_I175@PURE_QUANTA.SCONN288_ADR50017P087CC(CHIPS)':
 'VSS60': CDS_PINID='VSS60';
NODE_NAME     J6 139
 '@S9S_MB_2U_LIB.S9S_MB_2U(SCH_1):PAGE87_I175@PURE_QUANTA.SCONN288_ADR50017P087CC(CHIPS)':
 'VSS61': CDS_PINID='VSS61';
NODE_NAME     J6 141
 '@S9S_MB_2U_LIB.S9S_MB_2U(SCH_1):PAGE87_I175@PURE_QUANTA.SCONN288_ADR50017P087CC(CHIPS)':
 'VSS62': CDS_PINID='VSS62';
NODE_NAME     J6 143
 '@S9S_MB_2U_LIB.S9S_MB_2U(SCH_1):PAGE87_I175@PURE_QUANTA.SCONN288_ADR50017P087CC(CHIPS)':
 'VSS63': CDS_PINID='VSS63';
NODE_NAME     J6 151
 '@S9S_MB_2U_LIB.S9S_MB_2U(SCH_1):PAGE87_I175@PURE_QUANTA.SCONN288_ADR50017P087CC(CHIPS)':
 'VSS64': CDS_PINID='VSS64';
NODE_NAME     J6 153
 '@S9S_MB_2U_LIB.S9S_MB_2U(SCH_1):PAGE87_I175@PURE_QUANTA.SCONN288_ADR50017P087CC(CHIPS)':
 'VSS65': CDS_PINID='VSS65';
NODE_NAME     J6 155
 '@S9S_MB_2U_LIB.S9S_MB_2U(SCH_1):PAGE87_I175@PURE_QUANTA.SCONN288_ADR50017P087CC(CHIPS)':
 'VSS66': CDS_PINID='VSS66';
NODE_NAME     J6 158
 '@S9S_MB_2U_LIB.S9S_MB_2U(SCH_1):PAGE87_I175@PURE_QUANTA.SCONN288_ADR50017P087CC(CHIPS)':
 'VSS67': CDS_PINID='VSS67';
NODE_NAME     J6 160
 '@S9S_MB_2U_LIB.S9S_MB_2U(SCH_1):PAGE87_I175@PURE_QUANTA.SCONN288_ADR50017P087CC(CHIPS)':
 'VSS68': CDS_PINID='VSS68';
NODE_NAME     J6 162
 '@S9S_MB_2U_LIB.S9S_MB_2U(SCH_1):PAGE87_I175@PURE_QUANTA.SCONN288_ADR50017P087CC(CHIPS)':
 'VSS69': CDS_PINID='VSS69';
NODE_NAME     J6 164
 '@S9S_MB_2U_LIB.S9S_MB_2U(SCH_1):PAGE87_I175@PURE_QUANTA.SCONN288_ADR50017P087CC(CHIPS)':
 'VSS70': CDS_PINID='VSS70';
NODE_NAME     J6 166
 '@S9S_MB_2U_LIB.S9S_MB_2U(SCH_1):PAGE87_I175@PURE_QUANTA.SCONN288_ADR50017P087CC(CHIPS)':
 'VSS71': CDS_PINID='VSS71';
NODE_NAME     J6 169
 '@S9S_MB_2U_LIB.S9S_MB_2U(SCH_1):PAGE87_I175@PURE_QUANTA.SCONN288_ADR50017P087CC(CHIPS)':
 'VSS72': CDS_PINID='VSS72';
NODE_NAME     J6 171
 '@S9S_MB_2U_LIB.S9S_MB_2U(SCH_1):PAGE87_I175@PURE_QUANTA.SCONN288_ADR50017P087CC(CHIPS)':
 'VSS73': CDS_PINID='VSS73';
NODE_NAME     J6 173
 '@S9S_MB_2U_LIB.S9S_MB_2U(SCH_1):PAGE87_I175@PURE_QUANTA.SCONN288_ADR50017P087CC(CHIPS)':
 'VSS74': CDS_PINID='VSS74';
NODE_NAME     J6 175
 '@S9S_MB_2U_LIB.S9S_MB_2U(SCH_1):PAGE87_I175@PURE_QUANTA.SCONN288_ADR50017P087CC(CHIPS)':
 'VSS75': CDS_PINID='VSS75';
NODE_NAME     J6 177
 '@S9S_MB_2U_LIB.S9S_MB_2U(SCH_1):PAGE87_I175@PURE_QUANTA.SCONN288_ADR50017P087CC(CHIPS)':
 'VSS76': CDS_PINID='VSS76';
NODE_NAME     J6 180
 '@S9S_MB_2U_LIB.S9S_MB_2U(SCH_1):PAGE87_I175@PURE_QUANTA.SCONN288_ADR50017P087CC(CHIPS)':
 'VSS77': CDS_PINID='VSS77';
NODE_NAME     J6 182
 '@S9S_MB_2U_LIB.S9S_MB_2U(SCH_1):PAGE87_I175@PURE_QUANTA.SCONN288_ADR50017P087CC(CHIPS)':
 'VSS78': CDS_PINID='VSS78';
NODE_NAME     J6 184
 '@S9S_MB_2U_LIB.S9S_MB_2U(SCH_1):PAGE87_I175@PURE_QUANTA.SCONN288_ADR50017P087CC(CHIPS)':
 'VSS79': CDS_PINID='VSS79';
NODE_NAME     J6 186
 '@S9S_MB_2U_LIB.S9S_MB_2U(SCH_1):PAGE87_I175@PURE_QUANTA.SCONN288_ADR50017P087CC(CHIPS)':
 'VSS80': CDS_PINID='VSS80';
NODE_NAME     J6 188
 '@S9S_MB_2U_LIB.S9S_MB_2U(SCH_1):PAGE87_I175@PURE_QUANTA.SCONN288_ADR50017P087CC(CHIPS)':
 'VSS81': CDS_PINID='VSS81';
NODE_NAME     J6 191
 '@S9S_MB_2U_LIB.S9S_MB_2U(SCH_1):PAGE87_I175@PURE_QUANTA.SCONN288_ADR50017P087CC(CHIPS)':
 'VSS82': CDS_PINID='VSS82';
NODE_NAME     J6 193
 '@S9S_MB_2U_LIB.S9S_MB_2U(SCH_1):PAGE87_I175@PURE_QUANTA.SCONN288_ADR50017P087CC(CHIPS)':
 'VSS83': CDS_PINID='VSS83';
NODE_NAME     J6 195
 '@S9S_MB_2U_LIB.S9S_MB_2U(SCH_1):PAGE87_I175@PURE_QUANTA.SCONN288_ADR50017P087CC(CHIPS)':
 'VSS84': CDS_PINID='VSS84';
NODE_NAME     J6 197
 '@S9S_MB_2U_LIB.S9S_MB_2U(SCH_1):PAGE87_I175@PURE_QUANTA.SCONN288_ADR50017P087CC(CHIPS)':
 'VSS85': CDS_PINID='VSS85';
NODE_NAME     J6 199
 '@S9S_MB_2U_LIB.S9S_MB_2U(SCH_1):PAGE87_I175@PURE_QUANTA.SCONN288_ADR50017P087CC(CHIPS)':
 'VSS86': CDS_PINID='VSS86';
NODE_NAME     J6 202
 '@S9S_MB_2U_LIB.S9S_MB_2U(SCH_1):PAGE87_I175@PURE_QUANTA.SCONN288_ADR50017P087CC(CHIPS)':
 'VSS87': CDS_PINID='VSS87';
NODE_NAME     J6 204
 '@S9S_MB_2U_LIB.S9S_MB_2U(SCH_1):PAGE87_I175@PURE_QUANTA.SCONN288_ADR50017P087CC(CHIPS)':
 'VSS88': CDS_PINID='VSS88';
NODE_NAME     J6 206
 '@S9S_MB_2U_LIB.S9S_MB_2U(SCH_1):PAGE87_I175@PURE_QUANTA.SCONN288_ADR50017P087CC(CHIPS)':
 'VSS89': CDS_PINID='VSS89';
NODE_NAME     J6 208
 '@S9S_MB_2U_LIB.S9S_MB_2U(SCH_1):PAGE87_I175@PURE_QUANTA.SCONN288_ADR50017P087CC(CHIPS)':
 'VSS90': CDS_PINID='VSS90';
NODE_NAME     J6 210
 '@S9S_MB_2U_LIB.S9S_MB_2U(SCH_1):PAGE87_I175@PURE_QUANTA.SCONN288_ADR50017P087CC(CHIPS)':
 'VSS91': CDS_PINID='VSS91';
NODE_NAME     J6 212
 '@S9S_MB_2U_LIB.S9S_MB_2U(SCH_1):PAGE87_I175@PURE_QUANTA.SCONN288_ADR50017P087CC(CHIPS)':
 'VSS92': CDS_PINID='VSS92';
NODE_NAME     J6 214
 '@S9S_MB_2U_LIB.S9S_MB_2U(SCH_1):PAGE87_I175@PURE_QUANTA.SCONN288_ADR50017P087CC(CHIPS)':
 'VSS93': CDS_PINID='VSS93';
NODE_NAME     J6 216
 '@S9S_MB_2U_LIB.S9S_MB_2U(SCH_1):PAGE87_I175@PURE_QUANTA.SCONN288_ADR50017P087CC(CHIPS)':
 'VSS94': CDS_PINID='VSS94';
NODE_NAME     J6 219
 '@S9S_MB_2U_LIB.S9S_MB_2U(SCH_1):PAGE87_I175@PURE_QUANTA.SCONN288_ADR50017P087CC(CHIPS)':
 'VSS95': CDS_PINID='VSS95';
NODE_NAME     J6 222
 '@S9S_MB_2U_LIB.S9S_MB_2U(SCH_1):PAGE87_I175@PURE_QUANTA.SCONN288_ADR50017P087CC(CHIPS)':
 'VSS96': CDS_PINID='VSS96';
NODE_NAME     J6 224
 '@S9S_MB_2U_LIB.S9S_MB_2U(SCH_1):PAGE87_I175@PURE_QUANTA.SCONN288_ADR50017P087CC(CHIPS)':
 'VSS97': CDS_PINID='VSS97';
NODE_NAME     J6 226
 '@S9S_MB_2U_LIB.S9S_MB_2U(SCH_1):PAGE87_I175@PURE_QUANTA.SCONN288_ADR50017P087CC(CHIPS)':
 'VSS98': CDS_PINID='VSS98';
NODE_NAME     J6 228
 '@S9S_MB_2U_LIB.S9S_MB_2U(SCH_1):PAGE87_I175@PURE_QUANTA.SCONN288_ADR50017P087CC(CHIPS)':
 'VSS99': CDS_PINID='VSS99';
NODE_NAME     J6 230
 '@S9S_MB_2U_LIB.S9S_MB_2U(SCH_1):PAGE87_I175@PURE_QUANTA.SCONN288_ADR50017P087CC(CHIPS)':
 'VSS100': CDS_PINID='VSS100';
NODE_NAME     J6 233
 '@S9S_MB_2U_LIB.S9S_MB_2U(SCH_1):PAGE87_I175@PURE_QUANTA.SCONN288_ADR50017P087CC(CHIPS)':
 'VSS101': CDS_PINID='VSS101';
NODE_NAME     J6 235
 '@S9S_MB_2U_LIB.S9S_MB_2U(SCH_1):PAGE87_I175@PURE_QUANTA.SCONN288_ADR50017P087CC(CHIPS)':
 'VSS102': CDS_PINID='VSS102';
NODE_NAME     J6 237
 '@S9S_MB_2U_LIB.S9S_MB_2U(SCH_1):PAGE87_I175@PURE_QUANTA.SCONN288_ADR50017P087CC(CHIPS)':
 'VSS103': CDS_PINID='VSS103';
NODE_NAME     J6 240
 '@S9S_MB_2U_LIB.S9S_MB_2U(SCH_1):PAGE87_I175@PURE_QUANTA.SCONN288_ADR50017P087CC(CHIPS)':
 'VSS104': CDS_PINID='VSS104';
NODE_NAME     J6 242
 '@S9S_MB_2U_LIB.S9S_MB_2U(SCH_1):PAGE87_I175@PURE_QUANTA.SCONN288_ADR50017P087CC(CHIPS)':
 'VSS105': CDS_PINID='VSS105';
NODE_NAME     J6 244
 '@S9S_MB_2U_LIB.S9S_MB_2U(SCH_1):PAGE87_I175@PURE_QUANTA.SCONN288_ADR50017P087CC(CHIPS)':
 'VSS106': CDS_PINID='VSS106';
NODE_NAME     J6 246
 '@S9S_MB_2U_LIB.S9S_MB_2U(SCH_1):PAGE87_I175@PURE_QUANTA.SCONN288_ADR50017P087CC(CHIPS)':
 'VSS107': CDS_PINID='VSS107';
NODE_NAME     J6 248
 '@S9S_MB_2U_LIB.S9S_MB_2U(SCH_1):PAGE87_I175@PURE_QUANTA.SCONN288_ADR50017P087CC(CHIPS)':
 'VSS108': CDS_PINID='VSS108';
NODE_NAME     J6 251
 '@S9S_MB_2U_LIB.S9S_MB_2U(SCH_1):PAGE87_I175@PURE_QUANTA.SCONN288_ADR50017P087CC(CHIPS)':
 'VSS109': CDS_PINID='VSS109';
NODE_NAME     J6 253
 '@S9S_MB_2U_LIB.S9S_MB_2U(SCH_1):PAGE87_I175@PURE_QUANTA.SCONN288_ADR50017P087CC(CHIPS)':
 'VSS110': CDS_PINID='VSS110';
NODE_NAME     J6 255
 '@S9S_MB_2U_LIB.S9S_MB_2U(SCH_1):PAGE87_I175@PURE_QUANTA.SCONN288_ADR50017P087CC(CHIPS)':
 'VSS111': CDS_PINID='VSS111';
NODE_NAME     J6 257
 '@S9S_MB_2U_LIB.S9S_MB_2U(SCH_1):PAGE87_I175@PURE_QUANTA.SCONN288_ADR50017P087CC(CHIPS)':
 'VSS112': CDS_PINID='VSS112';
NODE_NAME     J6 259
 '@S9S_MB_2U_LIB.S9S_MB_2U(SCH_1):PAGE87_I175@PURE_QUANTA.SCONN288_ADR50017P087CC(CHIPS)':
 'VSS113': CDS_PINID='VSS113';
NODE_NAME     J6 262
 '@S9S_MB_2U_LIB.S9S_MB_2U(SCH_1):PAGE87_I175@PURE_QUANTA.SCONN288_ADR50017P087CC(CHIPS)':
 'VSS114': CDS_PINID='VSS114';
NODE_NAME     J6 264
 '@S9S_MB_2U_LIB.S9S_MB_2U(SCH_1):PAGE87_I175@PURE_QUANTA.SCONN288_ADR50017P087CC(CHIPS)':
 'VSS115': CDS_PINID='VSS115';
NODE_NAME     J6 266
 '@S9S_MB_2U_LIB.S9S_MB_2U(SCH_1):PAGE87_I175@PURE_QUANTA.SCONN288_ADR50017P087CC(CHIPS)':
 'VSS116': CDS_PINID='VSS116';
NODE_NAME     J6 268
 '@S9S_MB_2U_LIB.S9S_MB_2U(SCH_1):PAGE87_I175@PURE_QUANTA.SCONN288_ADR50017P087CC(CHIPS)':
 'VSS117': CDS_PINID='VSS117';
NODE_NAME     J6 270
 '@S9S_MB_2U_LIB.S9S_MB_2U(SCH_1):PAGE87_I175@PURE_QUANTA.SCONN288_ADR50017P087CC(CHIPS)':
 'VSS118': CDS_PINID='VSS118';
NODE_NAME     J6 273
 '@S9S_MB_2U_LIB.S9S_MB_2U(SCH_1):PAGE87_I175@PURE_QUANTA.SCONN288_ADR50017P087CC(CHIPS)':
 'VSS119': CDS_PINID='VSS119';
NODE_NAME     J6 275
 '@S9S_MB_2U_LIB.S9S_MB_2U(SCH_1):PAGE87_I175@PURE_QUANTA.SCONN288_ADR50017P087CC(CHIPS)':
 'VSS120': CDS_PINID='VSS120';
NODE_NAME     J6 277
 '@S9S_MB_2U_LIB.S9S_MB_2U(SCH_1):PAGE87_I175@PURE_QUANTA.SCONN288_ADR50017P087CC(CHIPS)':
 'VSS121': CDS_PINID='VSS121';
NODE_NAME     J6 279
 '@S9S_MB_2U_LIB.S9S_MB_2U(SCH_1):PAGE87_I175@PURE_QUANTA.SCONN288_ADR50017P087CC(CHIPS)':
 'VSS122': CDS_PINID='VSS122';
NODE_NAME     J6 281
 '@S9S_MB_2U_LIB.S9S_MB_2U(SCH_1):PAGE87_I175@PURE_QUANTA.SCONN288_ADR50017P087CC(CHIPS)':
 'VSS123': CDS_PINID='VSS123';
NODE_NAME     J6 284
 '@S9S_MB_2U_LIB.S9S_MB_2U(SCH_1):PAGE87_I175@PURE_QUANTA.SCONN288_ADR50017P087CC(CHIPS)':
 'VSS124': CDS_PINID='VSS124';
NODE_NAME     J6 286
 '@S9S_MB_2U_LIB.S9S_MB_2U(SCH_1):PAGE87_I175@PURE_QUANTA.SCONN288_ADR50017P087CC(CHIPS)':
 'VSS125': CDS_PINID='VSS125';
NODE_NAME     J6 288
 '@S9S_MB_2U_LIB.S9S_MB_2U(SCH_1):PAGE87_I175@PURE_QUANTA.SCONN288_ADR50017P087CC(CHIPS)':
 'VSS126': CDS_PINID='VSS126';
NODE_NAME     R32 2
 '@S9S_MB_2U_LIB.S9S_MB_2U(SCH_1):PAGE88_I2@PURE_QUANTA.Q_RES(CHIPS)':
 'B': CDS_PINID='B';
NODE_NAME     C20 2
 '@S9S_MB_2U_LIB.S9S_MB_2U(SCH_1):PAGE88_I123@PURE_QUANTA.Q_CAP(CHIPS)':
 'B': CDS_PINID='B';
NODE_NAME     C21 2
 '@S9S_MB_2U_LIB.S9S_MB_2U(SCH_1):PAGE88_I126@PURE_QUANTA.Q_CAP(CHIPS)':
 'B': CDS_PINID='B';
NODE_NAME     C22 2
 '@S9S_MB_2U_LIB.S9S_MB_2U(SCH_1):PAGE88_I166@PURE_QUANTA.Q_CAP(CHIPS)':
 'B': CDS_PINID='B';
NODE_NAME     J7 G1
 '@S9S_MB_2U_LIB.S9S_MB_2U(SCH_1):PAGE88_I168@PURE_QUANTA.SCONN288_ADR50017P130CC(CHIPS)':
 'G1': CDS_PINID='G1';
NODE_NAME     J7 G2
 '@S9S_MB_2U_LIB.S9S_MB_2U(SCH_1):PAGE88_I168@PURE_QUANTA.SCONN288_ADR50017P130CC(CHIPS)':
 'G2': CDS_PINID='G2';
NODE_NAME     J7 G3
 '@S9S_MB_2U_LIB.S9S_MB_2U(SCH_1):PAGE88_I168@PURE_QUANTA.SCONN288_ADR50017P130CC(CHIPS)':
 'G3': CDS_PINID='G3';
NODE_NAME     J7 6
 '@S9S_MB_2U_LIB.S9S_MB_2U(SCH_1):PAGE88_I168@PURE_QUANTA.SCONN288_ADR50017P130CC(CHIPS)':
 'VSS0': CDS_PINID='VSS0';
NODE_NAME     J7 8
 '@S9S_MB_2U_LIB.S9S_MB_2U(SCH_1):PAGE88_I168@PURE_QUANTA.SCONN288_ADR50017P130CC(CHIPS)':
 'VSS1': CDS_PINID='VSS1';
NODE_NAME     J7 10
 '@S9S_MB_2U_LIB.S9S_MB_2U(SCH_1):PAGE88_I168@PURE_QUANTA.SCONN288_ADR50017P130CC(CHIPS)':
 'VSS2': CDS_PINID='VSS2';
NODE_NAME     J7 13
 '@S9S_MB_2U_LIB.S9S_MB_2U(SCH_1):PAGE88_I168@PURE_QUANTA.SCONN288_ADR50017P130CC(CHIPS)':
 'VSS3': CDS_PINID='VSS3';
NODE_NAME     J7 15
 '@S9S_MB_2U_LIB.S9S_MB_2U(SCH_1):PAGE88_I168@PURE_QUANTA.SCONN288_ADR50017P130CC(CHIPS)':
 'VSS4': CDS_PINID='VSS4';
NODE_NAME     J7 17
 '@S9S_MB_2U_LIB.S9S_MB_2U(SCH_1):PAGE88_I168@PURE_QUANTA.SCONN288_ADR50017P130CC(CHIPS)':
 'VSS5': CDS_PINID='VSS5';
NODE_NAME     J7 19
 '@S9S_MB_2U_LIB.S9S_MB_2U(SCH_1):PAGE88_I168@PURE_QUANTA.SCONN288_ADR50017P130CC(CHIPS)':
 'VSS6': CDS_PINID='VSS6';
NODE_NAME     J7 21
 '@S9S_MB_2U_LIB.S9S_MB_2U(SCH_1):PAGE88_I168@PURE_QUANTA.SCONN288_ADR50017P130CC(CHIPS)':
 'VSS7': CDS_PINID='VSS7';
NODE_NAME     J7 24
 '@S9S_MB_2U_LIB.S9S_MB_2U(SCH_1):PAGE88_I168@PURE_QUANTA.SCONN288_ADR50017P130CC(CHIPS)':
 'VSS8': CDS_PINID='VSS8';
NODE_NAME     J7 26
 '@S9S_MB_2U_LIB.S9S_MB_2U(SCH_1):PAGE88_I168@PURE_QUANTA.SCONN288_ADR50017P130CC(CHIPS)':
 'VSS9': CDS_PINID='VSS9';
NODE_NAME     J7 28
 '@S9S_MB_2U_LIB.S9S_MB_2U(SCH_1):PAGE88_I168@PURE_QUANTA.SCONN288_ADR50017P130CC(CHIPS)':
 'VSS10': CDS_PINID='VSS10';
NODE_NAME     J7 30
 '@S9S_MB_2U_LIB.S9S_MB_2U(SCH_1):PAGE88_I168@PURE_QUANTA.SCONN288_ADR50017P130CC(CHIPS)':
 'VSS11': CDS_PINID='VSS11';
NODE_NAME     J7 32
 '@S9S_MB_2U_LIB.S9S_MB_2U(SCH_1):PAGE88_I168@PURE_QUANTA.SCONN288_ADR50017P130CC(CHIPS)':
 'VSS12': CDS_PINID='VSS12';
NODE_NAME     J7 35
 '@S9S_MB_2U_LIB.S9S_MB_2U(SCH_1):PAGE88_I168@PURE_QUANTA.SCONN288_ADR50017P130CC(CHIPS)':
 'VSS13': CDS_PINID='VSS13';
NODE_NAME     J7 37
 '@S9S_MB_2U_LIB.S9S_MB_2U(SCH_1):PAGE88_I168@PURE_QUANTA.SCONN288_ADR50017P130CC(CHIPS)':
 'VSS14': CDS_PINID='VSS14';
NODE_NAME     J7 39
 '@S9S_MB_2U_LIB.S9S_MB_2U(SCH_1):PAGE88_I168@PURE_QUANTA.SCONN288_ADR50017P130CC(CHIPS)':
 'VSS15': CDS_PINID='VSS15';
NODE_NAME     J7 41
 '@S9S_MB_2U_LIB.S9S_MB_2U(SCH_1):PAGE88_I168@PURE_QUANTA.SCONN288_ADR50017P130CC(CHIPS)':
 'VSS16': CDS_PINID='VSS16';
NODE_NAME     J7 43
 '@S9S_MB_2U_LIB.S9S_MB_2U(SCH_1):PAGE88_I168@PURE_QUANTA.SCONN288_ADR50017P130CC(CHIPS)':
 'VSS17': CDS_PINID='VSS17';
NODE_NAME     J7 46
 '@S9S_MB_2U_LIB.S9S_MB_2U(SCH_1):PAGE88_I168@PURE_QUANTA.SCONN288_ADR50017P130CC(CHIPS)':
 'VSS18': CDS_PINID='VSS18';
NODE_NAME     J7 48
 '@S9S_MB_2U_LIB.S9S_MB_2U(SCH_1):PAGE88_I168@PURE_QUANTA.SCONN288_ADR50017P130CC(CHIPS)':
 'VSS19': CDS_PINID='VSS19';
NODE_NAME     J7 50
 '@S9S_MB_2U_LIB.S9S_MB_2U(SCH_1):PAGE88_I168@PURE_QUANTA.SCONN288_ADR50017P130CC(CHIPS)':
 'VSS20': CDS_PINID='VSS20';
NODE_NAME     J7 52
 '@S9S_MB_2U_LIB.S9S_MB_2U(SCH_1):PAGE88_I168@PURE_QUANTA.SCONN288_ADR50017P130CC(CHIPS)':
 'VSS21': CDS_PINID='VSS21';
NODE_NAME     J7 54
 '@S9S_MB_2U_LIB.S9S_MB_2U(SCH_1):PAGE88_I168@PURE_QUANTA.SCONN288_ADR50017P130CC(CHIPS)':
 'VSS22': CDS_PINID='VSS22';
NODE_NAME     J7 57
 '@S9S_MB_2U_LIB.S9S_MB_2U(SCH_1):PAGE88_I168@PURE_QUANTA.SCONN288_ADR50017P130CC(CHIPS)':
 'VSS23': CDS_PINID='VSS23';
NODE_NAME     J7 59
 '@S9S_MB_2U_LIB.S9S_MB_2U(SCH_1):PAGE88_I168@PURE_QUANTA.SCONN288_ADR50017P130CC(CHIPS)':
 'VSS24': CDS_PINID='VSS24';
NODE_NAME     J7 61
 '@S9S_MB_2U_LIB.S9S_MB_2U(SCH_1):PAGE88_I168@PURE_QUANTA.SCONN288_ADR50017P130CC(CHIPS)':
 'VSS25': CDS_PINID='VSS25';
NODE_NAME     J7 63
 '@S9S_MB_2U_LIB.S9S_MB_2U(SCH_1):PAGE88_I168@PURE_QUANTA.SCONN288_ADR50017P130CC(CHIPS)':
 'VSS26': CDS_PINID='VSS26';
NODE_NAME     J7 65
 '@S9S_MB_2U_LIB.S9S_MB_2U(SCH_1):PAGE88_I168@PURE_QUANTA.SCONN288_ADR50017P130CC(CHIPS)':
 'VSS27': CDS_PINID='VSS27';
NODE_NAME     J7 67
 '@S9S_MB_2U_LIB.S9S_MB_2U(SCH_1):PAGE88_I168@PURE_QUANTA.SCONN288_ADR50017P130CC(CHIPS)':
 'VSS28': CDS_PINID='VSS28';
NODE_NAME     J7 69
 '@S9S_MB_2U_LIB.S9S_MB_2U(SCH_1):PAGE88_I168@PURE_QUANTA.SCONN288_ADR50017P130CC(CHIPS)':
 'VSS29': CDS_PINID='VSS29';
NODE_NAME     J7 71
 '@S9S_MB_2U_LIB.S9S_MB_2U(SCH_1):PAGE88_I168@PURE_QUANTA.SCONN288_ADR50017P130CC(CHIPS)':
 'VSS30': CDS_PINID='VSS30';
NODE_NAME     J7 73
 '@S9S_MB_2U_LIB.S9S_MB_2U(SCH_1):PAGE88_I168@PURE_QUANTA.SCONN288_ADR50017P130CC(CHIPS)':
 'VSS31': CDS_PINID='VSS31';
NODE_NAME     J7 75
 '@S9S_MB_2U_LIB.S9S_MB_2U(SCH_1):PAGE88_I168@PURE_QUANTA.SCONN288_ADR50017P130CC(CHIPS)':
 'VSS32': CDS_PINID='VSS32';
NODE_NAME     J7 77
 '@S9S_MB_2U_LIB.S9S_MB_2U(SCH_1):PAGE88_I168@PURE_QUANTA.SCONN288_ADR50017P130CC(CHIPS)':
 'VSS33': CDS_PINID='VSS33';
NODE_NAME     J7 79
 '@S9S_MB_2U_LIB.S9S_MB_2U(SCH_1):PAGE88_I168@PURE_QUANTA.SCONN288_ADR50017P130CC(CHIPS)':
 'VSS34': CDS_PINID='VSS34';
NODE_NAME     J7 81
 '@S9S_MB_2U_LIB.S9S_MB_2U(SCH_1):PAGE88_I168@PURE_QUANTA.SCONN288_ADR50017P130CC(CHIPS)':
 'VSS35': CDS_PINID='VSS35';
NODE_NAME     J7 83
 '@S9S_MB_2U_LIB.S9S_MB_2U(SCH_1):PAGE88_I168@PURE_QUANTA.SCONN288_ADR50017P130CC(CHIPS)':
 'VSS36': CDS_PINID='VSS36';
NODE_NAME     J7 85
 '@S9S_MB_2U_LIB.S9S_MB_2U(SCH_1):PAGE88_I168@PURE_QUANTA.SCONN288_ADR50017P130CC(CHIPS)':
 'VSS37': CDS_PINID='VSS37';
NODE_NAME     J7 88
 '@S9S_MB_2U_LIB.S9S_MB_2U(SCH_1):PAGE88_I168@PURE_QUANTA.SCONN288_ADR50017P130CC(CHIPS)':
 'VSS38': CDS_PINID='VSS38';
NODE_NAME     J7 90
 '@S9S_MB_2U_LIB.S9S_MB_2U(SCH_1):PAGE88_I168@PURE_QUANTA.SCONN288_ADR50017P130CC(CHIPS)':
 'VSS39': CDS_PINID='VSS39';
NODE_NAME     J7 92
 '@S9S_MB_2U_LIB.S9S_MB_2U(SCH_1):PAGE88_I168@PURE_QUANTA.SCONN288_ADR50017P130CC(CHIPS)':
 'VSS40': CDS_PINID='VSS40';
NODE_NAME     J7 95
 '@S9S_MB_2U_LIB.S9S_MB_2U(SCH_1):PAGE88_I168@PURE_QUANTA.SCONN288_ADR50017P130CC(CHIPS)':
 'VSS41': CDS_PINID='VSS41';
NODE_NAME     J7 97
 '@S9S_MB_2U_LIB.S9S_MB_2U(SCH_1):PAGE88_I168@PURE_QUANTA.SCONN288_ADR50017P130CC(CHIPS)':
 'VSS42': CDS_PINID='VSS42';
NODE_NAME     J7 99
 '@S9S_MB_2U_LIB.S9S_MB_2U(SCH_1):PAGE88_I168@PURE_QUANTA.SCONN288_ADR50017P130CC(CHIPS)':
 'VSS43': CDS_PINID='VSS43';
NODE_NAME     J7 101
 '@S9S_MB_2U_LIB.S9S_MB_2U(SCH_1):PAGE88_I168@PURE_QUANTA.SCONN288_ADR50017P130CC(CHIPS)':
 'VSS44': CDS_PINID='VSS44';
NODE_NAME     J7 103
 '@S9S_MB_2U_LIB.S9S_MB_2U(SCH_1):PAGE88_I168@PURE_QUANTA.SCONN288_ADR50017P130CC(CHIPS)':
 'VSS45': CDS_PINID='VSS45';
NODE_NAME     J7 106
 '@S9S_MB_2U_LIB.S9S_MB_2U(SCH_1):PAGE88_I168@PURE_QUANTA.SCONN288_ADR50017P130CC(CHIPS)':
 'VSS46': CDS_PINID='VSS46';
NODE_NAME     J7 108
 '@S9S_MB_2U_LIB.S9S_MB_2U(SCH_1):PAGE88_I168@PURE_QUANTA.SCONN288_ADR50017P130CC(CHIPS)':
 'VSS47': CDS_PINID='VSS47';
NODE_NAME     J7 110
 '@S9S_MB_2U_LIB.S9S_MB_2U(SCH_1):PAGE88_I168@PURE_QUANTA.SCONN288_ADR50017P130CC(CHIPS)':
 'VSS48': CDS_PINID='VSS48';
NODE_NAME     J7 112
 '@S9S_MB_2U_LIB.S9S_MB_2U(SCH_1):PAGE88_I168@PURE_QUANTA.SCONN288_ADR50017P130CC(CHIPS)':
 'VSS49': CDS_PINID='VSS49';
NODE_NAME     J7 114
 '@S9S_MB_2U_LIB.S9S_MB_2U(SCH_1):PAGE88_I168@PURE_QUANTA.SCONN288_ADR50017P130CC(CHIPS)':
 'VSS50': CDS_PINID='VSS50';
NODE_NAME     J7 117
 '@S9S_MB_2U_LIB.S9S_MB_2U(SCH_1):PAGE88_I168@PURE_QUANTA.SCONN288_ADR50017P130CC(CHIPS)':
 'VSS51': CDS_PINID='VSS51';
NODE_NAME     J7 119
 '@S9S_MB_2U_LIB.S9S_MB_2U(SCH_1):PAGE88_I168@PURE_QUANTA.SCONN288_ADR50017P130CC(CHIPS)':
 'VSS52': CDS_PINID='VSS52';
NODE_NAME     J7 121
 '@S9S_MB_2U_LIB.S9S_MB_2U(SCH_1):PAGE88_I168@PURE_QUANTA.SCONN288_ADR50017P130CC(CHIPS)':
 'VSS53': CDS_PINID='VSS53';
NODE_NAME     J7 123
 '@S9S_MB_2U_LIB.S9S_MB_2U(SCH_1):PAGE88_I168@PURE_QUANTA.SCONN288_ADR50017P130CC(CHIPS)':
 'VSS54': CDS_PINID='VSS54';
NODE_NAME     J7 125
 '@S9S_MB_2U_LIB.S9S_MB_2U(SCH_1):PAGE88_I168@PURE_QUANTA.SCONN288_ADR50017P130CC(CHIPS)':
 'VSS55': CDS_PINID='VSS55';
NODE_NAME     J7 128
 '@S9S_MB_2U_LIB.S9S_MB_2U(SCH_1):PAGE88_I168@PURE_QUANTA.SCONN288_ADR50017P130CC(CHIPS)':
 'VSS56': CDS_PINID='VSS56';
NODE_NAME     J7 130
 '@S9S_MB_2U_LIB.S9S_MB_2U(SCH_1):PAGE88_I168@PURE_QUANTA.SCONN288_ADR50017P130CC(CHIPS)':
 'VSS57': CDS_PINID='VSS57';
NODE_NAME     J7 132
 '@S9S_MB_2U_LIB.S9S_MB_2U(SCH_1):PAGE88_I168@PURE_QUANTA.SCONN288_ADR50017P130CC(CHIPS)':
 'VSS58': CDS_PINID='VSS58';
NODE_NAME     J7 134
 '@S9S_MB_2U_LIB.S9S_MB_2U(SCH_1):PAGE88_I168@PURE_QUANTA.SCONN288_ADR50017P130CC(CHIPS)':
 'VSS59': CDS_PINID='VSS59';
NODE_NAME     J7 136
 '@S9S_MB_2U_LIB.S9S_MB_2U(SCH_1):PAGE88_I168@PURE_QUANTA.SCONN288_ADR50017P130CC(CHIPS)':
 'VSS60': CDS_PINID='VSS60';
NODE_NAME     J7 139
 '@S9S_MB_2U_LIB.S9S_MB_2U(SCH_1):PAGE88_I168@PURE_QUANTA.SCONN288_ADR50017P130CC(CHIPS)':
 'VSS61': CDS_PINID='VSS61';
NODE_NAME     J7 141
 '@S9S_MB_2U_LIB.S9S_MB_2U(SCH_1):PAGE88_I168@PURE_QUANTA.SCONN288_ADR50017P130CC(CHIPS)':
 'VSS62': CDS_PINID='VSS62';
NODE_NAME     J7 143
 '@S9S_MB_2U_LIB.S9S_MB_2U(SCH_1):PAGE88_I168@PURE_QUANTA.SCONN288_ADR50017P130CC(CHIPS)':
 'VSS63': CDS_PINID='VSS63';
NODE_NAME     J7 151
 '@S9S_MB_2U_LIB.S9S_MB_2U(SCH_1):PAGE88_I168@PURE_QUANTA.SCONN288_ADR50017P130CC(CHIPS)':
 'VSS64': CDS_PINID='VSS64';
NODE_NAME     J7 153
 '@S9S_MB_2U_LIB.S9S_MB_2U(SCH_1):PAGE88_I168@PURE_QUANTA.SCONN288_ADR50017P130CC(CHIPS)':
 'VSS65': CDS_PINID='VSS65';
NODE_NAME     J7 155
 '@S9S_MB_2U_LIB.S9S_MB_2U(SCH_1):PAGE88_I168@PURE_QUANTA.SCONN288_ADR50017P130CC(CHIPS)':
 'VSS66': CDS_PINID='VSS66';
NODE_NAME     J7 158
 '@S9S_MB_2U_LIB.S9S_MB_2U(SCH_1):PAGE88_I168@PURE_QUANTA.SCONN288_ADR50017P130CC(CHIPS)':
 'VSS67': CDS_PINID='VSS67';
NODE_NAME     J7 160
 '@S9S_MB_2U_LIB.S9S_MB_2U(SCH_1):PAGE88_I168@PURE_QUANTA.SCONN288_ADR50017P130CC(CHIPS)':
 'VSS68': CDS_PINID='VSS68';
NODE_NAME     J7 162
 '@S9S_MB_2U_LIB.S9S_MB_2U(SCH_1):PAGE88_I168@PURE_QUANTA.SCONN288_ADR50017P130CC(CHIPS)':
 'VSS69': CDS_PINID='VSS69';
NODE_NAME     J7 164
 '@S9S_MB_2U_LIB.S9S_MB_2U(SCH_1):PAGE88_I168@PURE_QUANTA.SCONN288_ADR50017P130CC(CHIPS)':
 'VSS70': CDS_PINID='VSS70';
NODE_NAME     J7 166
 '@S9S_MB_2U_LIB.S9S_MB_2U(SCH_1):PAGE88_I168@PURE_QUANTA.SCONN288_ADR50017P130CC(CHIPS)':
 'VSS71': CDS_PINID='VSS71';
NODE_NAME     J7 169
 '@S9S_MB_2U_LIB.S9S_MB_2U(SCH_1):PAGE88_I168@PURE_QUANTA.SCONN288_ADR50017P130CC(CHIPS)':
 'VSS72': CDS_PINID='VSS72';
NODE_NAME     J7 171
 '@S9S_MB_2U_LIB.S9S_MB_2U(SCH_1):PAGE88_I168@PURE_QUANTA.SCONN288_ADR50017P130CC(CHIPS)':
 'VSS73': CDS_PINID='VSS73';
NODE_NAME     J7 173
 '@S9S_MB_2U_LIB.S9S_MB_2U(SCH_1):PAGE88_I168@PURE_QUANTA.SCONN288_ADR50017P130CC(CHIPS)':
 'VSS74': CDS_PINID='VSS74';
NODE_NAME     J7 175
 '@S9S_MB_2U_LIB.S9S_MB_2U(SCH_1):PAGE88_I168@PURE_QUANTA.SCONN288_ADR50017P130CC(CHIPS)':
 'VSS75': CDS_PINID='VSS75';
NODE_NAME     J7 177
 '@S9S_MB_2U_LIB.S9S_MB_2U(SCH_1):PAGE88_I168@PURE_QUANTA.SCONN288_ADR50017P130CC(CHIPS)':
 'VSS76': CDS_PINID='VSS76';
NODE_NAME     J7 180
 '@S9S_MB_2U_LIB.S9S_MB_2U(SCH_1):PAGE88_I168@PURE_QUANTA.SCONN288_ADR50017P130CC(CHIPS)':
 'VSS77': CDS_PINID='VSS77';
NODE_NAME     J7 182
 '@S9S_MB_2U_LIB.S9S_MB_2U(SCH_1):PAGE88_I168@PURE_QUANTA.SCONN288_ADR50017P130CC(CHIPS)':
 'VSS78': CDS_PINID='VSS78';
NODE_NAME     J7 184
 '@S9S_MB_2U_LIB.S9S_MB_2U(SCH_1):PAGE88_I168@PURE_QUANTA.SCONN288_ADR50017P130CC(CHIPS)':
 'VSS79': CDS_PINID='VSS79';
NODE_NAME     J7 186
 '@S9S_MB_2U_LIB.S9S_MB_2U(SCH_1):PAGE88_I168@PURE_QUANTA.SCONN288_ADR50017P130CC(CHIPS)':
 'VSS80': CDS_PINID='VSS80';
NODE_NAME     J7 188
 '@S9S_MB_2U_LIB.S9S_MB_2U(SCH_1):PAGE88_I168@PURE_QUANTA.SCONN288_ADR50017P130CC(CHIPS)':
 'VSS81': CDS_PINID='VSS81';
NODE_NAME     J7 191
 '@S9S_MB_2U_LIB.S9S_MB_2U(SCH_1):PAGE88_I168@PURE_QUANTA.SCONN288_ADR50017P130CC(CHIPS)':
 'VSS82': CDS_PINID='VSS82';
NODE_NAME     J7 193
 '@S9S_MB_2U_LIB.S9S_MB_2U(SCH_1):PAGE88_I168@PURE_QUANTA.SCONN288_ADR50017P130CC(CHIPS)':
 'VSS83': CDS_PINID='VSS83';
NODE_NAME     J7 195
 '@S9S_MB_2U_LIB.S9S_MB_2U(SCH_1):PAGE88_I168@PURE_QUANTA.SCONN288_ADR50017P130CC(CHIPS)':
 'VSS84': CDS_PINID='VSS84';
NODE_NAME     J7 197
 '@S9S_MB_2U_LIB.S9S_MB_2U(SCH_1):PAGE88_I168@PURE_QUANTA.SCONN288_ADR50017P130CC(CHIPS)':
 'VSS85': CDS_PINID='VSS85';
NODE_NAME     J7 199
 '@S9S_MB_2U_LIB.S9S_MB_2U(SCH_1):PAGE88_I168@PURE_QUANTA.SCONN288_ADR50017P130CC(CHIPS)':
 'VSS86': CDS_PINID='VSS86';
NODE_NAME     J7 202
 '@S9S_MB_2U_LIB.S9S_MB_2U(SCH_1):PAGE88_I168@PURE_QUANTA.SCONN288_ADR50017P130CC(CHIPS)':
 'VSS87': CDS_PINID='VSS87';
NODE_NAME     J7 204
 '@S9S_MB_2U_LIB.S9S_MB_2U(SCH_1):PAGE88_I168@PURE_QUANTA.SCONN288_ADR50017P130CC(CHIPS)':
 'VSS88': CDS_PINID='VSS88';
NODE_NAME     J7 206
 '@S9S_MB_2U_LIB.S9S_MB_2U(SCH_1):PAGE88_I168@PURE_QUANTA.SCONN288_ADR50017P130CC(CHIPS)':
 'VSS89': CDS_PINID='VSS89';
NODE_NAME     J7 208
 '@S9S_MB_2U_LIB.S9S_MB_2U(SCH_1):PAGE88_I168@PURE_QUANTA.SCONN288_ADR50017P130CC(CHIPS)':
 'VSS90': CDS_PINID='VSS90';
NODE_NAME     J7 210
 '@S9S_MB_2U_LIB.S9S_MB_2U(SCH_1):PAGE88_I168@PURE_QUANTA.SCONN288_ADR50017P130CC(CHIPS)':
 'VSS91': CDS_PINID='VSS91';
NODE_NAME     J7 212
 '@S9S_MB_2U_LIB.S9S_MB_2U(SCH_1):PAGE88_I168@PURE_QUANTA.SCONN288_ADR50017P130CC(CHIPS)':
 'VSS92': CDS_PINID='VSS92';
NODE_NAME     J7 214
 '@S9S_MB_2U_LIB.S9S_MB_2U(SCH_1):PAGE88_I168@PURE_QUANTA.SCONN288_ADR50017P130CC(CHIPS)':
 'VSS93': CDS_PINID='VSS93';
NODE_NAME     J7 216
 '@S9S_MB_2U_LIB.S9S_MB_2U(SCH_1):PAGE88_I168@PURE_QUANTA.SCONN288_ADR50017P130CC(CHIPS)':
 'VSS94': CDS_PINID='VSS94';
NODE_NAME     J7 219
 '@S9S_MB_2U_LIB.S9S_MB_2U(SCH_1):PAGE88_I168@PURE_QUANTA.SCONN288_ADR50017P130CC(CHIPS)':
 'VSS95': CDS_PINID='VSS95';
NODE_NAME     J7 222
 '@S9S_MB_2U_LIB.S9S_MB_2U(SCH_1):PAGE88_I168@PURE_QUANTA.SCONN288_ADR50017P130CC(CHIPS)':
 'VSS96': CDS_PINID='VSS96';
NODE_NAME     J7 224
 '@S9S_MB_2U_LIB.S9S_MB_2U(SCH_1):PAGE88_I168@PURE_QUANTA.SCONN288_ADR50017P130CC(CHIPS)':
 'VSS97': CDS_PINID='VSS97';
NODE_NAME     J7 226
 '@S9S_MB_2U_LIB.S9S_MB_2U(SCH_1):PAGE88_I168@PURE_QUANTA.SCONN288_ADR50017P130CC(CHIPS)':
 'VSS98': CDS_PINID='VSS98';
NODE_NAME     J7 228
 '@S9S_MB_2U_LIB.S9S_MB_2U(SCH_1):PAGE88_I168@PURE_QUANTA.SCONN288_ADR50017P130CC(CHIPS)':
 'VSS99': CDS_PINID='VSS99';
NODE_NAME     J7 230
 '@S9S_MB_2U_LIB.S9S_MB_2U(SCH_1):PAGE88_I168@PURE_QUANTA.SCONN288_ADR50017P130CC(CHIPS)':
 'VSS100': CDS_PINID='VSS100';
NODE_NAME     J7 233
 '@S9S_MB_2U_LIB.S9S_MB_2U(SCH_1):PAGE88_I168@PURE_QUANTA.SCONN288_ADR50017P130CC(CHIPS)':
 'VSS101': CDS_PINID='VSS101';
NODE_NAME     J7 235
 '@S9S_MB_2U_LIB.S9S_MB_2U(SCH_1):PAGE88_I168@PURE_QUANTA.SCONN288_ADR50017P130CC(CHIPS)':
 'VSS102': CDS_PINID='VSS102';
NODE_NAME     J7 237
 '@S9S_MB_2U_LIB.S9S_MB_2U(SCH_1):PAGE88_I168@PURE_QUANTA.SCONN288_ADR50017P130CC(CHIPS)':
 'VSS103': CDS_PINID='VSS103';
NODE_NAME     J7 240
 '@S9S_MB_2U_LIB.S9S_MB_2U(SCH_1):PAGE88_I168@PURE_QUANTA.SCONN288_ADR50017P130CC(CHIPS)':
 'VSS104': CDS_PINID='VSS104';
NODE_NAME     J7 242
 '@S9S_MB_2U_LIB.S9S_MB_2U(SCH_1):PAGE88_I168@PURE_QUANTA.SCONN288_ADR50017P130CC(CHIPS)':
 'VSS105': CDS_PINID='VSS105';
NODE_NAME     J7 244
 '@S9S_MB_2U_LIB.S9S_MB_2U(SCH_1):PAGE88_I168@PURE_QUANTA.SCONN288_ADR50017P130CC(CHIPS)':
 'VSS106': CDS_PINID='VSS106';
NODE_NAME     J7 246
 '@S9S_MB_2U_LIB.S9S_MB_2U(SCH_1):PAGE88_I168@PURE_QUANTA.SCONN288_ADR50017P130CC(CHIPS)':
 'VSS107': CDS_PINID='VSS107';
NODE_NAME     J7 248
 '@S9S_MB_2U_LIB.S9S_MB_2U(SCH_1):PAGE88_I168@PURE_QUANTA.SCONN288_ADR50017P130CC(CHIPS)':
 'VSS108': CDS_PINID='VSS108';
NODE_NAME     J7 251
 '@S9S_MB_2U_LIB.S9S_MB_2U(SCH_1):PAGE88_I168@PURE_QUANTA.SCONN288_ADR50017P130CC(CHIPS)':
 'VSS109': CDS_PINID='VSS109';
NODE_NAME     J7 253
 '@S9S_MB_2U_LIB.S9S_MB_2U(SCH_1):PAGE88_I168@PURE_QUANTA.SCONN288_ADR50017P130CC(CHIPS)':
 'VSS110': CDS_PINID='VSS110';
NODE_NAME     J7 255
 '@S9S_MB_2U_LIB.S9S_MB_2U(SCH_1):PAGE88_I168@PURE_QUANTA.SCONN288_ADR50017P130CC(CHIPS)':
 'VSS111': CDS_PINID='VSS111';
NODE_NAME     J7 257
 '@S9S_MB_2U_LIB.S9S_MB_2U(SCH_1):PAGE88_I168@PURE_QUANTA.SCONN288_ADR50017P130CC(CHIPS)':
 'VSS112': CDS_PINID='VSS112';
NODE_NAME     J7 259
 '@S9S_MB_2U_LIB.S9S_MB_2U(SCH_1):PAGE88_I168@PURE_QUANTA.SCONN288_ADR50017P130CC(CHIPS)':
 'VSS113': CDS_PINID='VSS113';
NODE_NAME     J7 262
 '@S9S_MB_2U_LIB.S9S_MB_2U(SCH_1):PAGE88_I168@PURE_QUANTA.SCONN288_ADR50017P130CC(CHIPS)':
 'VSS114': CDS_PINID='VSS114';
NODE_NAME     J7 264
 '@S9S_MB_2U_LIB.S9S_MB_2U(SCH_1):PAGE88_I168@PURE_QUANTA.SCONN288_ADR50017P130CC(CHIPS)':
 'VSS115': CDS_PINID='VSS115';
NODE_NAME     J7 266
 '@S9S_MB_2U_LIB.S9S_MB_2U(SCH_1):PAGE88_I168@PURE_QUANTA.SCONN288_ADR50017P130CC(CHIPS)':
 'VSS116': CDS_PINID='VSS116';
NODE_NAME     J7 268
 '@S9S_MB_2U_LIB.S9S_MB_2U(SCH_1):PAGE88_I168@PURE_QUANTA.SCONN288_ADR50017P130CC(CHIPS)':
 'VSS117': CDS_PINID='VSS117';
NODE_NAME     J7 270
 '@S9S_MB_2U_LIB.S9S_MB_2U(SCH_1):PAGE88_I168@PURE_QUANTA.SCONN288_ADR50017P130CC(CHIPS)':
 'VSS118': CDS_PINID='VSS118';
NODE_NAME     J7 273
 '@S9S_MB_2U_LIB.S9S_MB_2U(SCH_1):PAGE88_I168@PURE_QUANTA.SCONN288_ADR50017P130CC(CHIPS)':
 'VSS119': CDS_PINID='VSS119';
NODE_NAME     J7 275
 '@S9S_MB_2U_LIB.S9S_MB_2U(SCH_1):PAGE88_I168@PURE_QUANTA.SCONN288_ADR50017P130CC(CHIPS)':
 'VSS120': CDS_PINID='VSS120';
NODE_NAME     J7 277
 '@S9S_MB_2U_LIB.S9S_MB_2U(SCH_1):PAGE88_I168@PURE_QUANTA.SCONN288_ADR50017P130CC(CHIPS)':
 'VSS121': CDS_PINID='VSS121';
NODE_NAME     J7 279
 '@S9S_MB_2U_LIB.S9S_MB_2U(SCH_1):PAGE88_I168@PURE_QUANTA.SCONN288_ADR50017P130CC(CHIPS)':
 'VSS122': CDS_PINID='VSS122';
NODE_NAME     J7 281
 '@S9S_MB_2U_LIB.S9S_MB_2U(SCH_1):PAGE88_I168@PURE_QUANTA.SCONN288_ADR50017P130CC(CHIPS)':
 'VSS123': CDS_PINID='VSS123';
NODE_NAME     J7 284
 '@S9S_MB_2U_LIB.S9S_MB_2U(SCH_1):PAGE88_I168@PURE_QUANTA.SCONN288_ADR50017P130CC(CHIPS)':
 'VSS124': CDS_PINID='VSS124';
NODE_NAME     J7 286
 '@S9S_MB_2U_LIB.S9S_MB_2U(SCH_1):PAGE88_I168@PURE_QUANTA.SCONN288_ADR50017P130CC(CHIPS)':
 'VSS125': CDS_PINID='VSS125';
NODE_NAME     J7 288
 '@S9S_MB_2U_LIB.S9S_MB_2U(SCH_1):PAGE88_I168@PURE_QUANTA.SCONN288_ADR50017P130CC(CHIPS)':
 'VSS126': CDS_PINID='VSS126';
NODE_NAME     R33 2
 '@S9S_MB_2U_LIB.S9S_MB_2U(SCH_1):PAGE89_I2@PURE_QUANTA.Q_RES(CHIPS)':
 'B': CDS_PINID='B';
NODE_NAME     C23 2
 '@S9S_MB_2U_LIB.S9S_MB_2U(SCH_1):PAGE89_I121@PURE_QUANTA.Q_CAP(CHIPS)':
 'B': CDS_PINID='B';
NODE_NAME     C24 2
 '@S9S_MB_2U_LIB.S9S_MB_2U(SCH_1):PAGE89_I125@PURE_QUANTA.Q_CAP(CHIPS)':
 'B': CDS_PINID='B';
NODE_NAME     C25 2
 '@S9S_MB_2U_LIB.S9S_MB_2U(SCH_1):PAGE89_I127@PURE_QUANTA.Q_CAP(CHIPS)':
 'B': CDS_PINID='B';
NODE_NAME     J8 G1
 '@S9S_MB_2U_LIB.S9S_MB_2U(SCH_1):PAGE89_I175@PURE_QUANTA.SCONN288_ADR50017P087CC(CHIPS)':
 'G1': CDS_PINID='G1';
NODE_NAME     J8 G2
 '@S9S_MB_2U_LIB.S9S_MB_2U(SCH_1):PAGE89_I175@PURE_QUANTA.SCONN288_ADR50017P087CC(CHIPS)':
 'G2': CDS_PINID='G2';
NODE_NAME     J8 G3
 '@S9S_MB_2U_LIB.S9S_MB_2U(SCH_1):PAGE89_I175@PURE_QUANTA.SCONN288_ADR50017P087CC(CHIPS)':
 'G3': CDS_PINID='G3';
NODE_NAME     J8 6
 '@S9S_MB_2U_LIB.S9S_MB_2U(SCH_1):PAGE89_I175@PURE_QUANTA.SCONN288_ADR50017P087CC(CHIPS)':
 'VSS0': CDS_PINID='VSS0';
NODE_NAME     J8 8
 '@S9S_MB_2U_LIB.S9S_MB_2U(SCH_1):PAGE89_I175@PURE_QUANTA.SCONN288_ADR50017P087CC(CHIPS)':
 'VSS1': CDS_PINID='VSS1';
NODE_NAME     J8 10
 '@S9S_MB_2U_LIB.S9S_MB_2U(SCH_1):PAGE89_I175@PURE_QUANTA.SCONN288_ADR50017P087CC(CHIPS)':
 'VSS2': CDS_PINID='VSS2';
NODE_NAME     J8 13
 '@S9S_MB_2U_LIB.S9S_MB_2U(SCH_1):PAGE89_I175@PURE_QUANTA.SCONN288_ADR50017P087CC(CHIPS)':
 'VSS3': CDS_PINID='VSS3';
NODE_NAME     J8 15
 '@S9S_MB_2U_LIB.S9S_MB_2U(SCH_1):PAGE89_I175@PURE_QUANTA.SCONN288_ADR50017P087CC(CHIPS)':
 'VSS4': CDS_PINID='VSS4';
NODE_NAME     J8 17
 '@S9S_MB_2U_LIB.S9S_MB_2U(SCH_1):PAGE89_I175@PURE_QUANTA.SCONN288_ADR50017P087CC(CHIPS)':
 'VSS5': CDS_PINID='VSS5';
NODE_NAME     J8 19
 '@S9S_MB_2U_LIB.S9S_MB_2U(SCH_1):PAGE89_I175@PURE_QUANTA.SCONN288_ADR50017P087CC(CHIPS)':
 'VSS6': CDS_PINID='VSS6';
NODE_NAME     J8 21
 '@S9S_MB_2U_LIB.S9S_MB_2U(SCH_1):PAGE89_I175@PURE_QUANTA.SCONN288_ADR50017P087CC(CHIPS)':
 'VSS7': CDS_PINID='VSS7';
NODE_NAME     J8 24
 '@S9S_MB_2U_LIB.S9S_MB_2U(SCH_1):PAGE89_I175@PURE_QUANTA.SCONN288_ADR50017P087CC(CHIPS)':
 'VSS8': CDS_PINID='VSS8';
NODE_NAME     J8 26
 '@S9S_MB_2U_LIB.S9S_MB_2U(SCH_1):PAGE89_I175@PURE_QUANTA.SCONN288_ADR50017P087CC(CHIPS)':
 'VSS9': CDS_PINID='VSS9';
NODE_NAME     J8 28
 '@S9S_MB_2U_LIB.S9S_MB_2U(SCH_1):PAGE89_I175@PURE_QUANTA.SCONN288_ADR50017P087CC(CHIPS)':
 'VSS10': CDS_PINID='VSS10';
NODE_NAME     J8 30
 '@S9S_MB_2U_LIB.S9S_MB_2U(SCH_1):PAGE89_I175@PURE_QUANTA.SCONN288_ADR50017P087CC(CHIPS)':
 'VSS11': CDS_PINID='VSS11';
NODE_NAME     J8 32
 '@S9S_MB_2U_LIB.S9S_MB_2U(SCH_1):PAGE89_I175@PURE_QUANTA.SCONN288_ADR50017P087CC(CHIPS)':
 'VSS12': CDS_PINID='VSS12';
NODE_NAME     J8 35
 '@S9S_MB_2U_LIB.S9S_MB_2U(SCH_1):PAGE89_I175@PURE_QUANTA.SCONN288_ADR50017P087CC(CHIPS)':
 'VSS13': CDS_PINID='VSS13';
NODE_NAME     J8 37
 '@S9S_MB_2U_LIB.S9S_MB_2U(SCH_1):PAGE89_I175@PURE_QUANTA.SCONN288_ADR50017P087CC(CHIPS)':
 'VSS14': CDS_PINID='VSS14';
NODE_NAME     J8 39
 '@S9S_MB_2U_LIB.S9S_MB_2U(SCH_1):PAGE89_I175@PURE_QUANTA.SCONN288_ADR50017P087CC(CHIPS)':
 'VSS15': CDS_PINID='VSS15';
NODE_NAME     J8 41
 '@S9S_MB_2U_LIB.S9S_MB_2U(SCH_1):PAGE89_I175@PURE_QUANTA.SCONN288_ADR50017P087CC(CHIPS)':
 'VSS16': CDS_PINID='VSS16';
NODE_NAME     J8 43
 '@S9S_MB_2U_LIB.S9S_MB_2U(SCH_1):PAGE89_I175@PURE_QUANTA.SCONN288_ADR50017P087CC(CHIPS)':
 'VSS17': CDS_PINID='VSS17';
NODE_NAME     J8 46
 '@S9S_MB_2U_LIB.S9S_MB_2U(SCH_1):PAGE89_I175@PURE_QUANTA.SCONN288_ADR50017P087CC(CHIPS)':
 'VSS18': CDS_PINID='VSS18';
NODE_NAME     J8 48
 '@S9S_MB_2U_LIB.S9S_MB_2U(SCH_1):PAGE89_I175@PURE_QUANTA.SCONN288_ADR50017P087CC(CHIPS)':
 'VSS19': CDS_PINID='VSS19';
NODE_NAME     J8 50
 '@S9S_MB_2U_LIB.S9S_MB_2U(SCH_1):PAGE89_I175@PURE_QUANTA.SCONN288_ADR50017P087CC(CHIPS)':
 'VSS20': CDS_PINID='VSS20';
NODE_NAME     J8 52
 '@S9S_MB_2U_LIB.S9S_MB_2U(SCH_1):PAGE89_I175@PURE_QUANTA.SCONN288_ADR50017P087CC(CHIPS)':
 'VSS21': CDS_PINID='VSS21';
NODE_NAME     J8 54
 '@S9S_MB_2U_LIB.S9S_MB_2U(SCH_1):PAGE89_I175@PURE_QUANTA.SCONN288_ADR50017P087CC(CHIPS)':
 'VSS22': CDS_PINID='VSS22';
NODE_NAME     J8 57
 '@S9S_MB_2U_LIB.S9S_MB_2U(SCH_1):PAGE89_I175@PURE_QUANTA.SCONN288_ADR50017P087CC(CHIPS)':
 'VSS23': CDS_PINID='VSS23';
NODE_NAME     J8 59
 '@S9S_MB_2U_LIB.S9S_MB_2U(SCH_1):PAGE89_I175@PURE_QUANTA.SCONN288_ADR50017P087CC(CHIPS)':
 'VSS24': CDS_PINID='VSS24';
NODE_NAME     J8 61
 '@S9S_MB_2U_LIB.S9S_MB_2U(SCH_1):PAGE89_I175@PURE_QUANTA.SCONN288_ADR50017P087CC(CHIPS)':
 'VSS25': CDS_PINID='VSS25';
NODE_NAME     J8 63
 '@S9S_MB_2U_LIB.S9S_MB_2U(SCH_1):PAGE89_I175@PURE_QUANTA.SCONN288_ADR50017P087CC(CHIPS)':
 'VSS26': CDS_PINID='VSS26';
NODE_NAME     J8 65
 '@S9S_MB_2U_LIB.S9S_MB_2U(SCH_1):PAGE89_I175@PURE_QUANTA.SCONN288_ADR50017P087CC(CHIPS)':
 'VSS27': CDS_PINID='VSS27';
NODE_NAME     J8 67
 '@S9S_MB_2U_LIB.S9S_MB_2U(SCH_1):PAGE89_I175@PURE_QUANTA.SCONN288_ADR50017P087CC(CHIPS)':
 'VSS28': CDS_PINID='VSS28';
NODE_NAME     J8 69
 '@S9S_MB_2U_LIB.S9S_MB_2U(SCH_1):PAGE89_I175@PURE_QUANTA.SCONN288_ADR50017P087CC(CHIPS)':
 'VSS29': CDS_PINID='VSS29';
NODE_NAME     J8 71
 '@S9S_MB_2U_LIB.S9S_MB_2U(SCH_1):PAGE89_I175@PURE_QUANTA.SCONN288_ADR50017P087CC(CHIPS)':
 'VSS30': CDS_PINID='VSS30';
NODE_NAME     J8 73
 '@S9S_MB_2U_LIB.S9S_MB_2U(SCH_1):PAGE89_I175@PURE_QUANTA.SCONN288_ADR50017P087CC(CHIPS)':
 'VSS31': CDS_PINID='VSS31';
NODE_NAME     J8 75
 '@S9S_MB_2U_LIB.S9S_MB_2U(SCH_1):PAGE89_I175@PURE_QUANTA.SCONN288_ADR50017P087CC(CHIPS)':
 'VSS32': CDS_PINID='VSS32';
NODE_NAME     J8 77
 '@S9S_MB_2U_LIB.S9S_MB_2U(SCH_1):PAGE89_I175@PURE_QUANTA.SCONN288_ADR50017P087CC(CHIPS)':
 'VSS33': CDS_PINID='VSS33';
NODE_NAME     J8 79
 '@S9S_MB_2U_LIB.S9S_MB_2U(SCH_1):PAGE89_I175@PURE_QUANTA.SCONN288_ADR50017P087CC(CHIPS)':
 'VSS34': CDS_PINID='VSS34';
NODE_NAME     J8 81
 '@S9S_MB_2U_LIB.S9S_MB_2U(SCH_1):PAGE89_I175@PURE_QUANTA.SCONN288_ADR50017P087CC(CHIPS)':
 'VSS35': CDS_PINID='VSS35';
NODE_NAME     J8 83
 '@S9S_MB_2U_LIB.S9S_MB_2U(SCH_1):PAGE89_I175@PURE_QUANTA.SCONN288_ADR50017P087CC(CHIPS)':
 'VSS36': CDS_PINID='VSS36';
NODE_NAME     J8 85
 '@S9S_MB_2U_LIB.S9S_MB_2U(SCH_1):PAGE89_I175@PURE_QUANTA.SCONN288_ADR50017P087CC(CHIPS)':
 'VSS37': CDS_PINID='VSS37';
NODE_NAME     J8 88
 '@S9S_MB_2U_LIB.S9S_MB_2U(SCH_1):PAGE89_I175@PURE_QUANTA.SCONN288_ADR50017P087CC(CHIPS)':
 'VSS38': CDS_PINID='VSS38';
NODE_NAME     J8 90
 '@S9S_MB_2U_LIB.S9S_MB_2U(SCH_1):PAGE89_I175@PURE_QUANTA.SCONN288_ADR50017P087CC(CHIPS)':
 'VSS39': CDS_PINID='VSS39';
NODE_NAME     J8 92
 '@S9S_MB_2U_LIB.S9S_MB_2U(SCH_1):PAGE89_I175@PURE_QUANTA.SCONN288_ADR50017P087CC(CHIPS)':
 'VSS40': CDS_PINID='VSS40';
NODE_NAME     J8 95
 '@S9S_MB_2U_LIB.S9S_MB_2U(SCH_1):PAGE89_I175@PURE_QUANTA.SCONN288_ADR50017P087CC(CHIPS)':
 'VSS41': CDS_PINID='VSS41';
NODE_NAME     J8 97
 '@S9S_MB_2U_LIB.S9S_MB_2U(SCH_1):PAGE89_I175@PURE_QUANTA.SCONN288_ADR50017P087CC(CHIPS)':
 'VSS42': CDS_PINID='VSS42';
NODE_NAME     J8 99
 '@S9S_MB_2U_LIB.S9S_MB_2U(SCH_1):PAGE89_I175@PURE_QUANTA.SCONN288_ADR50017P087CC(CHIPS)':
 'VSS43': CDS_PINID='VSS43';
NODE_NAME     J8 101
 '@S9S_MB_2U_LIB.S9S_MB_2U(SCH_1):PAGE89_I175@PURE_QUANTA.SCONN288_ADR50017P087CC(CHIPS)':
 'VSS44': CDS_PINID='VSS44';
NODE_NAME     J8 103
 '@S9S_MB_2U_LIB.S9S_MB_2U(SCH_1):PAGE89_I175@PURE_QUANTA.SCONN288_ADR50017P087CC(CHIPS)':
 'VSS45': CDS_PINID='VSS45';
NODE_NAME     J8 106
 '@S9S_MB_2U_LIB.S9S_MB_2U(SCH_1):PAGE89_I175@PURE_QUANTA.SCONN288_ADR50017P087CC(CHIPS)':
 'VSS46': CDS_PINID='VSS46';
NODE_NAME     J8 108
 '@S9S_MB_2U_LIB.S9S_MB_2U(SCH_1):PAGE89_I175@PURE_QUANTA.SCONN288_ADR50017P087CC(CHIPS)':
 'VSS47': CDS_PINID='VSS47';
NODE_NAME     J8 110
 '@S9S_MB_2U_LIB.S9S_MB_2U(SCH_1):PAGE89_I175@PURE_QUANTA.SCONN288_ADR50017P087CC(CHIPS)':
 'VSS48': CDS_PINID='VSS48';
NODE_NAME     J8 112
 '@S9S_MB_2U_LIB.S9S_MB_2U(SCH_1):PAGE89_I175@PURE_QUANTA.SCONN288_ADR50017P087CC(CHIPS)':
 'VSS49': CDS_PINID='VSS49';
NODE_NAME     J8 114
 '@S9S_MB_2U_LIB.S9S_MB_2U(SCH_1):PAGE89_I175@PURE_QUANTA.SCONN288_ADR50017P087CC(CHIPS)':
 'VSS50': CDS_PINID='VSS50';
NODE_NAME     J8 117
 '@S9S_MB_2U_LIB.S9S_MB_2U(SCH_1):PAGE89_I175@PURE_QUANTA.SCONN288_ADR50017P087CC(CHIPS)':
 'VSS51': CDS_PINID='VSS51';
NODE_NAME     J8 119
 '@S9S_MB_2U_LIB.S9S_MB_2U(SCH_1):PAGE89_I175@PURE_QUANTA.SCONN288_ADR50017P087CC(CHIPS)':
 'VSS52': CDS_PINID='VSS52';
NODE_NAME     J8 121
 '@S9S_MB_2U_LIB.S9S_MB_2U(SCH_1):PAGE89_I175@PURE_QUANTA.SCONN288_ADR50017P087CC(CHIPS)':
 'VSS53': CDS_PINID='VSS53';
NODE_NAME     J8 123
 '@S9S_MB_2U_LIB.S9S_MB_2U(SCH_1):PAGE89_I175@PURE_QUANTA.SCONN288_ADR50017P087CC(CHIPS)':
 'VSS54': CDS_PINID='VSS54';
NODE_NAME     J8 125
 '@S9S_MB_2U_LIB.S9S_MB_2U(SCH_1):PAGE89_I175@PURE_QUANTA.SCONN288_ADR50017P087CC(CHIPS)':
 'VSS55': CDS_PINID='VSS55';
NODE_NAME     J8 128
 '@S9S_MB_2U_LIB.S9S_MB_2U(SCH_1):PAGE89_I175@PURE_QUANTA.SCONN288_ADR50017P087CC(CHIPS)':
 'VSS56': CDS_PINID='VSS56';
NODE_NAME     J8 130
 '@S9S_MB_2U_LIB.S9S_MB_2U(SCH_1):PAGE89_I175@PURE_QUANTA.SCONN288_ADR50017P087CC(CHIPS)':
 'VSS57': CDS_PINID='VSS57';
NODE_NAME     J8 132
 '@S9S_MB_2U_LIB.S9S_MB_2U(SCH_1):PAGE89_I175@PURE_QUANTA.SCONN288_ADR50017P087CC(CHIPS)':
 'VSS58': CDS_PINID='VSS58';
NODE_NAME     J8 134
 '@S9S_MB_2U_LIB.S9S_MB_2U(SCH_1):PAGE89_I175@PURE_QUANTA.SCONN288_ADR50017P087CC(CHIPS)':
 'VSS59': CDS_PINID='VSS59';
NODE_NAME     J8 136
 '@S9S_MB_2U_LIB.S9S_MB_2U(SCH_1):PAGE89_I175@PURE_QUANTA.SCONN288_ADR50017P087CC(CHIPS)':
 'VSS60': CDS_PINID='VSS60';
NODE_NAME     J8 139
 '@S9S_MB_2U_LIB.S9S_MB_2U(SCH_1):PAGE89_I175@PURE_QUANTA.SCONN288_ADR50017P087CC(CHIPS)':
 'VSS61': CDS_PINID='VSS61';
NODE_NAME     J8 141
 '@S9S_MB_2U_LIB.S9S_MB_2U(SCH_1):PAGE89_I175@PURE_QUANTA.SCONN288_ADR50017P087CC(CHIPS)':
 'VSS62': CDS_PINID='VSS62';
NODE_NAME     J8 143
 '@S9S_MB_2U_LIB.S9S_MB_2U(SCH_1):PAGE89_I175@PURE_QUANTA.SCONN288_ADR50017P087CC(CHIPS)':
 'VSS63': CDS_PINID='VSS63';
NODE_NAME     J8 151
 '@S9S_MB_2U_LIB.S9S_MB_2U(SCH_1):PAGE89_I175@PURE_QUANTA.SCONN288_ADR50017P087CC(CHIPS)':
 'VSS64': CDS_PINID='VSS64';
NODE_NAME     J8 153
 '@S9S_MB_2U_LIB.S9S_MB_2U(SCH_1):PAGE89_I175@PURE_QUANTA.SCONN288_ADR50017P087CC(CHIPS)':
 'VSS65': CDS_PINID='VSS65';
NODE_NAME     J8 155
 '@S9S_MB_2U_LIB.S9S_MB_2U(SCH_1):PAGE89_I175@PURE_QUANTA.SCONN288_ADR50017P087CC(CHIPS)':
 'VSS66': CDS_PINID='VSS66';
NODE_NAME     J8 158
 '@S9S_MB_2U_LIB.S9S_MB_2U(SCH_1):PAGE89_I175@PURE_QUANTA.SCONN288_ADR50017P087CC(CHIPS)':
 'VSS67': CDS_PINID='VSS67';
NODE_NAME     J8 160
 '@S9S_MB_2U_LIB.S9S_MB_2U(SCH_1):PAGE89_I175@PURE_QUANTA.SCONN288_ADR50017P087CC(CHIPS)':
 'VSS68': CDS_PINID='VSS68';
NODE_NAME     J8 162
 '@S9S_MB_2U_LIB.S9S_MB_2U(SCH_1):PAGE89_I175@PURE_QUANTA.SCONN288_ADR50017P087CC(CHIPS)':
 'VSS69': CDS_PINID='VSS69';
NODE_NAME     J8 164
 '@S9S_MB_2U_LIB.S9S_MB_2U(SCH_1):PAGE89_I175@PURE_QUANTA.SCONN288_ADR50017P087CC(CHIPS)':
 'VSS70': CDS_PINID='VSS70';
NODE_NAME     J8 166
 '@S9S_MB_2U_LIB.S9S_MB_2U(SCH_1):PAGE89_I175@PURE_QUANTA.SCONN288_ADR50017P087CC(CHIPS)':
 'VSS71': CDS_PINID='VSS71';
NODE_NAME     J8 169
 '@S9S_MB_2U_LIB.S9S_MB_2U(SCH_1):PAGE89_I175@PURE_QUANTA.SCONN288_ADR50017P087CC(CHIPS)':
 'VSS72': CDS_PINID='VSS72';
NODE_NAME     J8 171
 '@S9S_MB_2U_LIB.S9S_MB_2U(SCH_1):PAGE89_I175@PURE_QUANTA.SCONN288_ADR50017P087CC(CHIPS)':
 'VSS73': CDS_PINID='VSS73';
NODE_NAME     J8 173
 '@S9S_MB_2U_LIB.S9S_MB_2U(SCH_1):PAGE89_I175@PURE_QUANTA.SCONN288_ADR50017P087CC(CHIPS)':
 'VSS74': CDS_PINID='VSS74';
NODE_NAME     J8 175
 '@S9S_MB_2U_LIB.S9S_MB_2U(SCH_1):PAGE89_I175@PURE_QUANTA.SCONN288_ADR50017P087CC(CHIPS)':
 'VSS75': CDS_PINID='VSS75';
NODE_NAME     J8 177
 '@S9S_MB_2U_LIB.S9S_MB_2U(SCH_1):PAGE89_I175@PURE_QUANTA.SCONN288_ADR50017P087CC(CHIPS)':
 'VSS76': CDS_PINID='VSS76';
NODE_NAME     J8 180
 '@S9S_MB_2U_LIB.S9S_MB_2U(SCH_1):PAGE89_I175@PURE_QUANTA.SCONN288_ADR50017P087CC(CHIPS)':
 'VSS77': CDS_PINID='VSS77';
NODE_NAME     J8 182
 '@S9S_MB_2U_LIB.S9S_MB_2U(SCH_1):PAGE89_I175@PURE_QUANTA.SCONN288_ADR50017P087CC(CHIPS)':
 'VSS78': CDS_PINID='VSS78';
NODE_NAME     J8 184
 '@S9S_MB_2U_LIB.S9S_MB_2U(SCH_1):PAGE89_I175@PURE_QUANTA.SCONN288_ADR50017P087CC(CHIPS)':
 'VSS79': CDS_PINID='VSS79';
NODE_NAME     J8 186
 '@S9S_MB_2U_LIB.S9S_MB_2U(SCH_1):PAGE89_I175@PURE_QUANTA.SCONN288_ADR50017P087CC(CHIPS)':
 'VSS80': CDS_PINID='VSS80';
NODE_NAME     J8 188
 '@S9S_MB_2U_LIB.S9S_MB_2U(SCH_1):PAGE89_I175@PURE_QUANTA.SCONN288_ADR50017P087CC(CHIPS)':
 'VSS81': CDS_PINID='VSS81';
NODE_NAME     J8 191
 '@S9S_MB_2U_LIB.S9S_MB_2U(SCH_1):PAGE89_I175@PURE_QUANTA.SCONN288_ADR50017P087CC(CHIPS)':
 'VSS82': CDS_PINID='VSS82';
NODE_NAME     J8 193
 '@S9S_MB_2U_LIB.S9S_MB_2U(SCH_1):PAGE89_I175@PURE_QUANTA.SCONN288_ADR50017P087CC(CHIPS)':
 'VSS83': CDS_PINID='VSS83';
NODE_NAME     J8 195
 '@S9S_MB_2U_LIB.S9S_MB_2U(SCH_1):PAGE89_I175@PURE_QUANTA.SCONN288_ADR50017P087CC(CHIPS)':
 'VSS84': CDS_PINID='VSS84';
NODE_NAME     J8 197
 '@S9S_MB_2U_LIB.S9S_MB_2U(SCH_1):PAGE89_I175@PURE_QUANTA.SCONN288_ADR50017P087CC(CHIPS)':
 'VSS85': CDS_PINID='VSS85';
NODE_NAME     J8 199
 '@S9S_MB_2U_LIB.S9S_MB_2U(SCH_1):PAGE89_I175@PURE_QUANTA.SCONN288_ADR50017P087CC(CHIPS)':
 'VSS86': CDS_PINID='VSS86';
NODE_NAME     J8 202
 '@S9S_MB_2U_LIB.S9S_MB_2U(SCH_1):PAGE89_I175@PURE_QUANTA.SCONN288_ADR50017P087CC(CHIPS)':
 'VSS87': CDS_PINID='VSS87';
NODE_NAME     J8 204
 '@S9S_MB_2U_LIB.S9S_MB_2U(SCH_1):PAGE89_I175@PURE_QUANTA.SCONN288_ADR50017P087CC(CHIPS)':
 'VSS88': CDS_PINID='VSS88';
NODE_NAME     J8 206
 '@S9S_MB_2U_LIB.S9S_MB_2U(SCH_1):PAGE89_I175@PURE_QUANTA.SCONN288_ADR50017P087CC(CHIPS)':
 'VSS89': CDS_PINID='VSS89';
NODE_NAME     J8 208
 '@S9S_MB_2U_LIB.S9S_MB_2U(SCH_1):PAGE89_I175@PURE_QUANTA.SCONN288_ADR50017P087CC(CHIPS)':
 'VSS90': CDS_PINID='VSS90';
NODE_NAME     J8 210
 '@S9S_MB_2U_LIB.S9S_MB_2U(SCH_1):PAGE89_I175@PURE_QUANTA.SCONN288_ADR50017P087CC(CHIPS)':
 'VSS91': CDS_PINID='VSS91';
NODE_NAME     J8 212
 '@S9S_MB_2U_LIB.S9S_MB_2U(SCH_1):PAGE89_I175@PURE_QUANTA.SCONN288_ADR50017P087CC(CHIPS)':
 'VSS92': CDS_PINID='VSS92';
NODE_NAME     J8 214
 '@S9S_MB_2U_LIB.S9S_MB_2U(SCH_1):PAGE89_I175@PURE_QUANTA.SCONN288_ADR50017P087CC(CHIPS)':
 'VSS93': CDS_PINID='VSS93';
NODE_NAME     J8 216
 '@S9S_MB_2U_LIB.S9S_MB_2U(SCH_1):PAGE89_I175@PURE_QUANTA.SCONN288_ADR50017P087CC(CHIPS)':
 'VSS94': CDS_PINID='VSS94';
NODE_NAME     J8 219
 '@S9S_MB_2U_LIB.S9S_MB_2U(SCH_1):PAGE89_I175@PURE_QUANTA.SCONN288_ADR50017P087CC(CHIPS)':
 'VSS95': CDS_PINID='VSS95';
NODE_NAME     J8 222
 '@S9S_MB_2U_LIB.S9S_MB_2U(SCH_1):PAGE89_I175@PURE_QUANTA.SCONN288_ADR50017P087CC(CHIPS)':
 'VSS96': CDS_PINID='VSS96';
NODE_NAME     J8 224
 '@S9S_MB_2U_LIB.S9S_MB_2U(SCH_1):PAGE89_I175@PURE_QUANTA.SCONN288_ADR50017P087CC(CHIPS)':
 'VSS97': CDS_PINID='VSS97';
NODE_NAME     J8 226
 '@S9S_MB_2U_LIB.S9S_MB_2U(SCH_1):PAGE89_I175@PURE_QUANTA.SCONN288_ADR50017P087CC(CHIPS)':
 'VSS98': CDS_PINID='VSS98';
NODE_NAME     J8 228
 '@S9S_MB_2U_LIB.S9S_MB_2U(SCH_1):PAGE89_I175@PURE_QUANTA.SCONN288_ADR50017P087CC(CHIPS)':
 'VSS99': CDS_PINID='VSS99';
NODE_NAME     J8 230
 '@S9S_MB_2U_LIB.S9S_MB_2U(SCH_1):PAGE89_I175@PURE_QUANTA.SCONN288_ADR50017P087CC(CHIPS)':
 'VSS100': CDS_PINID='VSS100';
NODE_NAME     J8 233
 '@S9S_MB_2U_LIB.S9S_MB_2U(SCH_1):PAGE89_I175@PURE_QUANTA.SCONN288_ADR50017P087CC(CHIPS)':
 'VSS101': CDS_PINID='VSS101';
NODE_NAME     J8 235
 '@S9S_MB_2U_LIB.S9S_MB_2U(SCH_1):PAGE89_I175@PURE_QUANTA.SCONN288_ADR50017P087CC(CHIPS)':
 'VSS102': CDS_PINID='VSS102';
NODE_NAME     J8 237
 '@S9S_MB_2U_LIB.S9S_MB_2U(SCH_1):PAGE89_I175@PURE_QUANTA.SCONN288_ADR50017P087CC(CHIPS)':
 'VSS103': CDS_PINID='VSS103';
NODE_NAME     J8 240
 '@S9S_MB_2U_LIB.S9S_MB_2U(SCH_1):PAGE89_I175@PURE_QUANTA.SCONN288_ADR50017P087CC(CHIPS)':
 'VSS104': CDS_PINID='VSS104';
NODE_NAME     J8 242
 '@S9S_MB_2U_LIB.S9S_MB_2U(SCH_1):PAGE89_I175@PURE_QUANTA.SCONN288_ADR50017P087CC(CHIPS)':
 'VSS105': CDS_PINID='VSS105';
NODE_NAME     J8 244
 '@S9S_MB_2U_LIB.S9S_MB_2U(SCH_1):PAGE89_I175@PURE_QUANTA.SCONN288_ADR50017P087CC(CHIPS)':
 'VSS106': CDS_PINID='VSS106';
NODE_NAME     J8 246
 '@S9S_MB_2U_LIB.S9S_MB_2U(SCH_1):PAGE89_I175@PURE_QUANTA.SCONN288_ADR50017P087CC(CHIPS)':
 'VSS107': CDS_PINID='VSS107';
NODE_NAME     J8 248
 '@S9S_MB_2U_LIB.S9S_MB_2U(SCH_1):PAGE89_I175@PURE_QUANTA.SCONN288_ADR50017P087CC(CHIPS)':
 'VSS108': CDS_PINID='VSS108';
NODE_NAME     J8 251
 '@S9S_MB_2U_LIB.S9S_MB_2U(SCH_1):PAGE89_I175@PURE_QUANTA.SCONN288_ADR50017P087CC(CHIPS)':
 'VSS109': CDS_PINID='VSS109';
NODE_NAME     J8 253
 '@S9S_MB_2U_LIB.S9S_MB_2U(SCH_1):PAGE89_I175@PURE_QUANTA.SCONN288_ADR50017P087CC(CHIPS)':
 'VSS110': CDS_PINID='VSS110';
NODE_NAME     J8 255
 '@S9S_MB_2U_LIB.S9S_MB_2U(SCH_1):PAGE89_I175@PURE_QUANTA.SCONN288_ADR50017P087CC(CHIPS)':
 'VSS111': CDS_PINID='VSS111';
NODE_NAME     J8 257
 '@S9S_MB_2U_LIB.S9S_MB_2U(SCH_1):PAGE89_I175@PURE_QUANTA.SCONN288_ADR50017P087CC(CHIPS)':
 'VSS112': CDS_PINID='VSS112';
NODE_NAME     J8 259
 '@S9S_MB_2U_LIB.S9S_MB_2U(SCH_1):PAGE89_I175@PURE_QUANTA.SCONN288_ADR50017P087CC(CHIPS)':
 'VSS113': CDS_PINID='VSS113';
NODE_NAME     J8 262
 '@S9S_MB_2U_LIB.S9S_MB_2U(SCH_1):PAGE89_I175@PURE_QUANTA.SCONN288_ADR50017P087CC(CHIPS)':
 'VSS114': CDS_PINID='VSS114';
NODE_NAME     J8 264
 '@S9S_MB_2U_LIB.S9S_MB_2U(SCH_1):PAGE89_I175@PURE_QUANTA.SCONN288_ADR50017P087CC(CHIPS)':
 'VSS115': CDS_PINID='VSS115';
NODE_NAME     J8 266
 '@S9S_MB_2U_LIB.S9S_MB_2U(SCH_1):PAGE89_I175@PURE_QUANTA.SCONN288_ADR50017P087CC(CHIPS)':
 'VSS116': CDS_PINID='VSS116';
NODE_NAME     J8 268
 '@S9S_MB_2U_LIB.S9S_MB_2U(SCH_1):PAGE89_I175@PURE_QUANTA.SCONN288_ADR50017P087CC(CHIPS)':
 'VSS117': CDS_PINID='VSS117';
NODE_NAME     J8 270
 '@S9S_MB_2U_LIB.S9S_MB_2U(SCH_1):PAGE89_I175@PURE_QUANTA.SCONN288_ADR50017P087CC(CHIPS)':
 'VSS118': CDS_PINID='VSS118';
NODE_NAME     J8 273
 '@S9S_MB_2U_LIB.S9S_MB_2U(SCH_1):PAGE89_I175@PURE_QUANTA.SCONN288_ADR50017P087CC(CHIPS)':
 'VSS119': CDS_PINID='VSS119';
NODE_NAME     J8 275
 '@S9S_MB_2U_LIB.S9S_MB_2U(SCH_1):PAGE89_I175@PURE_QUANTA.SCONN288_ADR50017P087CC(CHIPS)':
 'VSS120': CDS_PINID='VSS120';
NODE_NAME     J8 277
 '@S9S_MB_2U_LIB.S9S_MB_2U(SCH_1):PAGE89_I175@PURE_QUANTA.SCONN288_ADR50017P087CC(CHIPS)':
 'VSS121': CDS_PINID='VSS121';
NODE_NAME     J8 279
 '@S9S_MB_2U_LIB.S9S_MB_2U(SCH_1):PAGE89_I175@PURE_QUANTA.SCONN288_ADR50017P087CC(CHIPS)':
 'VSS122': CDS_PINID='VSS122';
NODE_NAME     J8 281
 '@S9S_MB_2U_LIB.S9S_MB_2U(SCH_1):PAGE89_I175@PURE_QUANTA.SCONN288_ADR50017P087CC(CHIPS)':
 'VSS123': CDS_PINID='VSS123';
NODE_NAME     J8 284
 '@S9S_MB_2U_LIB.S9S_MB_2U(SCH_1):PAGE89_I175@PURE_QUANTA.SCONN288_ADR50017P087CC(CHIPS)':
 'VSS124': CDS_PINID='VSS124';
NODE_NAME     J8 286
 '@S9S_MB_2U_LIB.S9S_MB_2U(SCH_1):PAGE89_I175@PURE_QUANTA.SCONN288_ADR50017P087CC(CHIPS)':
 'VSS125': CDS_PINID='VSS125';
NODE_NAME     J8 288
 '@S9S_MB_2U_LIB.S9S_MB_2U(SCH_1):PAGE89_I175@PURE_QUANTA.SCONN288_ADR50017P087CC(CHIPS)':
 'VSS126': CDS_PINID='VSS126';
NODE_NAME     R34 2
 '@S9S_MB_2U_LIB.S9S_MB_2U(SCH_1):PAGE90_I11@PURE_QUANTA.Q_RES(CHIPS)':
 'B': CDS_PINID='B';
NODE_NAME     C26 2
 '@S9S_MB_2U_LIB.S9S_MB_2U(SCH_1):PAGE90_I122@PURE_QUANTA.Q_CAP(CHIPS)':
 'B': CDS_PINID='B';
NODE_NAME     C27 2
 '@S9S_MB_2U_LIB.S9S_MB_2U(SCH_1):PAGE90_I123@PURE_QUANTA.Q_CAP(CHIPS)':
 'B': CDS_PINID='B';
NODE_NAME     C28 2
 '@S9S_MB_2U_LIB.S9S_MB_2U(SCH_1):PAGE90_I145@PURE_QUANTA.Q_CAP(CHIPS)':
 'B': CDS_PINID='B';
NODE_NAME     J9 G1
 '@S9S_MB_2U_LIB.S9S_MB_2U(SCH_1):PAGE90_I147@PURE_QUANTA.SCONN288_ADR50017P130CC(CHIPS)':
 'G1': CDS_PINID='G1';
NODE_NAME     J9 G2
 '@S9S_MB_2U_LIB.S9S_MB_2U(SCH_1):PAGE90_I147@PURE_QUANTA.SCONN288_ADR50017P130CC(CHIPS)':
 'G2': CDS_PINID='G2';
NODE_NAME     J9 G3
 '@S9S_MB_2U_LIB.S9S_MB_2U(SCH_1):PAGE90_I147@PURE_QUANTA.SCONN288_ADR50017P130CC(CHIPS)':
 'G3': CDS_PINID='G3';
NODE_NAME     J9 6
 '@S9S_MB_2U_LIB.S9S_MB_2U(SCH_1):PAGE90_I147@PURE_QUANTA.SCONN288_ADR50017P130CC(CHIPS)':
 'VSS0': CDS_PINID='VSS0';
NODE_NAME     J9 8
 '@S9S_MB_2U_LIB.S9S_MB_2U(SCH_1):PAGE90_I147@PURE_QUANTA.SCONN288_ADR50017P130CC(CHIPS)':
 'VSS1': CDS_PINID='VSS1';
NODE_NAME     J9 10
 '@S9S_MB_2U_LIB.S9S_MB_2U(SCH_1):PAGE90_I147@PURE_QUANTA.SCONN288_ADR50017P130CC(CHIPS)':
 'VSS2': CDS_PINID='VSS2';
NODE_NAME     J9 13
 '@S9S_MB_2U_LIB.S9S_MB_2U(SCH_1):PAGE90_I147@PURE_QUANTA.SCONN288_ADR50017P130CC(CHIPS)':
 'VSS3': CDS_PINID='VSS3';
NODE_NAME     J9 15
 '@S9S_MB_2U_LIB.S9S_MB_2U(SCH_1):PAGE90_I147@PURE_QUANTA.SCONN288_ADR50017P130CC(CHIPS)':
 'VSS4': CDS_PINID='VSS4';
NODE_NAME     J9 17
 '@S9S_MB_2U_LIB.S9S_MB_2U(SCH_1):PAGE90_I147@PURE_QUANTA.SCONN288_ADR50017P130CC(CHIPS)':
 'VSS5': CDS_PINID='VSS5';
NODE_NAME     J9 19
 '@S9S_MB_2U_LIB.S9S_MB_2U(SCH_1):PAGE90_I147@PURE_QUANTA.SCONN288_ADR50017P130CC(CHIPS)':
 'VSS6': CDS_PINID='VSS6';
NODE_NAME     J9 21
 '@S9S_MB_2U_LIB.S9S_MB_2U(SCH_1):PAGE90_I147@PURE_QUANTA.SCONN288_ADR50017P130CC(CHIPS)':
 'VSS7': CDS_PINID='VSS7';
NODE_NAME     J9 24
 '@S9S_MB_2U_LIB.S9S_MB_2U(SCH_1):PAGE90_I147@PURE_QUANTA.SCONN288_ADR50017P130CC(CHIPS)':
 'VSS8': CDS_PINID='VSS8';
NODE_NAME     J9 26
 '@S9S_MB_2U_LIB.S9S_MB_2U(SCH_1):PAGE90_I147@PURE_QUANTA.SCONN288_ADR50017P130CC(CHIPS)':
 'VSS9': CDS_PINID='VSS9';
NODE_NAME     J9 28
 '@S9S_MB_2U_LIB.S9S_MB_2U(SCH_1):PAGE90_I147@PURE_QUANTA.SCONN288_ADR50017P130CC(CHIPS)':
 'VSS10': CDS_PINID='VSS10';
NODE_NAME     J9 30
 '@S9S_MB_2U_LIB.S9S_MB_2U(SCH_1):PAGE90_I147@PURE_QUANTA.SCONN288_ADR50017P130CC(CHIPS)':
 'VSS11': CDS_PINID='VSS11';
NODE_NAME     J9 32
 '@S9S_MB_2U_LIB.S9S_MB_2U(SCH_1):PAGE90_I147@PURE_QUANTA.SCONN288_ADR50017P130CC(CHIPS)':
 'VSS12': CDS_PINID='VSS12';
NODE_NAME     J9 35
 '@S9S_MB_2U_LIB.S9S_MB_2U(SCH_1):PAGE90_I147@PURE_QUANTA.SCONN288_ADR50017P130CC(CHIPS)':
 'VSS13': CDS_PINID='VSS13';
NODE_NAME     J9 37
 '@S9S_MB_2U_LIB.S9S_MB_2U(SCH_1):PAGE90_I147@PURE_QUANTA.SCONN288_ADR50017P130CC(CHIPS)':
 'VSS14': CDS_PINID='VSS14';
NODE_NAME     J9 39
 '@S9S_MB_2U_LIB.S9S_MB_2U(SCH_1):PAGE90_I147@PURE_QUANTA.SCONN288_ADR50017P130CC(CHIPS)':
 'VSS15': CDS_PINID='VSS15';
NODE_NAME     J9 41
 '@S9S_MB_2U_LIB.S9S_MB_2U(SCH_1):PAGE90_I147@PURE_QUANTA.SCONN288_ADR50017P130CC(CHIPS)':
 'VSS16': CDS_PINID='VSS16';
NODE_NAME     J9 43
 '@S9S_MB_2U_LIB.S9S_MB_2U(SCH_1):PAGE90_I147@PURE_QUANTA.SCONN288_ADR50017P130CC(CHIPS)':
 'VSS17': CDS_PINID='VSS17';
NODE_NAME     J9 46
 '@S9S_MB_2U_LIB.S9S_MB_2U(SCH_1):PAGE90_I147@PURE_QUANTA.SCONN288_ADR50017P130CC(CHIPS)':
 'VSS18': CDS_PINID='VSS18';
NODE_NAME     J9 48
 '@S9S_MB_2U_LIB.S9S_MB_2U(SCH_1):PAGE90_I147@PURE_QUANTA.SCONN288_ADR50017P130CC(CHIPS)':
 'VSS19': CDS_PINID='VSS19';
NODE_NAME     J9 50
 '@S9S_MB_2U_LIB.S9S_MB_2U(SCH_1):PAGE90_I147@PURE_QUANTA.SCONN288_ADR50017P130CC(CHIPS)':
 'VSS20': CDS_PINID='VSS20';
NODE_NAME     J9 52
 '@S9S_MB_2U_LIB.S9S_MB_2U(SCH_1):PAGE90_I147@PURE_QUANTA.SCONN288_ADR50017P130CC(CHIPS)':
 'VSS21': CDS_PINID='VSS21';
NODE_NAME     J9 54
 '@S9S_MB_2U_LIB.S9S_MB_2U(SCH_1):PAGE90_I147@PURE_QUANTA.SCONN288_ADR50017P130CC(CHIPS)':
 'VSS22': CDS_PINID='VSS22';
NODE_NAME     J9 57
 '@S9S_MB_2U_LIB.S9S_MB_2U(SCH_1):PAGE90_I147@PURE_QUANTA.SCONN288_ADR50017P130CC(CHIPS)':
 'VSS23': CDS_PINID='VSS23';
NODE_NAME     J9 59
 '@S9S_MB_2U_LIB.S9S_MB_2U(SCH_1):PAGE90_I147@PURE_QUANTA.SCONN288_ADR50017P130CC(CHIPS)':
 'VSS24': CDS_PINID='VSS24';
NODE_NAME     J9 61
 '@S9S_MB_2U_LIB.S9S_MB_2U(SCH_1):PAGE90_I147@PURE_QUANTA.SCONN288_ADR50017P130CC(CHIPS)':
 'VSS25': CDS_PINID='VSS25';
NODE_NAME     J9 63
 '@S9S_MB_2U_LIB.S9S_MB_2U(SCH_1):PAGE90_I147@PURE_QUANTA.SCONN288_ADR50017P130CC(CHIPS)':
 'VSS26': CDS_PINID='VSS26';
NODE_NAME     J9 65
 '@S9S_MB_2U_LIB.S9S_MB_2U(SCH_1):PAGE90_I147@PURE_QUANTA.SCONN288_ADR50017P130CC(CHIPS)':
 'VSS27': CDS_PINID='VSS27';
NODE_NAME     J9 67
 '@S9S_MB_2U_LIB.S9S_MB_2U(SCH_1):PAGE90_I147@PURE_QUANTA.SCONN288_ADR50017P130CC(CHIPS)':
 'VSS28': CDS_PINID='VSS28';
NODE_NAME     J9 69
 '@S9S_MB_2U_LIB.S9S_MB_2U(SCH_1):PAGE90_I147@PURE_QUANTA.SCONN288_ADR50017P130CC(CHIPS)':
 'VSS29': CDS_PINID='VSS29';
NODE_NAME     J9 71
 '@S9S_MB_2U_LIB.S9S_MB_2U(SCH_1):PAGE90_I147@PURE_QUANTA.SCONN288_ADR50017P130CC(CHIPS)':
 'VSS30': CDS_PINID='VSS30';
NODE_NAME     J9 73
 '@S9S_MB_2U_LIB.S9S_MB_2U(SCH_1):PAGE90_I147@PURE_QUANTA.SCONN288_ADR50017P130CC(CHIPS)':
 'VSS31': CDS_PINID='VSS31';
NODE_NAME     J9 75
 '@S9S_MB_2U_LIB.S9S_MB_2U(SCH_1):PAGE90_I147@PURE_QUANTA.SCONN288_ADR50017P130CC(CHIPS)':
 'VSS32': CDS_PINID='VSS32';
NODE_NAME     J9 77
 '@S9S_MB_2U_LIB.S9S_MB_2U(SCH_1):PAGE90_I147@PURE_QUANTA.SCONN288_ADR50017P130CC(CHIPS)':
 'VSS33': CDS_PINID='VSS33';
NODE_NAME     J9 79
 '@S9S_MB_2U_LIB.S9S_MB_2U(SCH_1):PAGE90_I147@PURE_QUANTA.SCONN288_ADR50017P130CC(CHIPS)':
 'VSS34': CDS_PINID='VSS34';
NODE_NAME     J9 81
 '@S9S_MB_2U_LIB.S9S_MB_2U(SCH_1):PAGE90_I147@PURE_QUANTA.SCONN288_ADR50017P130CC(CHIPS)':
 'VSS35': CDS_PINID='VSS35';
NODE_NAME     J9 83
 '@S9S_MB_2U_LIB.S9S_MB_2U(SCH_1):PAGE90_I147@PURE_QUANTA.SCONN288_ADR50017P130CC(CHIPS)':
 'VSS36': CDS_PINID='VSS36';
NODE_NAME     J9 85
 '@S9S_MB_2U_LIB.S9S_MB_2U(SCH_1):PAGE90_I147@PURE_QUANTA.SCONN288_ADR50017P130CC(CHIPS)':
 'VSS37': CDS_PINID='VSS37';
NODE_NAME     J9 88
 '@S9S_MB_2U_LIB.S9S_MB_2U(SCH_1):PAGE90_I147@PURE_QUANTA.SCONN288_ADR50017P130CC(CHIPS)':
 'VSS38': CDS_PINID='VSS38';
NODE_NAME     J9 90
 '@S9S_MB_2U_LIB.S9S_MB_2U(SCH_1):PAGE90_I147@PURE_QUANTA.SCONN288_ADR50017P130CC(CHIPS)':
 'VSS39': CDS_PINID='VSS39';
NODE_NAME     J9 92
 '@S9S_MB_2U_LIB.S9S_MB_2U(SCH_1):PAGE90_I147@PURE_QUANTA.SCONN288_ADR50017P130CC(CHIPS)':
 'VSS40': CDS_PINID='VSS40';
NODE_NAME     J9 95
 '@S9S_MB_2U_LIB.S9S_MB_2U(SCH_1):PAGE90_I147@PURE_QUANTA.SCONN288_ADR50017P130CC(CHIPS)':
 'VSS41': CDS_PINID='VSS41';
NODE_NAME     J9 97
 '@S9S_MB_2U_LIB.S9S_MB_2U(SCH_1):PAGE90_I147@PURE_QUANTA.SCONN288_ADR50017P130CC(CHIPS)':
 'VSS42': CDS_PINID='VSS42';
NODE_NAME     J9 99
 '@S9S_MB_2U_LIB.S9S_MB_2U(SCH_1):PAGE90_I147@PURE_QUANTA.SCONN288_ADR50017P130CC(CHIPS)':
 'VSS43': CDS_PINID='VSS43';
NODE_NAME     J9 101
 '@S9S_MB_2U_LIB.S9S_MB_2U(SCH_1):PAGE90_I147@PURE_QUANTA.SCONN288_ADR50017P130CC(CHIPS)':
 'VSS44': CDS_PINID='VSS44';
NODE_NAME     J9 103
 '@S9S_MB_2U_LIB.S9S_MB_2U(SCH_1):PAGE90_I147@PURE_QUANTA.SCONN288_ADR50017P130CC(CHIPS)':
 'VSS45': CDS_PINID='VSS45';
NODE_NAME     J9 106
 '@S9S_MB_2U_LIB.S9S_MB_2U(SCH_1):PAGE90_I147@PURE_QUANTA.SCONN288_ADR50017P130CC(CHIPS)':
 'VSS46': CDS_PINID='VSS46';
NODE_NAME     J9 108
 '@S9S_MB_2U_LIB.S9S_MB_2U(SCH_1):PAGE90_I147@PURE_QUANTA.SCONN288_ADR50017P130CC(CHIPS)':
 'VSS47': CDS_PINID='VSS47';
NODE_NAME     J9 110
 '@S9S_MB_2U_LIB.S9S_MB_2U(SCH_1):PAGE90_I147@PURE_QUANTA.SCONN288_ADR50017P130CC(CHIPS)':
 'VSS48': CDS_PINID='VSS48';
NODE_NAME     J9 112
 '@S9S_MB_2U_LIB.S9S_MB_2U(SCH_1):PAGE90_I147@PURE_QUANTA.SCONN288_ADR50017P130CC(CHIPS)':
 'VSS49': CDS_PINID='VSS49';
NODE_NAME     J9 114
 '@S9S_MB_2U_LIB.S9S_MB_2U(SCH_1):PAGE90_I147@PURE_QUANTA.SCONN288_ADR50017P130CC(CHIPS)':
 'VSS50': CDS_PINID='VSS50';
NODE_NAME     J9 117
 '@S9S_MB_2U_LIB.S9S_MB_2U(SCH_1):PAGE90_I147@PURE_QUANTA.SCONN288_ADR50017P130CC(CHIPS)':
 'VSS51': CDS_PINID='VSS51';
NODE_NAME     J9 119
 '@S9S_MB_2U_LIB.S9S_MB_2U(SCH_1):PAGE90_I147@PURE_QUANTA.SCONN288_ADR50017P130CC(CHIPS)':
 'VSS52': CDS_PINID='VSS52';
NODE_NAME     J9 121
 '@S9S_MB_2U_LIB.S9S_MB_2U(SCH_1):PAGE90_I147@PURE_QUANTA.SCONN288_ADR50017P130CC(CHIPS)':
 'VSS53': CDS_PINID='VSS53';
NODE_NAME     J9 123
 '@S9S_MB_2U_LIB.S9S_MB_2U(SCH_1):PAGE90_I147@PURE_QUANTA.SCONN288_ADR50017P130CC(CHIPS)':
 'VSS54': CDS_PINID='VSS54';
NODE_NAME     J9 125
 '@S9S_MB_2U_LIB.S9S_MB_2U(SCH_1):PAGE90_I147@PURE_QUANTA.SCONN288_ADR50017P130CC(CHIPS)':
 'VSS55': CDS_PINID='VSS55';
NODE_NAME     J9 128
 '@S9S_MB_2U_LIB.S9S_MB_2U(SCH_1):PAGE90_I147@PURE_QUANTA.SCONN288_ADR50017P130CC(CHIPS)':
 'VSS56': CDS_PINID='VSS56';
NODE_NAME     J9 130
 '@S9S_MB_2U_LIB.S9S_MB_2U(SCH_1):PAGE90_I147@PURE_QUANTA.SCONN288_ADR50017P130CC(CHIPS)':
 'VSS57': CDS_PINID='VSS57';
NODE_NAME     J9 132
 '@S9S_MB_2U_LIB.S9S_MB_2U(SCH_1):PAGE90_I147@PURE_QUANTA.SCONN288_ADR50017P130CC(CHIPS)':
 'VSS58': CDS_PINID='VSS58';
NODE_NAME     J9 134
 '@S9S_MB_2U_LIB.S9S_MB_2U(SCH_1):PAGE90_I147@PURE_QUANTA.SCONN288_ADR50017P130CC(CHIPS)':
 'VSS59': CDS_PINID='VSS59';
NODE_NAME     J9 136
 '@S9S_MB_2U_LIB.S9S_MB_2U(SCH_1):PAGE90_I147@PURE_QUANTA.SCONN288_ADR50017P130CC(CHIPS)':
 'VSS60': CDS_PINID='VSS60';
NODE_NAME     J9 139
 '@S9S_MB_2U_LIB.S9S_MB_2U(SCH_1):PAGE90_I147@PURE_QUANTA.SCONN288_ADR50017P130CC(CHIPS)':
 'VSS61': CDS_PINID='VSS61';
NODE_NAME     J9 141
 '@S9S_MB_2U_LIB.S9S_MB_2U(SCH_1):PAGE90_I147@PURE_QUANTA.SCONN288_ADR50017P130CC(CHIPS)':
 'VSS62': CDS_PINID='VSS62';
NODE_NAME     J9 143
 '@S9S_MB_2U_LIB.S9S_MB_2U(SCH_1):PAGE90_I147@PURE_QUANTA.SCONN288_ADR50017P130CC(CHIPS)':
 'VSS63': CDS_PINID='VSS63';
NODE_NAME     J9 151
 '@S9S_MB_2U_LIB.S9S_MB_2U(SCH_1):PAGE90_I147@PURE_QUANTA.SCONN288_ADR50017P130CC(CHIPS)':
 'VSS64': CDS_PINID='VSS64';
NODE_NAME     J9 153
 '@S9S_MB_2U_LIB.S9S_MB_2U(SCH_1):PAGE90_I147@PURE_QUANTA.SCONN288_ADR50017P130CC(CHIPS)':
 'VSS65': CDS_PINID='VSS65';
NODE_NAME     J9 155
 '@S9S_MB_2U_LIB.S9S_MB_2U(SCH_1):PAGE90_I147@PURE_QUANTA.SCONN288_ADR50017P130CC(CHIPS)':
 'VSS66': CDS_PINID='VSS66';
NODE_NAME     J9 158
 '@S9S_MB_2U_LIB.S9S_MB_2U(SCH_1):PAGE90_I147@PURE_QUANTA.SCONN288_ADR50017P130CC(CHIPS)':
 'VSS67': CDS_PINID='VSS67';
NODE_NAME     J9 160
 '@S9S_MB_2U_LIB.S9S_MB_2U(SCH_1):PAGE90_I147@PURE_QUANTA.SCONN288_ADR50017P130CC(CHIPS)':
 'VSS68': CDS_PINID='VSS68';
NODE_NAME     J9 162
 '@S9S_MB_2U_LIB.S9S_MB_2U(SCH_1):PAGE90_I147@PURE_QUANTA.SCONN288_ADR50017P130CC(CHIPS)':
 'VSS69': CDS_PINID='VSS69';
NODE_NAME     J9 164
 '@S9S_MB_2U_LIB.S9S_MB_2U(SCH_1):PAGE90_I147@PURE_QUANTA.SCONN288_ADR50017P130CC(CHIPS)':
 'VSS70': CDS_PINID='VSS70';
NODE_NAME     J9 166
 '@S9S_MB_2U_LIB.S9S_MB_2U(SCH_1):PAGE90_I147@PURE_QUANTA.SCONN288_ADR50017P130CC(CHIPS)':
 'VSS71': CDS_PINID='VSS71';
NODE_NAME     J9 169
 '@S9S_MB_2U_LIB.S9S_MB_2U(SCH_1):PAGE90_I147@PURE_QUANTA.SCONN288_ADR50017P130CC(CHIPS)':
 'VSS72': CDS_PINID='VSS72';
NODE_NAME     J9 171
 '@S9S_MB_2U_LIB.S9S_MB_2U(SCH_1):PAGE90_I147@PURE_QUANTA.SCONN288_ADR50017P130CC(CHIPS)':
 'VSS73': CDS_PINID='VSS73';
NODE_NAME     J9 173
 '@S9S_MB_2U_LIB.S9S_MB_2U(SCH_1):PAGE90_I147@PURE_QUANTA.SCONN288_ADR50017P130CC(CHIPS)':
 'VSS74': CDS_PINID='VSS74';
NODE_NAME     J9 175
 '@S9S_MB_2U_LIB.S9S_MB_2U(SCH_1):PAGE90_I147@PURE_QUANTA.SCONN288_ADR50017P130CC(CHIPS)':
 'VSS75': CDS_PINID='VSS75';
NODE_NAME     J9 177
 '@S9S_MB_2U_LIB.S9S_MB_2U(SCH_1):PAGE90_I147@PURE_QUANTA.SCONN288_ADR50017P130CC(CHIPS)':
 'VSS76': CDS_PINID='VSS76';
NODE_NAME     J9 180
 '@S9S_MB_2U_LIB.S9S_MB_2U(SCH_1):PAGE90_I147@PURE_QUANTA.SCONN288_ADR50017P130CC(CHIPS)':
 'VSS77': CDS_PINID='VSS77';
NODE_NAME     J9 182
 '@S9S_MB_2U_LIB.S9S_MB_2U(SCH_1):PAGE90_I147@PURE_QUANTA.SCONN288_ADR50017P130CC(CHIPS)':
 'VSS78': CDS_PINID='VSS78';
NODE_NAME     J9 184
 '@S9S_MB_2U_LIB.S9S_MB_2U(SCH_1):PAGE90_I147@PURE_QUANTA.SCONN288_ADR50017P130CC(CHIPS)':
 'VSS79': CDS_PINID='VSS79';
NODE_NAME     J9 186
 '@S9S_MB_2U_LIB.S9S_MB_2U(SCH_1):PAGE90_I147@PURE_QUANTA.SCONN288_ADR50017P130CC(CHIPS)':
 'VSS80': CDS_PINID='VSS80';
NODE_NAME     J9 188
 '@S9S_MB_2U_LIB.S9S_MB_2U(SCH_1):PAGE90_I147@PURE_QUANTA.SCONN288_ADR50017P130CC(CHIPS)':
 'VSS81': CDS_PINID='VSS81';
NODE_NAME     J9 191
 '@S9S_MB_2U_LIB.S9S_MB_2U(SCH_1):PAGE90_I147@PURE_QUANTA.SCONN288_ADR50017P130CC(CHIPS)':
 'VSS82': CDS_PINID='VSS82';
NODE_NAME     J9 193
 '@S9S_MB_2U_LIB.S9S_MB_2U(SCH_1):PAGE90_I147@PURE_QUANTA.SCONN288_ADR50017P130CC(CHIPS)':
 'VSS83': CDS_PINID='VSS83';
NODE_NAME     J9 195
 '@S9S_MB_2U_LIB.S9S_MB_2U(SCH_1):PAGE90_I147@PURE_QUANTA.SCONN288_ADR50017P130CC(CHIPS)':
 'VSS84': CDS_PINID='VSS84';
NODE_NAME     J9 197
 '@S9S_MB_2U_LIB.S9S_MB_2U(SCH_1):PAGE90_I147@PURE_QUANTA.SCONN288_ADR50017P130CC(CHIPS)':
 'VSS85': CDS_PINID='VSS85';
NODE_NAME     J9 199
 '@S9S_MB_2U_LIB.S9S_MB_2U(SCH_1):PAGE90_I147@PURE_QUANTA.SCONN288_ADR50017P130CC(CHIPS)':
 'VSS86': CDS_PINID='VSS86';
NODE_NAME     J9 202
 '@S9S_MB_2U_LIB.S9S_MB_2U(SCH_1):PAGE90_I147@PURE_QUANTA.SCONN288_ADR50017P130CC(CHIPS)':
 'VSS87': CDS_PINID='VSS87';
NODE_NAME     J9 204
 '@S9S_MB_2U_LIB.S9S_MB_2U(SCH_1):PAGE90_I147@PURE_QUANTA.SCONN288_ADR50017P130CC(CHIPS)':
 'VSS88': CDS_PINID='VSS88';
NODE_NAME     J9 206
 '@S9S_MB_2U_LIB.S9S_MB_2U(SCH_1):PAGE90_I147@PURE_QUANTA.SCONN288_ADR50017P130CC(CHIPS)':
 'VSS89': CDS_PINID='VSS89';
NODE_NAME     J9 208
 '@S9S_MB_2U_LIB.S9S_MB_2U(SCH_1):PAGE90_I147@PURE_QUANTA.SCONN288_ADR50017P130CC(CHIPS)':
 'VSS90': CDS_PINID='VSS90';
NODE_NAME     J9 210
 '@S9S_MB_2U_LIB.S9S_MB_2U(SCH_1):PAGE90_I147@PURE_QUANTA.SCONN288_ADR50017P130CC(CHIPS)':
 'VSS91': CDS_PINID='VSS91';
NODE_NAME     J9 212
 '@S9S_MB_2U_LIB.S9S_MB_2U(SCH_1):PAGE90_I147@PURE_QUANTA.SCONN288_ADR50017P130CC(CHIPS)':
 'VSS92': CDS_PINID='VSS92';
NODE_NAME     J9 214
 '@S9S_MB_2U_LIB.S9S_MB_2U(SCH_1):PAGE90_I147@PURE_QUANTA.SCONN288_ADR50017P130CC(CHIPS)':
 'VSS93': CDS_PINID='VSS93';
NODE_NAME     J9 216
 '@S9S_MB_2U_LIB.S9S_MB_2U(SCH_1):PAGE90_I147@PURE_QUANTA.SCONN288_ADR50017P130CC(CHIPS)':
 'VSS94': CDS_PINID='VSS94';
NODE_NAME     J9 219
 '@S9S_MB_2U_LIB.S9S_MB_2U(SCH_1):PAGE90_I147@PURE_QUANTA.SCONN288_ADR50017P130CC(CHIPS)':
 'VSS95': CDS_PINID='VSS95';
NODE_NAME     J9 222
 '@S9S_MB_2U_LIB.S9S_MB_2U(SCH_1):PAGE90_I147@PURE_QUANTA.SCONN288_ADR50017P130CC(CHIPS)':
 'VSS96': CDS_PINID='VSS96';
NODE_NAME     J9 224
 '@S9S_MB_2U_LIB.S9S_MB_2U(SCH_1):PAGE90_I147@PURE_QUANTA.SCONN288_ADR50017P130CC(CHIPS)':
 'VSS97': CDS_PINID='VSS97';
NODE_NAME     J9 226
 '@S9S_MB_2U_LIB.S9S_MB_2U(SCH_1):PAGE90_I147@PURE_QUANTA.SCONN288_ADR50017P130CC(CHIPS)':
 'VSS98': CDS_PINID='VSS98';
NODE_NAME     J9 228
 '@S9S_MB_2U_LIB.S9S_MB_2U(SCH_1):PAGE90_I147@PURE_QUANTA.SCONN288_ADR50017P130CC(CHIPS)':
 'VSS99': CDS_PINID='VSS99';
NODE_NAME     J9 230
 '@S9S_MB_2U_LIB.S9S_MB_2U(SCH_1):PAGE90_I147@PURE_QUANTA.SCONN288_ADR50017P130CC(CHIPS)':
 'VSS100': CDS_PINID='VSS100';
NODE_NAME     J9 233
 '@S9S_MB_2U_LIB.S9S_MB_2U(SCH_1):PAGE90_I147@PURE_QUANTA.SCONN288_ADR50017P130CC(CHIPS)':
 'VSS101': CDS_PINID='VSS101';
NODE_NAME     J9 235
 '@S9S_MB_2U_LIB.S9S_MB_2U(SCH_1):PAGE90_I147@PURE_QUANTA.SCONN288_ADR50017P130CC(CHIPS)':
 'VSS102': CDS_PINID='VSS102';
NODE_NAME     J9 237
 '@S9S_MB_2U_LIB.S9S_MB_2U(SCH_1):PAGE90_I147@PURE_QUANTA.SCONN288_ADR50017P130CC(CHIPS)':
 'VSS103': CDS_PINID='VSS103';
NODE_NAME     J9 240
 '@S9S_MB_2U_LIB.S9S_MB_2U(SCH_1):PAGE90_I147@PURE_QUANTA.SCONN288_ADR50017P130CC(CHIPS)':
 'VSS104': CDS_PINID='VSS104';
NODE_NAME     J9 242
 '@S9S_MB_2U_LIB.S9S_MB_2U(SCH_1):PAGE90_I147@PURE_QUANTA.SCONN288_ADR50017P130CC(CHIPS)':
 'VSS105': CDS_PINID='VSS105';
NODE_NAME     J9 244
 '@S9S_MB_2U_LIB.S9S_MB_2U(SCH_1):PAGE90_I147@PURE_QUANTA.SCONN288_ADR50017P130CC(CHIPS)':
 'VSS106': CDS_PINID='VSS106';
NODE_NAME     J9 246
 '@S9S_MB_2U_LIB.S9S_MB_2U(SCH_1):PAGE90_I147@PURE_QUANTA.SCONN288_ADR50017P130CC(CHIPS)':
 'VSS107': CDS_PINID='VSS107';
NODE_NAME     J9 248
 '@S9S_MB_2U_LIB.S9S_MB_2U(SCH_1):PAGE90_I147@PURE_QUANTA.SCONN288_ADR50017P130CC(CHIPS)':
 'VSS108': CDS_PINID='VSS108';
NODE_NAME     J9 251
 '@S9S_MB_2U_LIB.S9S_MB_2U(SCH_1):PAGE90_I147@PURE_QUANTA.SCONN288_ADR50017P130CC(CHIPS)':
 'VSS109': CDS_PINID='VSS109';
NODE_NAME     J9 253
 '@S9S_MB_2U_LIB.S9S_MB_2U(SCH_1):PAGE90_I147@PURE_QUANTA.SCONN288_ADR50017P130CC(CHIPS)':
 'VSS110': CDS_PINID='VSS110';
NODE_NAME     J9 255
 '@S9S_MB_2U_LIB.S9S_MB_2U(SCH_1):PAGE90_I147@PURE_QUANTA.SCONN288_ADR50017P130CC(CHIPS)':
 'VSS111': CDS_PINID='VSS111';
NODE_NAME     J9 257
 '@S9S_MB_2U_LIB.S9S_MB_2U(SCH_1):PAGE90_I147@PURE_QUANTA.SCONN288_ADR50017P130CC(CHIPS)':
 'VSS112': CDS_PINID='VSS112';
NODE_NAME     J9 259
 '@S9S_MB_2U_LIB.S9S_MB_2U(SCH_1):PAGE90_I147@PURE_QUANTA.SCONN288_ADR50017P130CC(CHIPS)':
 'VSS113': CDS_PINID='VSS113';
NODE_NAME     J9 262
 '@S9S_MB_2U_LIB.S9S_MB_2U(SCH_1):PAGE90_I147@PURE_QUANTA.SCONN288_ADR50017P130CC(CHIPS)':
 'VSS114': CDS_PINID='VSS114';
NODE_NAME     J9 264
 '@S9S_MB_2U_LIB.S9S_MB_2U(SCH_1):PAGE90_I147@PURE_QUANTA.SCONN288_ADR50017P130CC(CHIPS)':
 'VSS115': CDS_PINID='VSS115';
NODE_NAME     J9 266
 '@S9S_MB_2U_LIB.S9S_MB_2U(SCH_1):PAGE90_I147@PURE_QUANTA.SCONN288_ADR50017P130CC(CHIPS)':
 'VSS116': CDS_PINID='VSS116';
NODE_NAME     J9 268
 '@S9S_MB_2U_LIB.S9S_MB_2U(SCH_1):PAGE90_I147@PURE_QUANTA.SCONN288_ADR50017P130CC(CHIPS)':
 'VSS117': CDS_PINID='VSS117';
NODE_NAME     J9 270
 '@S9S_MB_2U_LIB.S9S_MB_2U(SCH_1):PAGE90_I147@PURE_QUANTA.SCONN288_ADR50017P130CC(CHIPS)':
 'VSS118': CDS_PINID='VSS118';
NODE_NAME     J9 273
 '@S9S_MB_2U_LIB.S9S_MB_2U(SCH_1):PAGE90_I147@PURE_QUANTA.SCONN288_ADR50017P130CC(CHIPS)':
 'VSS119': CDS_PINID='VSS119';
NODE_NAME     J9 275
 '@S9S_MB_2U_LIB.S9S_MB_2U(SCH_1):PAGE90_I147@PURE_QUANTA.SCONN288_ADR50017P130CC(CHIPS)':
 'VSS120': CDS_PINID='VSS120';
NODE_NAME     J9 277
 '@S9S_MB_2U_LIB.S9S_MB_2U(SCH_1):PAGE90_I147@PURE_QUANTA.SCONN288_ADR50017P130CC(CHIPS)':
 'VSS121': CDS_PINID='VSS121';
NODE_NAME     J9 279
 '@S9S_MB_2U_LIB.S9S_MB_2U(SCH_1):PAGE90_I147@PURE_QUANTA.SCONN288_ADR50017P130CC(CHIPS)':
 'VSS122': CDS_PINID='VSS122';
NODE_NAME     J9 281
 '@S9S_MB_2U_LIB.S9S_MB_2U(SCH_1):PAGE90_I147@PURE_QUANTA.SCONN288_ADR50017P130CC(CHIPS)':
 'VSS123': CDS_PINID='VSS123';
NODE_NAME     J9 284
 '@S9S_MB_2U_LIB.S9S_MB_2U(SCH_1):PAGE90_I147@PURE_QUANTA.SCONN288_ADR50017P130CC(CHIPS)':
 'VSS124': CDS_PINID='VSS124';
NODE_NAME     J9 286
 '@S9S_MB_2U_LIB.S9S_MB_2U(SCH_1):PAGE90_I147@PURE_QUANTA.SCONN288_ADR50017P130CC(CHIPS)':
 'VSS125': CDS_PINID='VSS125';
NODE_NAME     J9 288
 '@S9S_MB_2U_LIB.S9S_MB_2U(SCH_1):PAGE90_I147@PURE_QUANTA.SCONN288_ADR50017P130CC(CHIPS)':
 'VSS126': CDS_PINID='VSS126';
NODE_NAME     R35 2
 '@S9S_MB_2U_LIB.S9S_MB_2U(SCH_1):PAGE91_I2@PURE_QUANTA.Q_RES(CHIPS)':
 'B': CDS_PINID='B';
NODE_NAME     C29 2
 '@S9S_MB_2U_LIB.S9S_MB_2U(SCH_1):PAGE91_I123@PURE_QUANTA.Q_CAP(CHIPS)':
 'B': CDS_PINID='B';
NODE_NAME     C30 2
 '@S9S_MB_2U_LIB.S9S_MB_2U(SCH_1):PAGE91_I124@PURE_QUANTA.Q_CAP(CHIPS)':
 'B': CDS_PINID='B';
NODE_NAME     C31 2
 '@S9S_MB_2U_LIB.S9S_MB_2U(SCH_1):PAGE91_I146@PURE_QUANTA.Q_CAP(CHIPS)':
 'B': CDS_PINID='B';
NODE_NAME     J10 G1
 '@S9S_MB_2U_LIB.S9S_MB_2U(SCH_1):PAGE91_I148@PURE_QUANTA.SCONN288_ADR50017P087CC(CHIPS)':
 'G1': CDS_PINID='G1';
NODE_NAME     J10 G2
 '@S9S_MB_2U_LIB.S9S_MB_2U(SCH_1):PAGE91_I148@PURE_QUANTA.SCONN288_ADR50017P087CC(CHIPS)':
 'G2': CDS_PINID='G2';
NODE_NAME     J10 G3
 '@S9S_MB_2U_LIB.S9S_MB_2U(SCH_1):PAGE91_I148@PURE_QUANTA.SCONN288_ADR50017P087CC(CHIPS)':
 'G3': CDS_PINID='G3';
NODE_NAME     J10 6
 '@S9S_MB_2U_LIB.S9S_MB_2U(SCH_1):PAGE91_I148@PURE_QUANTA.SCONN288_ADR50017P087CC(CHIPS)':
 'VSS0': CDS_PINID='VSS0';
NODE_NAME     J10 8
 '@S9S_MB_2U_LIB.S9S_MB_2U(SCH_1):PAGE91_I148@PURE_QUANTA.SCONN288_ADR50017P087CC(CHIPS)':
 'VSS1': CDS_PINID='VSS1';
NODE_NAME     J10 10
 '@S9S_MB_2U_LIB.S9S_MB_2U(SCH_1):PAGE91_I148@PURE_QUANTA.SCONN288_ADR50017P087CC(CHIPS)':
 'VSS2': CDS_PINID='VSS2';
NODE_NAME     J10 13
 '@S9S_MB_2U_LIB.S9S_MB_2U(SCH_1):PAGE91_I148@PURE_QUANTA.SCONN288_ADR50017P087CC(CHIPS)':
 'VSS3': CDS_PINID='VSS3';
NODE_NAME     J10 15
 '@S9S_MB_2U_LIB.S9S_MB_2U(SCH_1):PAGE91_I148@PURE_QUANTA.SCONN288_ADR50017P087CC(CHIPS)':
 'VSS4': CDS_PINID='VSS4';
NODE_NAME     J10 17
 '@S9S_MB_2U_LIB.S9S_MB_2U(SCH_1):PAGE91_I148@PURE_QUANTA.SCONN288_ADR50017P087CC(CHIPS)':
 'VSS5': CDS_PINID='VSS5';
NODE_NAME     J10 19
 '@S9S_MB_2U_LIB.S9S_MB_2U(SCH_1):PAGE91_I148@PURE_QUANTA.SCONN288_ADR50017P087CC(CHIPS)':
 'VSS6': CDS_PINID='VSS6';
NODE_NAME     J10 21
 '@S9S_MB_2U_LIB.S9S_MB_2U(SCH_1):PAGE91_I148@PURE_QUANTA.SCONN288_ADR50017P087CC(CHIPS)':
 'VSS7': CDS_PINID='VSS7';
NODE_NAME     J10 24
 '@S9S_MB_2U_LIB.S9S_MB_2U(SCH_1):PAGE91_I148@PURE_QUANTA.SCONN288_ADR50017P087CC(CHIPS)':
 'VSS8': CDS_PINID='VSS8';
NODE_NAME     J10 26
 '@S9S_MB_2U_LIB.S9S_MB_2U(SCH_1):PAGE91_I148@PURE_QUANTA.SCONN288_ADR50017P087CC(CHIPS)':
 'VSS9': CDS_PINID='VSS9';
NODE_NAME     J10 28
 '@S9S_MB_2U_LIB.S9S_MB_2U(SCH_1):PAGE91_I148@PURE_QUANTA.SCONN288_ADR50017P087CC(CHIPS)':
 'VSS10': CDS_PINID='VSS10';
NODE_NAME     J10 30
 '@S9S_MB_2U_LIB.S9S_MB_2U(SCH_1):PAGE91_I148@PURE_QUANTA.SCONN288_ADR50017P087CC(CHIPS)':
 'VSS11': CDS_PINID='VSS11';
NODE_NAME     J10 32
 '@S9S_MB_2U_LIB.S9S_MB_2U(SCH_1):PAGE91_I148@PURE_QUANTA.SCONN288_ADR50017P087CC(CHIPS)':
 'VSS12': CDS_PINID='VSS12';
NODE_NAME     J10 35
 '@S9S_MB_2U_LIB.S9S_MB_2U(SCH_1):PAGE91_I148@PURE_QUANTA.SCONN288_ADR50017P087CC(CHIPS)':
 'VSS13': CDS_PINID='VSS13';
NODE_NAME     J10 37
 '@S9S_MB_2U_LIB.S9S_MB_2U(SCH_1):PAGE91_I148@PURE_QUANTA.SCONN288_ADR50017P087CC(CHIPS)':
 'VSS14': CDS_PINID='VSS14';
NODE_NAME     J10 39
 '@S9S_MB_2U_LIB.S9S_MB_2U(SCH_1):PAGE91_I148@PURE_QUANTA.SCONN288_ADR50017P087CC(CHIPS)':
 'VSS15': CDS_PINID='VSS15';
NODE_NAME     J10 41
 '@S9S_MB_2U_LIB.S9S_MB_2U(SCH_1):PAGE91_I148@PURE_QUANTA.SCONN288_ADR50017P087CC(CHIPS)':
 'VSS16': CDS_PINID='VSS16';
NODE_NAME     J10 43
 '@S9S_MB_2U_LIB.S9S_MB_2U(SCH_1):PAGE91_I148@PURE_QUANTA.SCONN288_ADR50017P087CC(CHIPS)':
 'VSS17': CDS_PINID='VSS17';
NODE_NAME     J10 46
 '@S9S_MB_2U_LIB.S9S_MB_2U(SCH_1):PAGE91_I148@PURE_QUANTA.SCONN288_ADR50017P087CC(CHIPS)':
 'VSS18': CDS_PINID='VSS18';
NODE_NAME     J10 48
 '@S9S_MB_2U_LIB.S9S_MB_2U(SCH_1):PAGE91_I148@PURE_QUANTA.SCONN288_ADR50017P087CC(CHIPS)':
 'VSS19': CDS_PINID='VSS19';
NODE_NAME     J10 50
 '@S9S_MB_2U_LIB.S9S_MB_2U(SCH_1):PAGE91_I148@PURE_QUANTA.SCONN288_ADR50017P087CC(CHIPS)':
 'VSS20': CDS_PINID='VSS20';
NODE_NAME     J10 52
 '@S9S_MB_2U_LIB.S9S_MB_2U(SCH_1):PAGE91_I148@PURE_QUANTA.SCONN288_ADR50017P087CC(CHIPS)':
 'VSS21': CDS_PINID='VSS21';
NODE_NAME     J10 54
 '@S9S_MB_2U_LIB.S9S_MB_2U(SCH_1):PAGE91_I148@PURE_QUANTA.SCONN288_ADR50017P087CC(CHIPS)':
 'VSS22': CDS_PINID='VSS22';
NODE_NAME     J10 57
 '@S9S_MB_2U_LIB.S9S_MB_2U(SCH_1):PAGE91_I148@PURE_QUANTA.SCONN288_ADR50017P087CC(CHIPS)':
 'VSS23': CDS_PINID='VSS23';
NODE_NAME     J10 59
 '@S9S_MB_2U_LIB.S9S_MB_2U(SCH_1):PAGE91_I148@PURE_QUANTA.SCONN288_ADR50017P087CC(CHIPS)':
 'VSS24': CDS_PINID='VSS24';
NODE_NAME     J10 61
 '@S9S_MB_2U_LIB.S9S_MB_2U(SCH_1):PAGE91_I148@PURE_QUANTA.SCONN288_ADR50017P087CC(CHIPS)':
 'VSS25': CDS_PINID='VSS25';
NODE_NAME     J10 63
 '@S9S_MB_2U_LIB.S9S_MB_2U(SCH_1):PAGE91_I148@PURE_QUANTA.SCONN288_ADR50017P087CC(CHIPS)':
 'VSS26': CDS_PINID='VSS26';
NODE_NAME     J10 65
 '@S9S_MB_2U_LIB.S9S_MB_2U(SCH_1):PAGE91_I148@PURE_QUANTA.SCONN288_ADR50017P087CC(CHIPS)':
 'VSS27': CDS_PINID='VSS27';
NODE_NAME     J10 67
 '@S9S_MB_2U_LIB.S9S_MB_2U(SCH_1):PAGE91_I148@PURE_QUANTA.SCONN288_ADR50017P087CC(CHIPS)':
 'VSS28': CDS_PINID='VSS28';
NODE_NAME     J10 69
 '@S9S_MB_2U_LIB.S9S_MB_2U(SCH_1):PAGE91_I148@PURE_QUANTA.SCONN288_ADR50017P087CC(CHIPS)':
 'VSS29': CDS_PINID='VSS29';
NODE_NAME     J10 71
 '@S9S_MB_2U_LIB.S9S_MB_2U(SCH_1):PAGE91_I148@PURE_QUANTA.SCONN288_ADR50017P087CC(CHIPS)':
 'VSS30': CDS_PINID='VSS30';
NODE_NAME     J10 73
 '@S9S_MB_2U_LIB.S9S_MB_2U(SCH_1):PAGE91_I148@PURE_QUANTA.SCONN288_ADR50017P087CC(CHIPS)':
 'VSS31': CDS_PINID='VSS31';
NODE_NAME     J10 75
 '@S9S_MB_2U_LIB.S9S_MB_2U(SCH_1):PAGE91_I148@PURE_QUANTA.SCONN288_ADR50017P087CC(CHIPS)':
 'VSS32': CDS_PINID='VSS32';
NODE_NAME     J10 77
 '@S9S_MB_2U_LIB.S9S_MB_2U(SCH_1):PAGE91_I148@PURE_QUANTA.SCONN288_ADR50017P087CC(CHIPS)':
 'VSS33': CDS_PINID='VSS33';
NODE_NAME     J10 79
 '@S9S_MB_2U_LIB.S9S_MB_2U(SCH_1):PAGE91_I148@PURE_QUANTA.SCONN288_ADR50017P087CC(CHIPS)':
 'VSS34': CDS_PINID='VSS34';
NODE_NAME     J10 81
 '@S9S_MB_2U_LIB.S9S_MB_2U(SCH_1):PAGE91_I148@PURE_QUANTA.SCONN288_ADR50017P087CC(CHIPS)':
 'VSS35': CDS_PINID='VSS35';
NODE_NAME     J10 83
 '@S9S_MB_2U_LIB.S9S_MB_2U(SCH_1):PAGE91_I148@PURE_QUANTA.SCONN288_ADR50017P087CC(CHIPS)':
 'VSS36': CDS_PINID='VSS36';
NODE_NAME     J10 85
 '@S9S_MB_2U_LIB.S9S_MB_2U(SCH_1):PAGE91_I148@PURE_QUANTA.SCONN288_ADR50017P087CC(CHIPS)':
 'VSS37': CDS_PINID='VSS37';
NODE_NAME     J10 88
 '@S9S_MB_2U_LIB.S9S_MB_2U(SCH_1):PAGE91_I148@PURE_QUANTA.SCONN288_ADR50017P087CC(CHIPS)':
 'VSS38': CDS_PINID='VSS38';
NODE_NAME     J10 90
 '@S9S_MB_2U_LIB.S9S_MB_2U(SCH_1):PAGE91_I148@PURE_QUANTA.SCONN288_ADR50017P087CC(CHIPS)':
 'VSS39': CDS_PINID='VSS39';
NODE_NAME     J10 92
 '@S9S_MB_2U_LIB.S9S_MB_2U(SCH_1):PAGE91_I148@PURE_QUANTA.SCONN288_ADR50017P087CC(CHIPS)':
 'VSS40': CDS_PINID='VSS40';
NODE_NAME     J10 95
 '@S9S_MB_2U_LIB.S9S_MB_2U(SCH_1):PAGE91_I148@PURE_QUANTA.SCONN288_ADR50017P087CC(CHIPS)':
 'VSS41': CDS_PINID='VSS41';
NODE_NAME     J10 97
 '@S9S_MB_2U_LIB.S9S_MB_2U(SCH_1):PAGE91_I148@PURE_QUANTA.SCONN288_ADR50017P087CC(CHIPS)':
 'VSS42': CDS_PINID='VSS42';
NODE_NAME     J10 99
 '@S9S_MB_2U_LIB.S9S_MB_2U(SCH_1):PAGE91_I148@PURE_QUANTA.SCONN288_ADR50017P087CC(CHIPS)':
 'VSS43': CDS_PINID='VSS43';
NODE_NAME     J10 101
 '@S9S_MB_2U_LIB.S9S_MB_2U(SCH_1):PAGE91_I148@PURE_QUANTA.SCONN288_ADR50017P087CC(CHIPS)':
 'VSS44': CDS_PINID='VSS44';
NODE_NAME     J10 103
 '@S9S_MB_2U_LIB.S9S_MB_2U(SCH_1):PAGE91_I148@PURE_QUANTA.SCONN288_ADR50017P087CC(CHIPS)':
 'VSS45': CDS_PINID='VSS45';
NODE_NAME     J10 106
 '@S9S_MB_2U_LIB.S9S_MB_2U(SCH_1):PAGE91_I148@PURE_QUANTA.SCONN288_ADR50017P087CC(CHIPS)':
 'VSS46': CDS_PINID='VSS46';
NODE_NAME     J10 108
 '@S9S_MB_2U_LIB.S9S_MB_2U(SCH_1):PAGE91_I148@PURE_QUANTA.SCONN288_ADR50017P087CC(CHIPS)':
 'VSS47': CDS_PINID='VSS47';
NODE_NAME     J10 110
 '@S9S_MB_2U_LIB.S9S_MB_2U(SCH_1):PAGE91_I148@PURE_QUANTA.SCONN288_ADR50017P087CC(CHIPS)':
 'VSS48': CDS_PINID='VSS48';
NODE_NAME     J10 112
 '@S9S_MB_2U_LIB.S9S_MB_2U(SCH_1):PAGE91_I148@PURE_QUANTA.SCONN288_ADR50017P087CC(CHIPS)':
 'VSS49': CDS_PINID='VSS49';
NODE_NAME     J10 114
 '@S9S_MB_2U_LIB.S9S_MB_2U(SCH_1):PAGE91_I148@PURE_QUANTA.SCONN288_ADR50017P087CC(CHIPS)':
 'VSS50': CDS_PINID='VSS50';
NODE_NAME     J10 117
 '@S9S_MB_2U_LIB.S9S_MB_2U(SCH_1):PAGE91_I148@PURE_QUANTA.SCONN288_ADR50017P087CC(CHIPS)':
 'VSS51': CDS_PINID='VSS51';
NODE_NAME     J10 119
 '@S9S_MB_2U_LIB.S9S_MB_2U(SCH_1):PAGE91_I148@PURE_QUANTA.SCONN288_ADR50017P087CC(CHIPS)':
 'VSS52': CDS_PINID='VSS52';
NODE_NAME     J10 121
 '@S9S_MB_2U_LIB.S9S_MB_2U(SCH_1):PAGE91_I148@PURE_QUANTA.SCONN288_ADR50017P087CC(CHIPS)':
 'VSS53': CDS_PINID='VSS53';
NODE_NAME     J10 123
 '@S9S_MB_2U_LIB.S9S_MB_2U(SCH_1):PAGE91_I148@PURE_QUANTA.SCONN288_ADR50017P087CC(CHIPS)':
 'VSS54': CDS_PINID='VSS54';
NODE_NAME     J10 125
 '@S9S_MB_2U_LIB.S9S_MB_2U(SCH_1):PAGE91_I148@PURE_QUANTA.SCONN288_ADR50017P087CC(CHIPS)':
 'VSS55': CDS_PINID='VSS55';
NODE_NAME     J10 128
 '@S9S_MB_2U_LIB.S9S_MB_2U(SCH_1):PAGE91_I148@PURE_QUANTA.SCONN288_ADR50017P087CC(CHIPS)':
 'VSS56': CDS_PINID='VSS56';
NODE_NAME     J10 130
 '@S9S_MB_2U_LIB.S9S_MB_2U(SCH_1):PAGE91_I148@PURE_QUANTA.SCONN288_ADR50017P087CC(CHIPS)':
 'VSS57': CDS_PINID='VSS57';
NODE_NAME     J10 132
 '@S9S_MB_2U_LIB.S9S_MB_2U(SCH_1):PAGE91_I148@PURE_QUANTA.SCONN288_ADR50017P087CC(CHIPS)':
 'VSS58': CDS_PINID='VSS58';
NODE_NAME     J10 134
 '@S9S_MB_2U_LIB.S9S_MB_2U(SCH_1):PAGE91_I148@PURE_QUANTA.SCONN288_ADR50017P087CC(CHIPS)':
 'VSS59': CDS_PINID='VSS59';
NODE_NAME     J10 136
 '@S9S_MB_2U_LIB.S9S_MB_2U(SCH_1):PAGE91_I148@PURE_QUANTA.SCONN288_ADR50017P087CC(CHIPS)':
 'VSS60': CDS_PINID='VSS60';
NODE_NAME     J10 139
 '@S9S_MB_2U_LIB.S9S_MB_2U(SCH_1):PAGE91_I148@PURE_QUANTA.SCONN288_ADR50017P087CC(CHIPS)':
 'VSS61': CDS_PINID='VSS61';
NODE_NAME     J10 141
 '@S9S_MB_2U_LIB.S9S_MB_2U(SCH_1):PAGE91_I148@PURE_QUANTA.SCONN288_ADR50017P087CC(CHIPS)':
 'VSS62': CDS_PINID='VSS62';
NODE_NAME     J10 143
 '@S9S_MB_2U_LIB.S9S_MB_2U(SCH_1):PAGE91_I148@PURE_QUANTA.SCONN288_ADR50017P087CC(CHIPS)':
 'VSS63': CDS_PINID='VSS63';
NODE_NAME     J10 151
 '@S9S_MB_2U_LIB.S9S_MB_2U(SCH_1):PAGE91_I148@PURE_QUANTA.SCONN288_ADR50017P087CC(CHIPS)':
 'VSS64': CDS_PINID='VSS64';
NODE_NAME     J10 153
 '@S9S_MB_2U_LIB.S9S_MB_2U(SCH_1):PAGE91_I148@PURE_QUANTA.SCONN288_ADR50017P087CC(CHIPS)':
 'VSS65': CDS_PINID='VSS65';
NODE_NAME     J10 155
 '@S9S_MB_2U_LIB.S9S_MB_2U(SCH_1):PAGE91_I148@PURE_QUANTA.SCONN288_ADR50017P087CC(CHIPS)':
 'VSS66': CDS_PINID='VSS66';
NODE_NAME     J10 158
 '@S9S_MB_2U_LIB.S9S_MB_2U(SCH_1):PAGE91_I148@PURE_QUANTA.SCONN288_ADR50017P087CC(CHIPS)':
 'VSS67': CDS_PINID='VSS67';
NODE_NAME     J10 160
 '@S9S_MB_2U_LIB.S9S_MB_2U(SCH_1):PAGE91_I148@PURE_QUANTA.SCONN288_ADR50017P087CC(CHIPS)':
 'VSS68': CDS_PINID='VSS68';
NODE_NAME     J10 162
 '@S9S_MB_2U_LIB.S9S_MB_2U(SCH_1):PAGE91_I148@PURE_QUANTA.SCONN288_ADR50017P087CC(CHIPS)':
 'VSS69': CDS_PINID='VSS69';
NODE_NAME     J10 164
 '@S9S_MB_2U_LIB.S9S_MB_2U(SCH_1):PAGE91_I148@PURE_QUANTA.SCONN288_ADR50017P087CC(CHIPS)':
 'VSS70': CDS_PINID='VSS70';
NODE_NAME     J10 166
 '@S9S_MB_2U_LIB.S9S_MB_2U(SCH_1):PAGE91_I148@PURE_QUANTA.SCONN288_ADR50017P087CC(CHIPS)':
 'VSS71': CDS_PINID='VSS71';
NODE_NAME     J10 169
 '@S9S_MB_2U_LIB.S9S_MB_2U(SCH_1):PAGE91_I148@PURE_QUANTA.SCONN288_ADR50017P087CC(CHIPS)':
 'VSS72': CDS_PINID='VSS72';
NODE_NAME     J10 171
 '@S9S_MB_2U_LIB.S9S_MB_2U(SCH_1):PAGE91_I148@PURE_QUANTA.SCONN288_ADR50017P087CC(CHIPS)':
 'VSS73': CDS_PINID='VSS73';
NODE_NAME     J10 173
 '@S9S_MB_2U_LIB.S9S_MB_2U(SCH_1):PAGE91_I148@PURE_QUANTA.SCONN288_ADR50017P087CC(CHIPS)':
 'VSS74': CDS_PINID='VSS74';
NODE_NAME     J10 175
 '@S9S_MB_2U_LIB.S9S_MB_2U(SCH_1):PAGE91_I148@PURE_QUANTA.SCONN288_ADR50017P087CC(CHIPS)':
 'VSS75': CDS_PINID='VSS75';
NODE_NAME     J10 177
 '@S9S_MB_2U_LIB.S9S_MB_2U(SCH_1):PAGE91_I148@PURE_QUANTA.SCONN288_ADR50017P087CC(CHIPS)':
 'VSS76': CDS_PINID='VSS76';
NODE_NAME     J10 180
 '@S9S_MB_2U_LIB.S9S_MB_2U(SCH_1):PAGE91_I148@PURE_QUANTA.SCONN288_ADR50017P087CC(CHIPS)':
 'VSS77': CDS_PINID='VSS77';
NODE_NAME     J10 182
 '@S9S_MB_2U_LIB.S9S_MB_2U(SCH_1):PAGE91_I148@PURE_QUANTA.SCONN288_ADR50017P087CC(CHIPS)':
 'VSS78': CDS_PINID='VSS78';
NODE_NAME     J10 184
 '@S9S_MB_2U_LIB.S9S_MB_2U(SCH_1):PAGE91_I148@PURE_QUANTA.SCONN288_ADR50017P087CC(CHIPS)':
 'VSS79': CDS_PINID='VSS79';
NODE_NAME     J10 186
 '@S9S_MB_2U_LIB.S9S_MB_2U(SCH_1):PAGE91_I148@PURE_QUANTA.SCONN288_ADR50017P087CC(CHIPS)':
 'VSS80': CDS_PINID='VSS80';
NODE_NAME     J10 188
 '@S9S_MB_2U_LIB.S9S_MB_2U(SCH_1):PAGE91_I148@PURE_QUANTA.SCONN288_ADR50017P087CC(CHIPS)':
 'VSS81': CDS_PINID='VSS81';
NODE_NAME     J10 191
 '@S9S_MB_2U_LIB.S9S_MB_2U(SCH_1):PAGE91_I148@PURE_QUANTA.SCONN288_ADR50017P087CC(CHIPS)':
 'VSS82': CDS_PINID='VSS82';
NODE_NAME     J10 193
 '@S9S_MB_2U_LIB.S9S_MB_2U(SCH_1):PAGE91_I148@PURE_QUANTA.SCONN288_ADR50017P087CC(CHIPS)':
 'VSS83': CDS_PINID='VSS83';
NODE_NAME     J10 195
 '@S9S_MB_2U_LIB.S9S_MB_2U(SCH_1):PAGE91_I148@PURE_QUANTA.SCONN288_ADR50017P087CC(CHIPS)':
 'VSS84': CDS_PINID='VSS84';
NODE_NAME     J10 197
 '@S9S_MB_2U_LIB.S9S_MB_2U(SCH_1):PAGE91_I148@PURE_QUANTA.SCONN288_ADR50017P087CC(CHIPS)':
 'VSS85': CDS_PINID='VSS85';
NODE_NAME     J10 199
 '@S9S_MB_2U_LIB.S9S_MB_2U(SCH_1):PAGE91_I148@PURE_QUANTA.SCONN288_ADR50017P087CC(CHIPS)':
 'VSS86': CDS_PINID='VSS86';
NODE_NAME     J10 202
 '@S9S_MB_2U_LIB.S9S_MB_2U(SCH_1):PAGE91_I148@PURE_QUANTA.SCONN288_ADR50017P087CC(CHIPS)':
 'VSS87': CDS_PINID='VSS87';
NODE_NAME     J10 204
 '@S9S_MB_2U_LIB.S9S_MB_2U(SCH_1):PAGE91_I148@PURE_QUANTA.SCONN288_ADR50017P087CC(CHIPS)':
 'VSS88': CDS_PINID='VSS88';
NODE_NAME     J10 206
 '@S9S_MB_2U_LIB.S9S_MB_2U(SCH_1):PAGE91_I148@PURE_QUANTA.SCONN288_ADR50017P087CC(CHIPS)':
 'VSS89': CDS_PINID='VSS89';
NODE_NAME     J10 208
 '@S9S_MB_2U_LIB.S9S_MB_2U(SCH_1):PAGE91_I148@PURE_QUANTA.SCONN288_ADR50017P087CC(CHIPS)':
 'VSS90': CDS_PINID='VSS90';
NODE_NAME     J10 210
 '@S9S_MB_2U_LIB.S9S_MB_2U(SCH_1):PAGE91_I148@PURE_QUANTA.SCONN288_ADR50017P087CC(CHIPS)':
 'VSS91': CDS_PINID='VSS91';
NODE_NAME     J10 212
 '@S9S_MB_2U_LIB.S9S_MB_2U(SCH_1):PAGE91_I148@PURE_QUANTA.SCONN288_ADR50017P087CC(CHIPS)':
 'VSS92': CDS_PINID='VSS92';
NODE_NAME     J10 214
 '@S9S_MB_2U_LIB.S9S_MB_2U(SCH_1):PAGE91_I148@PURE_QUANTA.SCONN288_ADR50017P087CC(CHIPS)':
 'VSS93': CDS_PINID='VSS93';
NODE_NAME     J10 216
 '@S9S_MB_2U_LIB.S9S_MB_2U(SCH_1):PAGE91_I148@PURE_QUANTA.SCONN288_ADR50017P087CC(CHIPS)':
 'VSS94': CDS_PINID='VSS94';
NODE_NAME     J10 219
 '@S9S_MB_2U_LIB.S9S_MB_2U(SCH_1):PAGE91_I148@PURE_QUANTA.SCONN288_ADR50017P087CC(CHIPS)':
 'VSS95': CDS_PINID='VSS95';
NODE_NAME     J10 222
 '@S9S_MB_2U_LIB.S9S_MB_2U(SCH_1):PAGE91_I148@PURE_QUANTA.SCONN288_ADR50017P087CC(CHIPS)':
 'VSS96': CDS_PINID='VSS96';
NODE_NAME     J10 224
 '@S9S_MB_2U_LIB.S9S_MB_2U(SCH_1):PAGE91_I148@PURE_QUANTA.SCONN288_ADR50017P087CC(CHIPS)':
 'VSS97': CDS_PINID='VSS97';
NODE_NAME     J10 226
 '@S9S_MB_2U_LIB.S9S_MB_2U(SCH_1):PAGE91_I148@PURE_QUANTA.SCONN288_ADR50017P087CC(CHIPS)':
 'VSS98': CDS_PINID='VSS98';
NODE_NAME     J10 228
 '@S9S_MB_2U_LIB.S9S_MB_2U(SCH_1):PAGE91_I148@PURE_QUANTA.SCONN288_ADR50017P087CC(CHIPS)':
 'VSS99': CDS_PINID='VSS99';
NODE_NAME     J10 230
 '@S9S_MB_2U_LIB.S9S_MB_2U(SCH_1):PAGE91_I148@PURE_QUANTA.SCONN288_ADR50017P087CC(CHIPS)':
 'VSS100': CDS_PINID='VSS100';
NODE_NAME     J10 233
 '@S9S_MB_2U_LIB.S9S_MB_2U(SCH_1):PAGE91_I148@PURE_QUANTA.SCONN288_ADR50017P087CC(CHIPS)':
 'VSS101': CDS_PINID='VSS101';
NODE_NAME     J10 235
 '@S9S_MB_2U_LIB.S9S_MB_2U(SCH_1):PAGE91_I148@PURE_QUANTA.SCONN288_ADR50017P087CC(CHIPS)':
 'VSS102': CDS_PINID='VSS102';
NODE_NAME     J10 237
 '@S9S_MB_2U_LIB.S9S_MB_2U(SCH_1):PAGE91_I148@PURE_QUANTA.SCONN288_ADR50017P087CC(CHIPS)':
 'VSS103': CDS_PINID='VSS103';
NODE_NAME     J10 240
 '@S9S_MB_2U_LIB.S9S_MB_2U(SCH_1):PAGE91_I148@PURE_QUANTA.SCONN288_ADR50017P087CC(CHIPS)':
 'VSS104': CDS_PINID='VSS104';
NODE_NAME     J10 242
 '@S9S_MB_2U_LIB.S9S_MB_2U(SCH_1):PAGE91_I148@PURE_QUANTA.SCONN288_ADR50017P087CC(CHIPS)':
 'VSS105': CDS_PINID='VSS105';
NODE_NAME     J10 244
 '@S9S_MB_2U_LIB.S9S_MB_2U(SCH_1):PAGE91_I148@PURE_QUANTA.SCONN288_ADR50017P087CC(CHIPS)':
 'VSS106': CDS_PINID='VSS106';
NODE_NAME     J10 246
 '@S9S_MB_2U_LIB.S9S_MB_2U(SCH_1):PAGE91_I148@PURE_QUANTA.SCONN288_ADR50017P087CC(CHIPS)':
 'VSS107': CDS_PINID='VSS107';
NODE_NAME     J10 248
 '@S9S_MB_2U_LIB.S9S_MB_2U(SCH_1):PAGE91_I148@PURE_QUANTA.SCONN288_ADR50017P087CC(CHIPS)':
 'VSS108': CDS_PINID='VSS108';
NODE_NAME     J10 251
 '@S9S_MB_2U_LIB.S9S_MB_2U(SCH_1):PAGE91_I148@PURE_QUANTA.SCONN288_ADR50017P087CC(CHIPS)':
 'VSS109': CDS_PINID='VSS109';
NODE_NAME     J10 253
 '@S9S_MB_2U_LIB.S9S_MB_2U(SCH_1):PAGE91_I148@PURE_QUANTA.SCONN288_ADR50017P087CC(CHIPS)':
 'VSS110': CDS_PINID='VSS110';
NODE_NAME     J10 255
 '@S9S_MB_2U_LIB.S9S_MB_2U(SCH_1):PAGE91_I148@PURE_QUANTA.SCONN288_ADR50017P087CC(CHIPS)':
 'VSS111': CDS_PINID='VSS111';
NODE_NAME     J10 257
 '@S9S_MB_2U_LIB.S9S_MB_2U(SCH_1):PAGE91_I148@PURE_QUANTA.SCONN288_ADR50017P087CC(CHIPS)':
 'VSS112': CDS_PINID='VSS112';
NODE_NAME     J10 259
 '@S9S_MB_2U_LIB.S9S_MB_2U(SCH_1):PAGE91_I148@PURE_QUANTA.SCONN288_ADR50017P087CC(CHIPS)':
 'VSS113': CDS_PINID='VSS113';
NODE_NAME     J10 262
 '@S9S_MB_2U_LIB.S9S_MB_2U(SCH_1):PAGE91_I148@PURE_QUANTA.SCONN288_ADR50017P087CC(CHIPS)':
 'VSS114': CDS_PINID='VSS114';
NODE_NAME     J10 264
 '@S9S_MB_2U_LIB.S9S_MB_2U(SCH_1):PAGE91_I148@PURE_QUANTA.SCONN288_ADR50017P087CC(CHIPS)':
 'VSS115': CDS_PINID='VSS115';
NODE_NAME     J10 266
 '@S9S_MB_2U_LIB.S9S_MB_2U(SCH_1):PAGE91_I148@PURE_QUANTA.SCONN288_ADR50017P087CC(CHIPS)':
 'VSS116': CDS_PINID='VSS116';
NODE_NAME     J10 268
 '@S9S_MB_2U_LIB.S9S_MB_2U(SCH_1):PAGE91_I148@PURE_QUANTA.SCONN288_ADR50017P087CC(CHIPS)':
 'VSS117': CDS_PINID='VSS117';
NODE_NAME     J10 270
 '@S9S_MB_2U_LIB.S9S_MB_2U(SCH_1):PAGE91_I148@PURE_QUANTA.SCONN288_ADR50017P087CC(CHIPS)':
 'VSS118': CDS_PINID='VSS118';
NODE_NAME     J10 273
 '@S9S_MB_2U_LIB.S9S_MB_2U(SCH_1):PAGE91_I148@PURE_QUANTA.SCONN288_ADR50017P087CC(CHIPS)':
 'VSS119': CDS_PINID='VSS119';
NODE_NAME     J10 275
 '@S9S_MB_2U_LIB.S9S_MB_2U(SCH_1):PAGE91_I148@PURE_QUANTA.SCONN288_ADR50017P087CC(CHIPS)':
 'VSS120': CDS_PINID='VSS120';
NODE_NAME     J10 277
 '@S9S_MB_2U_LIB.S9S_MB_2U(SCH_1):PAGE91_I148@PURE_QUANTA.SCONN288_ADR50017P087CC(CHIPS)':
 'VSS121': CDS_PINID='VSS121';
NODE_NAME     J10 279
 '@S9S_MB_2U_LIB.S9S_MB_2U(SCH_1):PAGE91_I148@PURE_QUANTA.SCONN288_ADR50017P087CC(CHIPS)':
 'VSS122': CDS_PINID='VSS122';
NODE_NAME     J10 281
 '@S9S_MB_2U_LIB.S9S_MB_2U(SCH_1):PAGE91_I148@PURE_QUANTA.SCONN288_ADR50017P087CC(CHIPS)':
 'VSS123': CDS_PINID='VSS123';
NODE_NAME     J10 284
 '@S9S_MB_2U_LIB.S9S_MB_2U(SCH_1):PAGE91_I148@PURE_QUANTA.SCONN288_ADR50017P087CC(CHIPS)':
 'VSS124': CDS_PINID='VSS124';
NODE_NAME     J10 286
 '@S9S_MB_2U_LIB.S9S_MB_2U(SCH_1):PAGE91_I148@PURE_QUANTA.SCONN288_ADR50017P087CC(CHIPS)':
 'VSS125': CDS_PINID='VSS125';
NODE_NAME     J10 288
 '@S9S_MB_2U_LIB.S9S_MB_2U(SCH_1):PAGE91_I148@PURE_QUANTA.SCONN288_ADR50017P087CC(CHIPS)':
 'VSS126': CDS_PINID='VSS126';
NODE_NAME     R36 2
 '@S9S_MB_2U_LIB.S9S_MB_2U(SCH_1):PAGE92_I2@PURE_QUANTA.Q_RES(CHIPS)':
 'B': CDS_PINID='B';
NODE_NAME     C32 2
 '@S9S_MB_2U_LIB.S9S_MB_2U(SCH_1):PAGE92_I122@PURE_QUANTA.Q_CAP(CHIPS)':
 'B': CDS_PINID='B';
NODE_NAME     C33 2
 '@S9S_MB_2U_LIB.S9S_MB_2U(SCH_1):PAGE92_I127@PURE_QUANTA.Q_CAP(CHIPS)':
 'B': CDS_PINID='B';
NODE_NAME     C34 2
 '@S9S_MB_2U_LIB.S9S_MB_2U(SCH_1):PAGE92_I130@PURE_QUANTA.Q_CAP(CHIPS)':
 'B': CDS_PINID='B';
NODE_NAME     J11 G1
 '@S9S_MB_2U_LIB.S9S_MB_2U(SCH_1):PAGE92_I175@PURE_QUANTA.SCONN288_ADR50017P130CC(CHIPS)':
 'G1': CDS_PINID='G1';
NODE_NAME     J11 G2
 '@S9S_MB_2U_LIB.S9S_MB_2U(SCH_1):PAGE92_I175@PURE_QUANTA.SCONN288_ADR50017P130CC(CHIPS)':
 'G2': CDS_PINID='G2';
NODE_NAME     J11 G3
 '@S9S_MB_2U_LIB.S9S_MB_2U(SCH_1):PAGE92_I175@PURE_QUANTA.SCONN288_ADR50017P130CC(CHIPS)':
 'G3': CDS_PINID='G3';
NODE_NAME     J11 6
 '@S9S_MB_2U_LIB.S9S_MB_2U(SCH_1):PAGE92_I175@PURE_QUANTA.SCONN288_ADR50017P130CC(CHIPS)':
 'VSS0': CDS_PINID='VSS0';
NODE_NAME     J11 8
 '@S9S_MB_2U_LIB.S9S_MB_2U(SCH_1):PAGE92_I175@PURE_QUANTA.SCONN288_ADR50017P130CC(CHIPS)':
 'VSS1': CDS_PINID='VSS1';
NODE_NAME     J11 10
 '@S9S_MB_2U_LIB.S9S_MB_2U(SCH_1):PAGE92_I175@PURE_QUANTA.SCONN288_ADR50017P130CC(CHIPS)':
 'VSS2': CDS_PINID='VSS2';
NODE_NAME     J11 13
 '@S9S_MB_2U_LIB.S9S_MB_2U(SCH_1):PAGE92_I175@PURE_QUANTA.SCONN288_ADR50017P130CC(CHIPS)':
 'VSS3': CDS_PINID='VSS3';
NODE_NAME     J11 15
 '@S9S_MB_2U_LIB.S9S_MB_2U(SCH_1):PAGE92_I175@PURE_QUANTA.SCONN288_ADR50017P130CC(CHIPS)':
 'VSS4': CDS_PINID='VSS4';
NODE_NAME     J11 17
 '@S9S_MB_2U_LIB.S9S_MB_2U(SCH_1):PAGE92_I175@PURE_QUANTA.SCONN288_ADR50017P130CC(CHIPS)':
 'VSS5': CDS_PINID='VSS5';
NODE_NAME     J11 19
 '@S9S_MB_2U_LIB.S9S_MB_2U(SCH_1):PAGE92_I175@PURE_QUANTA.SCONN288_ADR50017P130CC(CHIPS)':
 'VSS6': CDS_PINID='VSS6';
NODE_NAME     J11 21
 '@S9S_MB_2U_LIB.S9S_MB_2U(SCH_1):PAGE92_I175@PURE_QUANTA.SCONN288_ADR50017P130CC(CHIPS)':
 'VSS7': CDS_PINID='VSS7';
NODE_NAME     J11 24
 '@S9S_MB_2U_LIB.S9S_MB_2U(SCH_1):PAGE92_I175@PURE_QUANTA.SCONN288_ADR50017P130CC(CHIPS)':
 'VSS8': CDS_PINID='VSS8';
NODE_NAME     J11 26
 '@S9S_MB_2U_LIB.S9S_MB_2U(SCH_1):PAGE92_I175@PURE_QUANTA.SCONN288_ADR50017P130CC(CHIPS)':
 'VSS9': CDS_PINID='VSS9';
NODE_NAME     J11 28
 '@S9S_MB_2U_LIB.S9S_MB_2U(SCH_1):PAGE92_I175@PURE_QUANTA.SCONN288_ADR50017P130CC(CHIPS)':
 'VSS10': CDS_PINID='VSS10';
NODE_NAME     J11 30
 '@S9S_MB_2U_LIB.S9S_MB_2U(SCH_1):PAGE92_I175@PURE_QUANTA.SCONN288_ADR50017P130CC(CHIPS)':
 'VSS11': CDS_PINID='VSS11';
NODE_NAME     J11 32
 '@S9S_MB_2U_LIB.S9S_MB_2U(SCH_1):PAGE92_I175@PURE_QUANTA.SCONN288_ADR50017P130CC(CHIPS)':
 'VSS12': CDS_PINID='VSS12';
NODE_NAME     J11 35
 '@S9S_MB_2U_LIB.S9S_MB_2U(SCH_1):PAGE92_I175@PURE_QUANTA.SCONN288_ADR50017P130CC(CHIPS)':
 'VSS13': CDS_PINID='VSS13';
NODE_NAME     J11 37
 '@S9S_MB_2U_LIB.S9S_MB_2U(SCH_1):PAGE92_I175@PURE_QUANTA.SCONN288_ADR50017P130CC(CHIPS)':
 'VSS14': CDS_PINID='VSS14';
NODE_NAME     J11 39
 '@S9S_MB_2U_LIB.S9S_MB_2U(SCH_1):PAGE92_I175@PURE_QUANTA.SCONN288_ADR50017P130CC(CHIPS)':
 'VSS15': CDS_PINID='VSS15';
NODE_NAME     J11 41
 '@S9S_MB_2U_LIB.S9S_MB_2U(SCH_1):PAGE92_I175@PURE_QUANTA.SCONN288_ADR50017P130CC(CHIPS)':
 'VSS16': CDS_PINID='VSS16';
NODE_NAME     J11 43
 '@S9S_MB_2U_LIB.S9S_MB_2U(SCH_1):PAGE92_I175@PURE_QUANTA.SCONN288_ADR50017P130CC(CHIPS)':
 'VSS17': CDS_PINID='VSS17';
NODE_NAME     J11 46
 '@S9S_MB_2U_LIB.S9S_MB_2U(SCH_1):PAGE92_I175@PURE_QUANTA.SCONN288_ADR50017P130CC(CHIPS)':
 'VSS18': CDS_PINID='VSS18';
NODE_NAME     J11 48
 '@S9S_MB_2U_LIB.S9S_MB_2U(SCH_1):PAGE92_I175@PURE_QUANTA.SCONN288_ADR50017P130CC(CHIPS)':
 'VSS19': CDS_PINID='VSS19';
NODE_NAME     J11 50
 '@S9S_MB_2U_LIB.S9S_MB_2U(SCH_1):PAGE92_I175@PURE_QUANTA.SCONN288_ADR50017P130CC(CHIPS)':
 'VSS20': CDS_PINID='VSS20';
NODE_NAME     J11 52
 '@S9S_MB_2U_LIB.S9S_MB_2U(SCH_1):PAGE92_I175@PURE_QUANTA.SCONN288_ADR50017P130CC(CHIPS)':
 'VSS21': CDS_PINID='VSS21';
NODE_NAME     J11 54
 '@S9S_MB_2U_LIB.S9S_MB_2U(SCH_1):PAGE92_I175@PURE_QUANTA.SCONN288_ADR50017P130CC(CHIPS)':
 'VSS22': CDS_PINID='VSS22';
NODE_NAME     J11 57
 '@S9S_MB_2U_LIB.S9S_MB_2U(SCH_1):PAGE92_I175@PURE_QUANTA.SCONN288_ADR50017P130CC(CHIPS)':
 'VSS23': CDS_PINID='VSS23';
NODE_NAME     J11 59
 '@S9S_MB_2U_LIB.S9S_MB_2U(SCH_1):PAGE92_I175@PURE_QUANTA.SCONN288_ADR50017P130CC(CHIPS)':
 'VSS24': CDS_PINID='VSS24';
NODE_NAME     J11 61
 '@S9S_MB_2U_LIB.S9S_MB_2U(SCH_1):PAGE92_I175@PURE_QUANTA.SCONN288_ADR50017P130CC(CHIPS)':
 'VSS25': CDS_PINID='VSS25';
NODE_NAME     J11 63
 '@S9S_MB_2U_LIB.S9S_MB_2U(SCH_1):PAGE92_I175@PURE_QUANTA.SCONN288_ADR50017P130CC(CHIPS)':
 'VSS26': CDS_PINID='VSS26';
NODE_NAME     J11 65
 '@S9S_MB_2U_LIB.S9S_MB_2U(SCH_1):PAGE92_I175@PURE_QUANTA.SCONN288_ADR50017P130CC(CHIPS)':
 'VSS27': CDS_PINID='VSS27';
NODE_NAME     J11 67
 '@S9S_MB_2U_LIB.S9S_MB_2U(SCH_1):PAGE92_I175@PURE_QUANTA.SCONN288_ADR50017P130CC(CHIPS)':
 'VSS28': CDS_PINID='VSS28';
NODE_NAME     J11 69
 '@S9S_MB_2U_LIB.S9S_MB_2U(SCH_1):PAGE92_I175@PURE_QUANTA.SCONN288_ADR50017P130CC(CHIPS)':
 'VSS29': CDS_PINID='VSS29';
NODE_NAME     J11 71
 '@S9S_MB_2U_LIB.S9S_MB_2U(SCH_1):PAGE92_I175@PURE_QUANTA.SCONN288_ADR50017P130CC(CHIPS)':
 'VSS30': CDS_PINID='VSS30';
NODE_NAME     J11 73
 '@S9S_MB_2U_LIB.S9S_MB_2U(SCH_1):PAGE92_I175@PURE_QUANTA.SCONN288_ADR50017P130CC(CHIPS)':
 'VSS31': CDS_PINID='VSS31';
NODE_NAME     J11 75
 '@S9S_MB_2U_LIB.S9S_MB_2U(SCH_1):PAGE92_I175@PURE_QUANTA.SCONN288_ADR50017P130CC(CHIPS)':
 'VSS32': CDS_PINID='VSS32';
NODE_NAME     J11 77
 '@S9S_MB_2U_LIB.S9S_MB_2U(SCH_1):PAGE92_I175@PURE_QUANTA.SCONN288_ADR50017P130CC(CHIPS)':
 'VSS33': CDS_PINID='VSS33';
NODE_NAME     J11 79
 '@S9S_MB_2U_LIB.S9S_MB_2U(SCH_1):PAGE92_I175@PURE_QUANTA.SCONN288_ADR50017P130CC(CHIPS)':
 'VSS34': CDS_PINID='VSS34';
NODE_NAME     J11 81
 '@S9S_MB_2U_LIB.S9S_MB_2U(SCH_1):PAGE92_I175@PURE_QUANTA.SCONN288_ADR50017P130CC(CHIPS)':
 'VSS35': CDS_PINID='VSS35';
NODE_NAME     J11 83
 '@S9S_MB_2U_LIB.S9S_MB_2U(SCH_1):PAGE92_I175@PURE_QUANTA.SCONN288_ADR50017P130CC(CHIPS)':
 'VSS36': CDS_PINID='VSS36';
NODE_NAME     J11 85
 '@S9S_MB_2U_LIB.S9S_MB_2U(SCH_1):PAGE92_I175@PURE_QUANTA.SCONN288_ADR50017P130CC(CHIPS)':
 'VSS37': CDS_PINID='VSS37';
NODE_NAME     J11 88
 '@S9S_MB_2U_LIB.S9S_MB_2U(SCH_1):PAGE92_I175@PURE_QUANTA.SCONN288_ADR50017P130CC(CHIPS)':
 'VSS38': CDS_PINID='VSS38';
NODE_NAME     J11 90
 '@S9S_MB_2U_LIB.S9S_MB_2U(SCH_1):PAGE92_I175@PURE_QUANTA.SCONN288_ADR50017P130CC(CHIPS)':
 'VSS39': CDS_PINID='VSS39';
NODE_NAME     J11 92
 '@S9S_MB_2U_LIB.S9S_MB_2U(SCH_1):PAGE92_I175@PURE_QUANTA.SCONN288_ADR50017P130CC(CHIPS)':
 'VSS40': CDS_PINID='VSS40';
NODE_NAME     J11 95
 '@S9S_MB_2U_LIB.S9S_MB_2U(SCH_1):PAGE92_I175@PURE_QUANTA.SCONN288_ADR50017P130CC(CHIPS)':
 'VSS41': CDS_PINID='VSS41';
NODE_NAME     J11 97
 '@S9S_MB_2U_LIB.S9S_MB_2U(SCH_1):PAGE92_I175@PURE_QUANTA.SCONN288_ADR50017P130CC(CHIPS)':
 'VSS42': CDS_PINID='VSS42';
NODE_NAME     J11 99
 '@S9S_MB_2U_LIB.S9S_MB_2U(SCH_1):PAGE92_I175@PURE_QUANTA.SCONN288_ADR50017P130CC(CHIPS)':
 'VSS43': CDS_PINID='VSS43';
NODE_NAME     J11 101
 '@S9S_MB_2U_LIB.S9S_MB_2U(SCH_1):PAGE92_I175@PURE_QUANTA.SCONN288_ADR50017P130CC(CHIPS)':
 'VSS44': CDS_PINID='VSS44';
NODE_NAME     J11 103
 '@S9S_MB_2U_LIB.S9S_MB_2U(SCH_1):PAGE92_I175@PURE_QUANTA.SCONN288_ADR50017P130CC(CHIPS)':
 'VSS45': CDS_PINID='VSS45';
NODE_NAME     J11 106
 '@S9S_MB_2U_LIB.S9S_MB_2U(SCH_1):PAGE92_I175@PURE_QUANTA.SCONN288_ADR50017P130CC(CHIPS)':
 'VSS46': CDS_PINID='VSS46';
NODE_NAME     J11 108
 '@S9S_MB_2U_LIB.S9S_MB_2U(SCH_1):PAGE92_I175@PURE_QUANTA.SCONN288_ADR50017P130CC(CHIPS)':
 'VSS47': CDS_PINID='VSS47';
NODE_NAME     J11 110
 '@S9S_MB_2U_LIB.S9S_MB_2U(SCH_1):PAGE92_I175@PURE_QUANTA.SCONN288_ADR50017P130CC(CHIPS)':
 'VSS48': CDS_PINID='VSS48';
NODE_NAME     J11 112
 '@S9S_MB_2U_LIB.S9S_MB_2U(SCH_1):PAGE92_I175@PURE_QUANTA.SCONN288_ADR50017P130CC(CHIPS)':
 'VSS49': CDS_PINID='VSS49';
NODE_NAME     J11 114
 '@S9S_MB_2U_LIB.S9S_MB_2U(SCH_1):PAGE92_I175@PURE_QUANTA.SCONN288_ADR50017P130CC(CHIPS)':
 'VSS50': CDS_PINID='VSS50';
NODE_NAME     J11 117
 '@S9S_MB_2U_LIB.S9S_MB_2U(SCH_1):PAGE92_I175@PURE_QUANTA.SCONN288_ADR50017P130CC(CHIPS)':
 'VSS51': CDS_PINID='VSS51';
NODE_NAME     J11 119
 '@S9S_MB_2U_LIB.S9S_MB_2U(SCH_1):PAGE92_I175@PURE_QUANTA.SCONN288_ADR50017P130CC(CHIPS)':
 'VSS52': CDS_PINID='VSS52';
NODE_NAME     J11 121
 '@S9S_MB_2U_LIB.S9S_MB_2U(SCH_1):PAGE92_I175@PURE_QUANTA.SCONN288_ADR50017P130CC(CHIPS)':
 'VSS53': CDS_PINID='VSS53';
NODE_NAME     J11 123
 '@S9S_MB_2U_LIB.S9S_MB_2U(SCH_1):PAGE92_I175@PURE_QUANTA.SCONN288_ADR50017P130CC(CHIPS)':
 'VSS54': CDS_PINID='VSS54';
NODE_NAME     J11 125
 '@S9S_MB_2U_LIB.S9S_MB_2U(SCH_1):PAGE92_I175@PURE_QUANTA.SCONN288_ADR50017P130CC(CHIPS)':
 'VSS55': CDS_PINID='VSS55';
NODE_NAME     J11 128
 '@S9S_MB_2U_LIB.S9S_MB_2U(SCH_1):PAGE92_I175@PURE_QUANTA.SCONN288_ADR50017P130CC(CHIPS)':
 'VSS56': CDS_PINID='VSS56';
NODE_NAME     J11 130
 '@S9S_MB_2U_LIB.S9S_MB_2U(SCH_1):PAGE92_I175@PURE_QUANTA.SCONN288_ADR50017P130CC(CHIPS)':
 'VSS57': CDS_PINID='VSS57';
NODE_NAME     J11 132
 '@S9S_MB_2U_LIB.S9S_MB_2U(SCH_1):PAGE92_I175@PURE_QUANTA.SCONN288_ADR50017P130CC(CHIPS)':
 'VSS58': CDS_PINID='VSS58';
NODE_NAME     J11 134
 '@S9S_MB_2U_LIB.S9S_MB_2U(SCH_1):PAGE92_I175@PURE_QUANTA.SCONN288_ADR50017P130CC(CHIPS)':
 'VSS59': CDS_PINID='VSS59';
NODE_NAME     J11 136
 '@S9S_MB_2U_LIB.S9S_MB_2U(SCH_1):PAGE92_I175@PURE_QUANTA.SCONN288_ADR50017P130CC(CHIPS)':
 'VSS60': CDS_PINID='VSS60';
NODE_NAME     J11 139
 '@S9S_MB_2U_LIB.S9S_MB_2U(SCH_1):PAGE92_I175@PURE_QUANTA.SCONN288_ADR50017P130CC(CHIPS)':
 'VSS61': CDS_PINID='VSS61';
NODE_NAME     J11 141
 '@S9S_MB_2U_LIB.S9S_MB_2U(SCH_1):PAGE92_I175@PURE_QUANTA.SCONN288_ADR50017P130CC(CHIPS)':
 'VSS62': CDS_PINID='VSS62';
NODE_NAME     J11 143
 '@S9S_MB_2U_LIB.S9S_MB_2U(SCH_1):PAGE92_I175@PURE_QUANTA.SCONN288_ADR50017P130CC(CHIPS)':
 'VSS63': CDS_PINID='VSS63';
NODE_NAME     J11 151
 '@S9S_MB_2U_LIB.S9S_MB_2U(SCH_1):PAGE92_I175@PURE_QUANTA.SCONN288_ADR50017P130CC(CHIPS)':
 'VSS64': CDS_PINID='VSS64';
NODE_NAME     J11 153
 '@S9S_MB_2U_LIB.S9S_MB_2U(SCH_1):PAGE92_I175@PURE_QUANTA.SCONN288_ADR50017P130CC(CHIPS)':
 'VSS65': CDS_PINID='VSS65';
NODE_NAME     J11 155
 '@S9S_MB_2U_LIB.S9S_MB_2U(SCH_1):PAGE92_I175@PURE_QUANTA.SCONN288_ADR50017P130CC(CHIPS)':
 'VSS66': CDS_PINID='VSS66';
NODE_NAME     J11 158
 '@S9S_MB_2U_LIB.S9S_MB_2U(SCH_1):PAGE92_I175@PURE_QUANTA.SCONN288_ADR50017P130CC(CHIPS)':
 'VSS67': CDS_PINID='VSS67';
NODE_NAME     J11 160
 '@S9S_MB_2U_LIB.S9S_MB_2U(SCH_1):PAGE92_I175@PURE_QUANTA.SCONN288_ADR50017P130CC(CHIPS)':
 'VSS68': CDS_PINID='VSS68';
NODE_NAME     J11 162
 '@S9S_MB_2U_LIB.S9S_MB_2U(SCH_1):PAGE92_I175@PURE_QUANTA.SCONN288_ADR50017P130CC(CHIPS)':
 'VSS69': CDS_PINID='VSS69';
NODE_NAME     J11 164
 '@S9S_MB_2U_LIB.S9S_MB_2U(SCH_1):PAGE92_I175@PURE_QUANTA.SCONN288_ADR50017P130CC(CHIPS)':
 'VSS70': CDS_PINID='VSS70';
NODE_NAME     J11 166
 '@S9S_MB_2U_LIB.S9S_MB_2U(SCH_1):PAGE92_I175@PURE_QUANTA.SCONN288_ADR50017P130CC(CHIPS)':
 'VSS71': CDS_PINID='VSS71';
NODE_NAME     J11 169
 '@S9S_MB_2U_LIB.S9S_MB_2U(SCH_1):PAGE92_I175@PURE_QUANTA.SCONN288_ADR50017P130CC(CHIPS)':
 'VSS72': CDS_PINID='VSS72';
NODE_NAME     J11 171
 '@S9S_MB_2U_LIB.S9S_MB_2U(SCH_1):PAGE92_I175@PURE_QUANTA.SCONN288_ADR50017P130CC(CHIPS)':
 'VSS73': CDS_PINID='VSS73';
NODE_NAME     J11 173
 '@S9S_MB_2U_LIB.S9S_MB_2U(SCH_1):PAGE92_I175@PURE_QUANTA.SCONN288_ADR50017P130CC(CHIPS)':
 'VSS74': CDS_PINID='VSS74';
NODE_NAME     J11 175
 '@S9S_MB_2U_LIB.S9S_MB_2U(SCH_1):PAGE92_I175@PURE_QUANTA.SCONN288_ADR50017P130CC(CHIPS)':
 'VSS75': CDS_PINID='VSS75';
NODE_NAME     J11 177
 '@S9S_MB_2U_LIB.S9S_MB_2U(SCH_1):PAGE92_I175@PURE_QUANTA.SCONN288_ADR50017P130CC(CHIPS)':
 'VSS76': CDS_PINID='VSS76';
NODE_NAME     J11 180
 '@S9S_MB_2U_LIB.S9S_MB_2U(SCH_1):PAGE92_I175@PURE_QUANTA.SCONN288_ADR50017P130CC(CHIPS)':
 'VSS77': CDS_PINID='VSS77';
NODE_NAME     J11 182
 '@S9S_MB_2U_LIB.S9S_MB_2U(SCH_1):PAGE92_I175@PURE_QUANTA.SCONN288_ADR50017P130CC(CHIPS)':
 'VSS78': CDS_PINID='VSS78';
NODE_NAME     J11 184
 '@S9S_MB_2U_LIB.S9S_MB_2U(SCH_1):PAGE92_I175@PURE_QUANTA.SCONN288_ADR50017P130CC(CHIPS)':
 'VSS79': CDS_PINID='VSS79';
NODE_NAME     J11 186
 '@S9S_MB_2U_LIB.S9S_MB_2U(SCH_1):PAGE92_I175@PURE_QUANTA.SCONN288_ADR50017P130CC(CHIPS)':
 'VSS80': CDS_PINID='VSS80';
NODE_NAME     J11 188
 '@S9S_MB_2U_LIB.S9S_MB_2U(SCH_1):PAGE92_I175@PURE_QUANTA.SCONN288_ADR50017P130CC(CHIPS)':
 'VSS81': CDS_PINID='VSS81';
NODE_NAME     J11 191
 '@S9S_MB_2U_LIB.S9S_MB_2U(SCH_1):PAGE92_I175@PURE_QUANTA.SCONN288_ADR50017P130CC(CHIPS)':
 'VSS82': CDS_PINID='VSS82';
NODE_NAME     J11 193
 '@S9S_MB_2U_LIB.S9S_MB_2U(SCH_1):PAGE92_I175@PURE_QUANTA.SCONN288_ADR50017P130CC(CHIPS)':
 'VSS83': CDS_PINID='VSS83';
NODE_NAME     J11 195
 '@S9S_MB_2U_LIB.S9S_MB_2U(SCH_1):PAGE92_I175@PURE_QUANTA.SCONN288_ADR50017P130CC(CHIPS)':
 'VSS84': CDS_PINID='VSS84';
NODE_NAME     J11 197
 '@S9S_MB_2U_LIB.S9S_MB_2U(SCH_1):PAGE92_I175@PURE_QUANTA.SCONN288_ADR50017P130CC(CHIPS)':
 'VSS85': CDS_PINID='VSS85';
NODE_NAME     J11 199
 '@S9S_MB_2U_LIB.S9S_MB_2U(SCH_1):PAGE92_I175@PURE_QUANTA.SCONN288_ADR50017P130CC(CHIPS)':
 'VSS86': CDS_PINID='VSS86';
NODE_NAME     J11 202
 '@S9S_MB_2U_LIB.S9S_MB_2U(SCH_1):PAGE92_I175@PURE_QUANTA.SCONN288_ADR50017P130CC(CHIPS)':
 'VSS87': CDS_PINID='VSS87';
NODE_NAME     J11 204
 '@S9S_MB_2U_LIB.S9S_MB_2U(SCH_1):PAGE92_I175@PURE_QUANTA.SCONN288_ADR50017P130CC(CHIPS)':
 'VSS88': CDS_PINID='VSS88';
NODE_NAME     J11 206
 '@S9S_MB_2U_LIB.S9S_MB_2U(SCH_1):PAGE92_I175@PURE_QUANTA.SCONN288_ADR50017P130CC(CHIPS)':
 'VSS89': CDS_PINID='VSS89';
NODE_NAME     J11 208
 '@S9S_MB_2U_LIB.S9S_MB_2U(SCH_1):PAGE92_I175@PURE_QUANTA.SCONN288_ADR50017P130CC(CHIPS)':
 'VSS90': CDS_PINID='VSS90';
NODE_NAME     J11 210
 '@S9S_MB_2U_LIB.S9S_MB_2U(SCH_1):PAGE92_I175@PURE_QUANTA.SCONN288_ADR50017P130CC(CHIPS)':
 'VSS91': CDS_PINID='VSS91';
NODE_NAME     J11 212
 '@S9S_MB_2U_LIB.S9S_MB_2U(SCH_1):PAGE92_I175@PURE_QUANTA.SCONN288_ADR50017P130CC(CHIPS)':
 'VSS92': CDS_PINID='VSS92';
NODE_NAME     J11 214
 '@S9S_MB_2U_LIB.S9S_MB_2U(SCH_1):PAGE92_I175@PURE_QUANTA.SCONN288_ADR50017P130CC(CHIPS)':
 'VSS93': CDS_PINID='VSS93';
NODE_NAME     J11 216
 '@S9S_MB_2U_LIB.S9S_MB_2U(SCH_1):PAGE92_I175@PURE_QUANTA.SCONN288_ADR50017P130CC(CHIPS)':
 'VSS94': CDS_PINID='VSS94';
NODE_NAME     J11 219
 '@S9S_MB_2U_LIB.S9S_MB_2U(SCH_1):PAGE92_I175@PURE_QUANTA.SCONN288_ADR50017P130CC(CHIPS)':
 'VSS95': CDS_PINID='VSS95';
NODE_NAME     J11 222
 '@S9S_MB_2U_LIB.S9S_MB_2U(SCH_1):PAGE92_I175@PURE_QUANTA.SCONN288_ADR50017P130CC(CHIPS)':
 'VSS96': CDS_PINID='VSS96';
NODE_NAME     J11 224
 '@S9S_MB_2U_LIB.S9S_MB_2U(SCH_1):PAGE92_I175@PURE_QUANTA.SCONN288_ADR50017P130CC(CHIPS)':
 'VSS97': CDS_PINID='VSS97';
NODE_NAME     J11 226
 '@S9S_MB_2U_LIB.S9S_MB_2U(SCH_1):PAGE92_I175@PURE_QUANTA.SCONN288_ADR50017P130CC(CHIPS)':
 'VSS98': CDS_PINID='VSS98';
NODE_NAME     J11 228
 '@S9S_MB_2U_LIB.S9S_MB_2U(SCH_1):PAGE92_I175@PURE_QUANTA.SCONN288_ADR50017P130CC(CHIPS)':
 'VSS99': CDS_PINID='VSS99';
NODE_NAME     J11 230
 '@S9S_MB_2U_LIB.S9S_MB_2U(SCH_1):PAGE92_I175@PURE_QUANTA.SCONN288_ADR50017P130CC(CHIPS)':
 'VSS100': CDS_PINID='VSS100';
NODE_NAME     J11 233
 '@S9S_MB_2U_LIB.S9S_MB_2U(SCH_1):PAGE92_I175@PURE_QUANTA.SCONN288_ADR50017P130CC(CHIPS)':
 'VSS101': CDS_PINID='VSS101';
NODE_NAME     J11 235
 '@S9S_MB_2U_LIB.S9S_MB_2U(SCH_1):PAGE92_I175@PURE_QUANTA.SCONN288_ADR50017P130CC(CHIPS)':
 'VSS102': CDS_PINID='VSS102';
NODE_NAME     J11 237
 '@S9S_MB_2U_LIB.S9S_MB_2U(SCH_1):PAGE92_I175@PURE_QUANTA.SCONN288_ADR50017P130CC(CHIPS)':
 'VSS103': CDS_PINID='VSS103';
NODE_NAME     J11 240
 '@S9S_MB_2U_LIB.S9S_MB_2U(SCH_1):PAGE92_I175@PURE_QUANTA.SCONN288_ADR50017P130CC(CHIPS)':
 'VSS104': CDS_PINID='VSS104';
NODE_NAME     J11 242
 '@S9S_MB_2U_LIB.S9S_MB_2U(SCH_1):PAGE92_I175@PURE_QUANTA.SCONN288_ADR50017P130CC(CHIPS)':
 'VSS105': CDS_PINID='VSS105';
NODE_NAME     J11 244
 '@S9S_MB_2U_LIB.S9S_MB_2U(SCH_1):PAGE92_I175@PURE_QUANTA.SCONN288_ADR50017P130CC(CHIPS)':
 'VSS106': CDS_PINID='VSS106';
NODE_NAME     J11 246
 '@S9S_MB_2U_LIB.S9S_MB_2U(SCH_1):PAGE92_I175@PURE_QUANTA.SCONN288_ADR50017P130CC(CHIPS)':
 'VSS107': CDS_PINID='VSS107';
NODE_NAME     J11 248
 '@S9S_MB_2U_LIB.S9S_MB_2U(SCH_1):PAGE92_I175@PURE_QUANTA.SCONN288_ADR50017P130CC(CHIPS)':
 'VSS108': CDS_PINID='VSS108';
NODE_NAME     J11 251
 '@S9S_MB_2U_LIB.S9S_MB_2U(SCH_1):PAGE92_I175@PURE_QUANTA.SCONN288_ADR50017P130CC(CHIPS)':
 'VSS109': CDS_PINID='VSS109';
NODE_NAME     J11 253
 '@S9S_MB_2U_LIB.S9S_MB_2U(SCH_1):PAGE92_I175@PURE_QUANTA.SCONN288_ADR50017P130CC(CHIPS)':
 'VSS110': CDS_PINID='VSS110';
NODE_NAME     J11 255
 '@S9S_MB_2U_LIB.S9S_MB_2U(SCH_1):PAGE92_I175@PURE_QUANTA.SCONN288_ADR50017P130CC(CHIPS)':
 'VSS111': CDS_PINID='VSS111';
NODE_NAME     J11 257
 '@S9S_MB_2U_LIB.S9S_MB_2U(SCH_1):PAGE92_I175@PURE_QUANTA.SCONN288_ADR50017P130CC(CHIPS)':
 'VSS112': CDS_PINID='VSS112';
NODE_NAME     J11 259
 '@S9S_MB_2U_LIB.S9S_MB_2U(SCH_1):PAGE92_I175@PURE_QUANTA.SCONN288_ADR50017P130CC(CHIPS)':
 'VSS113': CDS_PINID='VSS113';
NODE_NAME     J11 262
 '@S9S_MB_2U_LIB.S9S_MB_2U(SCH_1):PAGE92_I175@PURE_QUANTA.SCONN288_ADR50017P130CC(CHIPS)':
 'VSS114': CDS_PINID='VSS114';
NODE_NAME     J11 264
 '@S9S_MB_2U_LIB.S9S_MB_2U(SCH_1):PAGE92_I175@PURE_QUANTA.SCONN288_ADR50017P130CC(CHIPS)':
 'VSS115': CDS_PINID='VSS115';
NODE_NAME     J11 266
 '@S9S_MB_2U_LIB.S9S_MB_2U(SCH_1):PAGE92_I175@PURE_QUANTA.SCONN288_ADR50017P130CC(CHIPS)':
 'VSS116': CDS_PINID='VSS116';
NODE_NAME     J11 268
 '@S9S_MB_2U_LIB.S9S_MB_2U(SCH_1):PAGE92_I175@PURE_QUANTA.SCONN288_ADR50017P130CC(CHIPS)':
 'VSS117': CDS_PINID='VSS117';
NODE_NAME     J11 270
 '@S9S_MB_2U_LIB.S9S_MB_2U(SCH_1):PAGE92_I175@PURE_QUANTA.SCONN288_ADR50017P130CC(CHIPS)':
 'VSS118': CDS_PINID='VSS118';
NODE_NAME     J11 273
 '@S9S_MB_2U_LIB.S9S_MB_2U(SCH_1):PAGE92_I175@PURE_QUANTA.SCONN288_ADR50017P130CC(CHIPS)':
 'VSS119': CDS_PINID='VSS119';
NODE_NAME     J11 275
 '@S9S_MB_2U_LIB.S9S_MB_2U(SCH_1):PAGE92_I175@PURE_QUANTA.SCONN288_ADR50017P130CC(CHIPS)':
 'VSS120': CDS_PINID='VSS120';
NODE_NAME     J11 277
 '@S9S_MB_2U_LIB.S9S_MB_2U(SCH_1):PAGE92_I175@PURE_QUANTA.SCONN288_ADR50017P130CC(CHIPS)':
 'VSS121': CDS_PINID='VSS121';
NODE_NAME     J11 279
 '@S9S_MB_2U_LIB.S9S_MB_2U(SCH_1):PAGE92_I175@PURE_QUANTA.SCONN288_ADR50017P130CC(CHIPS)':
 'VSS122': CDS_PINID='VSS122';
NODE_NAME     J11 281
 '@S9S_MB_2U_LIB.S9S_MB_2U(SCH_1):PAGE92_I175@PURE_QUANTA.SCONN288_ADR50017P130CC(CHIPS)':
 'VSS123': CDS_PINID='VSS123';
NODE_NAME     J11 284
 '@S9S_MB_2U_LIB.S9S_MB_2U(SCH_1):PAGE92_I175@PURE_QUANTA.SCONN288_ADR50017P130CC(CHIPS)':
 'VSS124': CDS_PINID='VSS124';
NODE_NAME     J11 286
 '@S9S_MB_2U_LIB.S9S_MB_2U(SCH_1):PAGE92_I175@PURE_QUANTA.SCONN288_ADR50017P130CC(CHIPS)':
 'VSS125': CDS_PINID='VSS125';
NODE_NAME     J11 288
 '@S9S_MB_2U_LIB.S9S_MB_2U(SCH_1):PAGE92_I175@PURE_QUANTA.SCONN288_ADR50017P130CC(CHIPS)':
 'VSS126': CDS_PINID='VSS126';
NODE_NAME     R37 2
 '@S9S_MB_2U_LIB.S9S_MB_2U(SCH_1):PAGE93_I2@PURE_QUANTA.Q_RES(CHIPS)':
 'B': CDS_PINID='B';
NODE_NAME     C35 2
 '@S9S_MB_2U_LIB.S9S_MB_2U(SCH_1):PAGE93_I122@PURE_QUANTA.Q_CAP(CHIPS)':
 'B': CDS_PINID='B';
NODE_NAME     C36 2
 '@S9S_MB_2U_LIB.S9S_MB_2U(SCH_1):PAGE93_I126@PURE_QUANTA.Q_CAP(CHIPS)':
 'B': CDS_PINID='B';
NODE_NAME     C37 2
 '@S9S_MB_2U_LIB.S9S_MB_2U(SCH_1):PAGE93_I128@PURE_QUANTA.Q_CAP(CHIPS)':
 'B': CDS_PINID='B';
NODE_NAME     J12 G1
 '@S9S_MB_2U_LIB.S9S_MB_2U(SCH_1):PAGE93_I175@PURE_QUANTA.SCONN288_ADR50017P087CC(CHIPS)':
 'G1': CDS_PINID='G1';
NODE_NAME     J12 G2
 '@S9S_MB_2U_LIB.S9S_MB_2U(SCH_1):PAGE93_I175@PURE_QUANTA.SCONN288_ADR50017P087CC(CHIPS)':
 'G2': CDS_PINID='G2';
NODE_NAME     J12 G3
 '@S9S_MB_2U_LIB.S9S_MB_2U(SCH_1):PAGE93_I175@PURE_QUANTA.SCONN288_ADR50017P087CC(CHIPS)':
 'G3': CDS_PINID='G3';
NODE_NAME     J12 6
 '@S9S_MB_2U_LIB.S9S_MB_2U(SCH_1):PAGE93_I175@PURE_QUANTA.SCONN288_ADR50017P087CC(CHIPS)':
 'VSS0': CDS_PINID='VSS0';
NODE_NAME     J12 8
 '@S9S_MB_2U_LIB.S9S_MB_2U(SCH_1):PAGE93_I175@PURE_QUANTA.SCONN288_ADR50017P087CC(CHIPS)':
 'VSS1': CDS_PINID='VSS1';
NODE_NAME     J12 10
 '@S9S_MB_2U_LIB.S9S_MB_2U(SCH_1):PAGE93_I175@PURE_QUANTA.SCONN288_ADR50017P087CC(CHIPS)':
 'VSS2': CDS_PINID='VSS2';
NODE_NAME     J12 13
 '@S9S_MB_2U_LIB.S9S_MB_2U(SCH_1):PAGE93_I175@PURE_QUANTA.SCONN288_ADR50017P087CC(CHIPS)':
 'VSS3': CDS_PINID='VSS3';
NODE_NAME     J12 15
 '@S9S_MB_2U_LIB.S9S_MB_2U(SCH_1):PAGE93_I175@PURE_QUANTA.SCONN288_ADR50017P087CC(CHIPS)':
 'VSS4': CDS_PINID='VSS4';
NODE_NAME     J12 17
 '@S9S_MB_2U_LIB.S9S_MB_2U(SCH_1):PAGE93_I175@PURE_QUANTA.SCONN288_ADR50017P087CC(CHIPS)':
 'VSS5': CDS_PINID='VSS5';
NODE_NAME     J12 19
 '@S9S_MB_2U_LIB.S9S_MB_2U(SCH_1):PAGE93_I175@PURE_QUANTA.SCONN288_ADR50017P087CC(CHIPS)':
 'VSS6': CDS_PINID='VSS6';
NODE_NAME     J12 21
 '@S9S_MB_2U_LIB.S9S_MB_2U(SCH_1):PAGE93_I175@PURE_QUANTA.SCONN288_ADR50017P087CC(CHIPS)':
 'VSS7': CDS_PINID='VSS7';
NODE_NAME     J12 24
 '@S9S_MB_2U_LIB.S9S_MB_2U(SCH_1):PAGE93_I175@PURE_QUANTA.SCONN288_ADR50017P087CC(CHIPS)':
 'VSS8': CDS_PINID='VSS8';
NODE_NAME     J12 26
 '@S9S_MB_2U_LIB.S9S_MB_2U(SCH_1):PAGE93_I175@PURE_QUANTA.SCONN288_ADR50017P087CC(CHIPS)':
 'VSS9': CDS_PINID='VSS9';
NODE_NAME     J12 28
 '@S9S_MB_2U_LIB.S9S_MB_2U(SCH_1):PAGE93_I175@PURE_QUANTA.SCONN288_ADR50017P087CC(CHIPS)':
 'VSS10': CDS_PINID='VSS10';
NODE_NAME     J12 30
 '@S9S_MB_2U_LIB.S9S_MB_2U(SCH_1):PAGE93_I175@PURE_QUANTA.SCONN288_ADR50017P087CC(CHIPS)':
 'VSS11': CDS_PINID='VSS11';
NODE_NAME     J12 32
 '@S9S_MB_2U_LIB.S9S_MB_2U(SCH_1):PAGE93_I175@PURE_QUANTA.SCONN288_ADR50017P087CC(CHIPS)':
 'VSS12': CDS_PINID='VSS12';
NODE_NAME     J12 35
 '@S9S_MB_2U_LIB.S9S_MB_2U(SCH_1):PAGE93_I175@PURE_QUANTA.SCONN288_ADR50017P087CC(CHIPS)':
 'VSS13': CDS_PINID='VSS13';
NODE_NAME     J12 37
 '@S9S_MB_2U_LIB.S9S_MB_2U(SCH_1):PAGE93_I175@PURE_QUANTA.SCONN288_ADR50017P087CC(CHIPS)':
 'VSS14': CDS_PINID='VSS14';
NODE_NAME     J12 39
 '@S9S_MB_2U_LIB.S9S_MB_2U(SCH_1):PAGE93_I175@PURE_QUANTA.SCONN288_ADR50017P087CC(CHIPS)':
 'VSS15': CDS_PINID='VSS15';
NODE_NAME     J12 41
 '@S9S_MB_2U_LIB.S9S_MB_2U(SCH_1):PAGE93_I175@PURE_QUANTA.SCONN288_ADR50017P087CC(CHIPS)':
 'VSS16': CDS_PINID='VSS16';
NODE_NAME     J12 43
 '@S9S_MB_2U_LIB.S9S_MB_2U(SCH_1):PAGE93_I175@PURE_QUANTA.SCONN288_ADR50017P087CC(CHIPS)':
 'VSS17': CDS_PINID='VSS17';
NODE_NAME     J12 46
 '@S9S_MB_2U_LIB.S9S_MB_2U(SCH_1):PAGE93_I175@PURE_QUANTA.SCONN288_ADR50017P087CC(CHIPS)':
 'VSS18': CDS_PINID='VSS18';
NODE_NAME     J12 48
 '@S9S_MB_2U_LIB.S9S_MB_2U(SCH_1):PAGE93_I175@PURE_QUANTA.SCONN288_ADR50017P087CC(CHIPS)':
 'VSS19': CDS_PINID='VSS19';
NODE_NAME     J12 50
 '@S9S_MB_2U_LIB.S9S_MB_2U(SCH_1):PAGE93_I175@PURE_QUANTA.SCONN288_ADR50017P087CC(CHIPS)':
 'VSS20': CDS_PINID='VSS20';
NODE_NAME     J12 52
 '@S9S_MB_2U_LIB.S9S_MB_2U(SCH_1):PAGE93_I175@PURE_QUANTA.SCONN288_ADR50017P087CC(CHIPS)':
 'VSS21': CDS_PINID='VSS21';
NODE_NAME     J12 54
 '@S9S_MB_2U_LIB.S9S_MB_2U(SCH_1):PAGE93_I175@PURE_QUANTA.SCONN288_ADR50017P087CC(CHIPS)':
 'VSS22': CDS_PINID='VSS22';
NODE_NAME     J12 57
 '@S9S_MB_2U_LIB.S9S_MB_2U(SCH_1):PAGE93_I175@PURE_QUANTA.SCONN288_ADR50017P087CC(CHIPS)':
 'VSS23': CDS_PINID='VSS23';
NODE_NAME     J12 59
 '@S9S_MB_2U_LIB.S9S_MB_2U(SCH_1):PAGE93_I175@PURE_QUANTA.SCONN288_ADR50017P087CC(CHIPS)':
 'VSS24': CDS_PINID='VSS24';
NODE_NAME     J12 61
 '@S9S_MB_2U_LIB.S9S_MB_2U(SCH_1):PAGE93_I175@PURE_QUANTA.SCONN288_ADR50017P087CC(CHIPS)':
 'VSS25': CDS_PINID='VSS25';
NODE_NAME     J12 63
 '@S9S_MB_2U_LIB.S9S_MB_2U(SCH_1):PAGE93_I175@PURE_QUANTA.SCONN288_ADR50017P087CC(CHIPS)':
 'VSS26': CDS_PINID='VSS26';
NODE_NAME     J12 65
 '@S9S_MB_2U_LIB.S9S_MB_2U(SCH_1):PAGE93_I175@PURE_QUANTA.SCONN288_ADR50017P087CC(CHIPS)':
 'VSS27': CDS_PINID='VSS27';
NODE_NAME     J12 67
 '@S9S_MB_2U_LIB.S9S_MB_2U(SCH_1):PAGE93_I175@PURE_QUANTA.SCONN288_ADR50017P087CC(CHIPS)':
 'VSS28': CDS_PINID='VSS28';
NODE_NAME     J12 69
 '@S9S_MB_2U_LIB.S9S_MB_2U(SCH_1):PAGE93_I175@PURE_QUANTA.SCONN288_ADR50017P087CC(CHIPS)':
 'VSS29': CDS_PINID='VSS29';
NODE_NAME     J12 71
 '@S9S_MB_2U_LIB.S9S_MB_2U(SCH_1):PAGE93_I175@PURE_QUANTA.SCONN288_ADR50017P087CC(CHIPS)':
 'VSS30': CDS_PINID='VSS30';
NODE_NAME     J12 73
 '@S9S_MB_2U_LIB.S9S_MB_2U(SCH_1):PAGE93_I175@PURE_QUANTA.SCONN288_ADR50017P087CC(CHIPS)':
 'VSS31': CDS_PINID='VSS31';
NODE_NAME     J12 75
 '@S9S_MB_2U_LIB.S9S_MB_2U(SCH_1):PAGE93_I175@PURE_QUANTA.SCONN288_ADR50017P087CC(CHIPS)':
 'VSS32': CDS_PINID='VSS32';
NODE_NAME     J12 77
 '@S9S_MB_2U_LIB.S9S_MB_2U(SCH_1):PAGE93_I175@PURE_QUANTA.SCONN288_ADR50017P087CC(CHIPS)':
 'VSS33': CDS_PINID='VSS33';
NODE_NAME     J12 79
 '@S9S_MB_2U_LIB.S9S_MB_2U(SCH_1):PAGE93_I175@PURE_QUANTA.SCONN288_ADR50017P087CC(CHIPS)':
 'VSS34': CDS_PINID='VSS34';
NODE_NAME     J12 81
 '@S9S_MB_2U_LIB.S9S_MB_2U(SCH_1):PAGE93_I175@PURE_QUANTA.SCONN288_ADR50017P087CC(CHIPS)':
 'VSS35': CDS_PINID='VSS35';
NODE_NAME     J12 83
 '@S9S_MB_2U_LIB.S9S_MB_2U(SCH_1):PAGE93_I175@PURE_QUANTA.SCONN288_ADR50017P087CC(CHIPS)':
 'VSS36': CDS_PINID='VSS36';
NODE_NAME     J12 85
 '@S9S_MB_2U_LIB.S9S_MB_2U(SCH_1):PAGE93_I175@PURE_QUANTA.SCONN288_ADR50017P087CC(CHIPS)':
 'VSS37': CDS_PINID='VSS37';
NODE_NAME     J12 88
 '@S9S_MB_2U_LIB.S9S_MB_2U(SCH_1):PAGE93_I175@PURE_QUANTA.SCONN288_ADR50017P087CC(CHIPS)':
 'VSS38': CDS_PINID='VSS38';
NODE_NAME     J12 90
 '@S9S_MB_2U_LIB.S9S_MB_2U(SCH_1):PAGE93_I175@PURE_QUANTA.SCONN288_ADR50017P087CC(CHIPS)':
 'VSS39': CDS_PINID='VSS39';
NODE_NAME     J12 92
 '@S9S_MB_2U_LIB.S9S_MB_2U(SCH_1):PAGE93_I175@PURE_QUANTA.SCONN288_ADR50017P087CC(CHIPS)':
 'VSS40': CDS_PINID='VSS40';
NODE_NAME     J12 95
 '@S9S_MB_2U_LIB.S9S_MB_2U(SCH_1):PAGE93_I175@PURE_QUANTA.SCONN288_ADR50017P087CC(CHIPS)':
 'VSS41': CDS_PINID='VSS41';
NODE_NAME     J12 97
 '@S9S_MB_2U_LIB.S9S_MB_2U(SCH_1):PAGE93_I175@PURE_QUANTA.SCONN288_ADR50017P087CC(CHIPS)':
 'VSS42': CDS_PINID='VSS42';
NODE_NAME     J12 99
 '@S9S_MB_2U_LIB.S9S_MB_2U(SCH_1):PAGE93_I175@PURE_QUANTA.SCONN288_ADR50017P087CC(CHIPS)':
 'VSS43': CDS_PINID='VSS43';
NODE_NAME     J12 101
 '@S9S_MB_2U_LIB.S9S_MB_2U(SCH_1):PAGE93_I175@PURE_QUANTA.SCONN288_ADR50017P087CC(CHIPS)':
 'VSS44': CDS_PINID='VSS44';
NODE_NAME     J12 103
 '@S9S_MB_2U_LIB.S9S_MB_2U(SCH_1):PAGE93_I175@PURE_QUANTA.SCONN288_ADR50017P087CC(CHIPS)':
 'VSS45': CDS_PINID='VSS45';
NODE_NAME     J12 106
 '@S9S_MB_2U_LIB.S9S_MB_2U(SCH_1):PAGE93_I175@PURE_QUANTA.SCONN288_ADR50017P087CC(CHIPS)':
 'VSS46': CDS_PINID='VSS46';
NODE_NAME     J12 108
 '@S9S_MB_2U_LIB.S9S_MB_2U(SCH_1):PAGE93_I175@PURE_QUANTA.SCONN288_ADR50017P087CC(CHIPS)':
 'VSS47': CDS_PINID='VSS47';
NODE_NAME     J12 110
 '@S9S_MB_2U_LIB.S9S_MB_2U(SCH_1):PAGE93_I175@PURE_QUANTA.SCONN288_ADR50017P087CC(CHIPS)':
 'VSS48': CDS_PINID='VSS48';
NODE_NAME     J12 112
 '@S9S_MB_2U_LIB.S9S_MB_2U(SCH_1):PAGE93_I175@PURE_QUANTA.SCONN288_ADR50017P087CC(CHIPS)':
 'VSS49': CDS_PINID='VSS49';
NODE_NAME     J12 114
 '@S9S_MB_2U_LIB.S9S_MB_2U(SCH_1):PAGE93_I175@PURE_QUANTA.SCONN288_ADR50017P087CC(CHIPS)':
 'VSS50': CDS_PINID='VSS50';
NODE_NAME     J12 117
 '@S9S_MB_2U_LIB.S9S_MB_2U(SCH_1):PAGE93_I175@PURE_QUANTA.SCONN288_ADR50017P087CC(CHIPS)':
 'VSS51': CDS_PINID='VSS51';
NODE_NAME     J12 119
 '@S9S_MB_2U_LIB.S9S_MB_2U(SCH_1):PAGE93_I175@PURE_QUANTA.SCONN288_ADR50017P087CC(CHIPS)':
 'VSS52': CDS_PINID='VSS52';
NODE_NAME     J12 121
 '@S9S_MB_2U_LIB.S9S_MB_2U(SCH_1):PAGE93_I175@PURE_QUANTA.SCONN288_ADR50017P087CC(CHIPS)':
 'VSS53': CDS_PINID='VSS53';
NODE_NAME     J12 123
 '@S9S_MB_2U_LIB.S9S_MB_2U(SCH_1):PAGE93_I175@PURE_QUANTA.SCONN288_ADR50017P087CC(CHIPS)':
 'VSS54': CDS_PINID='VSS54';
NODE_NAME     J12 125
 '@S9S_MB_2U_LIB.S9S_MB_2U(SCH_1):PAGE93_I175@PURE_QUANTA.SCONN288_ADR50017P087CC(CHIPS)':
 'VSS55': CDS_PINID='VSS55';
NODE_NAME     J12 128
 '@S9S_MB_2U_LIB.S9S_MB_2U(SCH_1):PAGE93_I175@PURE_QUANTA.SCONN288_ADR50017P087CC(CHIPS)':
 'VSS56': CDS_PINID='VSS56';
NODE_NAME     J12 130
 '@S9S_MB_2U_LIB.S9S_MB_2U(SCH_1):PAGE93_I175@PURE_QUANTA.SCONN288_ADR50017P087CC(CHIPS)':
 'VSS57': CDS_PINID='VSS57';
NODE_NAME     J12 132
 '@S9S_MB_2U_LIB.S9S_MB_2U(SCH_1):PAGE93_I175@PURE_QUANTA.SCONN288_ADR50017P087CC(CHIPS)':
 'VSS58': CDS_PINID='VSS58';
NODE_NAME     J12 134
 '@S9S_MB_2U_LIB.S9S_MB_2U(SCH_1):PAGE93_I175@PURE_QUANTA.SCONN288_ADR50017P087CC(CHIPS)':
 'VSS59': CDS_PINID='VSS59';
NODE_NAME     J12 136
 '@S9S_MB_2U_LIB.S9S_MB_2U(SCH_1):PAGE93_I175@PURE_QUANTA.SCONN288_ADR50017P087CC(CHIPS)':
 'VSS60': CDS_PINID='VSS60';
NODE_NAME     J12 139
 '@S9S_MB_2U_LIB.S9S_MB_2U(SCH_1):PAGE93_I175@PURE_QUANTA.SCONN288_ADR50017P087CC(CHIPS)':
 'VSS61': CDS_PINID='VSS61';
NODE_NAME     J12 141
 '@S9S_MB_2U_LIB.S9S_MB_2U(SCH_1):PAGE93_I175@PURE_QUANTA.SCONN288_ADR50017P087CC(CHIPS)':
 'VSS62': CDS_PINID='VSS62';
NODE_NAME     J12 143
 '@S9S_MB_2U_LIB.S9S_MB_2U(SCH_1):PAGE93_I175@PURE_QUANTA.SCONN288_ADR50017P087CC(CHIPS)':
 'VSS63': CDS_PINID='VSS63';
NODE_NAME     J12 151
 '@S9S_MB_2U_LIB.S9S_MB_2U(SCH_1):PAGE93_I175@PURE_QUANTA.SCONN288_ADR50017P087CC(CHIPS)':
 'VSS64': CDS_PINID='VSS64';
NODE_NAME     J12 153
 '@S9S_MB_2U_LIB.S9S_MB_2U(SCH_1):PAGE93_I175@PURE_QUANTA.SCONN288_ADR50017P087CC(CHIPS)':
 'VSS65': CDS_PINID='VSS65';
NODE_NAME     J12 155
 '@S9S_MB_2U_LIB.S9S_MB_2U(SCH_1):PAGE93_I175@PURE_QUANTA.SCONN288_ADR50017P087CC(CHIPS)':
 'VSS66': CDS_PINID='VSS66';
NODE_NAME     J12 158
 '@S9S_MB_2U_LIB.S9S_MB_2U(SCH_1):PAGE93_I175@PURE_QUANTA.SCONN288_ADR50017P087CC(CHIPS)':
 'VSS67': CDS_PINID='VSS67';
NODE_NAME     J12 160
 '@S9S_MB_2U_LIB.S9S_MB_2U(SCH_1):PAGE93_I175@PURE_QUANTA.SCONN288_ADR50017P087CC(CHIPS)':
 'VSS68': CDS_PINID='VSS68';
NODE_NAME     J12 162
 '@S9S_MB_2U_LIB.S9S_MB_2U(SCH_1):PAGE93_I175@PURE_QUANTA.SCONN288_ADR50017P087CC(CHIPS)':
 'VSS69': CDS_PINID='VSS69';
NODE_NAME     J12 164
 '@S9S_MB_2U_LIB.S9S_MB_2U(SCH_1):PAGE93_I175@PURE_QUANTA.SCONN288_ADR50017P087CC(CHIPS)':
 'VSS70': CDS_PINID='VSS70';
NODE_NAME     J12 166
 '@S9S_MB_2U_LIB.S9S_MB_2U(SCH_1):PAGE93_I175@PURE_QUANTA.SCONN288_ADR50017P087CC(CHIPS)':
 'VSS71': CDS_PINID='VSS71';
NODE_NAME     J12 169
 '@S9S_MB_2U_LIB.S9S_MB_2U(SCH_1):PAGE93_I175@PURE_QUANTA.SCONN288_ADR50017P087CC(CHIPS)':
 'VSS72': CDS_PINID='VSS72';
NODE_NAME     J12 171
 '@S9S_MB_2U_LIB.S9S_MB_2U(SCH_1):PAGE93_I175@PURE_QUANTA.SCONN288_ADR50017P087CC(CHIPS)':
 'VSS73': CDS_PINID='VSS73';
NODE_NAME     J12 173
 '@S9S_MB_2U_LIB.S9S_MB_2U(SCH_1):PAGE93_I175@PURE_QUANTA.SCONN288_ADR50017P087CC(CHIPS)':
 'VSS74': CDS_PINID='VSS74';
NODE_NAME     J12 175
 '@S9S_MB_2U_LIB.S9S_MB_2U(SCH_1):PAGE93_I175@PURE_QUANTA.SCONN288_ADR50017P087CC(CHIPS)':
 'VSS75': CDS_PINID='VSS75';
NODE_NAME     J12 177
 '@S9S_MB_2U_LIB.S9S_MB_2U(SCH_1):PAGE93_I175@PURE_QUANTA.SCONN288_ADR50017P087CC(CHIPS)':
 'VSS76': CDS_PINID='VSS76';
NODE_NAME     J12 180
 '@S9S_MB_2U_LIB.S9S_MB_2U(SCH_1):PAGE93_I175@PURE_QUANTA.SCONN288_ADR50017P087CC(CHIPS)':
 'VSS77': CDS_PINID='VSS77';
NODE_NAME     J12 182
 '@S9S_MB_2U_LIB.S9S_MB_2U(SCH_1):PAGE93_I175@PURE_QUANTA.SCONN288_ADR50017P087CC(CHIPS)':
 'VSS78': CDS_PINID='VSS78';
NODE_NAME     J12 184
 '@S9S_MB_2U_LIB.S9S_MB_2U(SCH_1):PAGE93_I175@PURE_QUANTA.SCONN288_ADR50017P087CC(CHIPS)':
 'VSS79': CDS_PINID='VSS79';
NODE_NAME     J12 186
 '@S9S_MB_2U_LIB.S9S_MB_2U(SCH_1):PAGE93_I175@PURE_QUANTA.SCONN288_ADR50017P087CC(CHIPS)':
 'VSS80': CDS_PINID='VSS80';
NODE_NAME     J12 188
 '@S9S_MB_2U_LIB.S9S_MB_2U(SCH_1):PAGE93_I175@PURE_QUANTA.SCONN288_ADR50017P087CC(CHIPS)':
 'VSS81': CDS_PINID='VSS81';
NODE_NAME     J12 191
 '@S9S_MB_2U_LIB.S9S_MB_2U(SCH_1):PAGE93_I175@PURE_QUANTA.SCONN288_ADR50017P087CC(CHIPS)':
 'VSS82': CDS_PINID='VSS82';
NODE_NAME     J12 193
 '@S9S_MB_2U_LIB.S9S_MB_2U(SCH_1):PAGE93_I175@PURE_QUANTA.SCONN288_ADR50017P087CC(CHIPS)':
 'VSS83': CDS_PINID='VSS83';
NODE_NAME     J12 195
 '@S9S_MB_2U_LIB.S9S_MB_2U(SCH_1):PAGE93_I175@PURE_QUANTA.SCONN288_ADR50017P087CC(CHIPS)':
 'VSS84': CDS_PINID='VSS84';
NODE_NAME     J12 197
 '@S9S_MB_2U_LIB.S9S_MB_2U(SCH_1):PAGE93_I175@PURE_QUANTA.SCONN288_ADR50017P087CC(CHIPS)':
 'VSS85': CDS_PINID='VSS85';
NODE_NAME     J12 199
 '@S9S_MB_2U_LIB.S9S_MB_2U(SCH_1):PAGE93_I175@PURE_QUANTA.SCONN288_ADR50017P087CC(CHIPS)':
 'VSS86': CDS_PINID='VSS86';
NODE_NAME     J12 202
 '@S9S_MB_2U_LIB.S9S_MB_2U(SCH_1):PAGE93_I175@PURE_QUANTA.SCONN288_ADR50017P087CC(CHIPS)':
 'VSS87': CDS_PINID='VSS87';
NODE_NAME     J12 204
 '@S9S_MB_2U_LIB.S9S_MB_2U(SCH_1):PAGE93_I175@PURE_QUANTA.SCONN288_ADR50017P087CC(CHIPS)':
 'VSS88': CDS_PINID='VSS88';
NODE_NAME     J12 206
 '@S9S_MB_2U_LIB.S9S_MB_2U(SCH_1):PAGE93_I175@PURE_QUANTA.SCONN288_ADR50017P087CC(CHIPS)':
 'VSS89': CDS_PINID='VSS89';
NODE_NAME     J12 208
 '@S9S_MB_2U_LIB.S9S_MB_2U(SCH_1):PAGE93_I175@PURE_QUANTA.SCONN288_ADR50017P087CC(CHIPS)':
 'VSS90': CDS_PINID='VSS90';
NODE_NAME     J12 210
 '@S9S_MB_2U_LIB.S9S_MB_2U(SCH_1):PAGE93_I175@PURE_QUANTA.SCONN288_ADR50017P087CC(CHIPS)':
 'VSS91': CDS_PINID='VSS91';
NODE_NAME     J12 212
 '@S9S_MB_2U_LIB.S9S_MB_2U(SCH_1):PAGE93_I175@PURE_QUANTA.SCONN288_ADR50017P087CC(CHIPS)':
 'VSS92': CDS_PINID='VSS92';
NODE_NAME     J12 214
 '@S9S_MB_2U_LIB.S9S_MB_2U(SCH_1):PAGE93_I175@PURE_QUANTA.SCONN288_ADR50017P087CC(CHIPS)':
 'VSS93': CDS_PINID='VSS93';
NODE_NAME     J12 216
 '@S9S_MB_2U_LIB.S9S_MB_2U(SCH_1):PAGE93_I175@PURE_QUANTA.SCONN288_ADR50017P087CC(CHIPS)':
 'VSS94': CDS_PINID='VSS94';
NODE_NAME     J12 219
 '@S9S_MB_2U_LIB.S9S_MB_2U(SCH_1):PAGE93_I175@PURE_QUANTA.SCONN288_ADR50017P087CC(CHIPS)':
 'VSS95': CDS_PINID='VSS95';
NODE_NAME     J12 222
 '@S9S_MB_2U_LIB.S9S_MB_2U(SCH_1):PAGE93_I175@PURE_QUANTA.SCONN288_ADR50017P087CC(CHIPS)':
 'VSS96': CDS_PINID='VSS96';
NODE_NAME     J12 224
 '@S9S_MB_2U_LIB.S9S_MB_2U(SCH_1):PAGE93_I175@PURE_QUANTA.SCONN288_ADR50017P087CC(CHIPS)':
 'VSS97': CDS_PINID='VSS97';
NODE_NAME     J12 226
 '@S9S_MB_2U_LIB.S9S_MB_2U(SCH_1):PAGE93_I175@PURE_QUANTA.SCONN288_ADR50017P087CC(CHIPS)':
 'VSS98': CDS_PINID='VSS98';
NODE_NAME     J12 228
 '@S9S_MB_2U_LIB.S9S_MB_2U(SCH_1):PAGE93_I175@PURE_QUANTA.SCONN288_ADR50017P087CC(CHIPS)':
 'VSS99': CDS_PINID='VSS99';
NODE_NAME     J12 230
 '@S9S_MB_2U_LIB.S9S_MB_2U(SCH_1):PAGE93_I175@PURE_QUANTA.SCONN288_ADR50017P087CC(CHIPS)':
 'VSS100': CDS_PINID='VSS100';
NODE_NAME     J12 233
 '@S9S_MB_2U_LIB.S9S_MB_2U(SCH_1):PAGE93_I175@PURE_QUANTA.SCONN288_ADR50017P087CC(CHIPS)':
 'VSS101': CDS_PINID='VSS101';
NODE_NAME     J12 235
 '@S9S_MB_2U_LIB.S9S_MB_2U(SCH_1):PAGE93_I175@PURE_QUANTA.SCONN288_ADR50017P087CC(CHIPS)':
 'VSS102': CDS_PINID='VSS102';
NODE_NAME     J12 237
 '@S9S_MB_2U_LIB.S9S_MB_2U(SCH_1):PAGE93_I175@PURE_QUANTA.SCONN288_ADR50017P087CC(CHIPS)':
 'VSS103': CDS_PINID='VSS103';
NODE_NAME     J12 240
 '@S9S_MB_2U_LIB.S9S_MB_2U(SCH_1):PAGE93_I175@PURE_QUANTA.SCONN288_ADR50017P087CC(CHIPS)':
 'VSS104': CDS_PINID='VSS104';
NODE_NAME     J12 242
 '@S9S_MB_2U_LIB.S9S_MB_2U(SCH_1):PAGE93_I175@PURE_QUANTA.SCONN288_ADR50017P087CC(CHIPS)':
 'VSS105': CDS_PINID='VSS105';
NODE_NAME     J12 244
 '@S9S_MB_2U_LIB.S9S_MB_2U(SCH_1):PAGE93_I175@PURE_QUANTA.SCONN288_ADR50017P087CC(CHIPS)':
 'VSS106': CDS_PINID='VSS106';
NODE_NAME     J12 246
 '@S9S_MB_2U_LIB.S9S_MB_2U(SCH_1):PAGE93_I175@PURE_QUANTA.SCONN288_ADR50017P087CC(CHIPS)':
 'VSS107': CDS_PINID='VSS107';
NODE_NAME     J12 248
 '@S9S_MB_2U_LIB.S9S_MB_2U(SCH_1):PAGE93_I175@PURE_QUANTA.SCONN288_ADR50017P087CC(CHIPS)':
 'VSS108': CDS_PINID='VSS108';
NODE_NAME     J12 251
 '@S9S_MB_2U_LIB.S9S_MB_2U(SCH_1):PAGE93_I175@PURE_QUANTA.SCONN288_ADR50017P087CC(CHIPS)':
 'VSS109': CDS_PINID='VSS109';
NODE_NAME     J12 253
 '@S9S_MB_2U_LIB.S9S_MB_2U(SCH_1):PAGE93_I175@PURE_QUANTA.SCONN288_ADR50017P087CC(CHIPS)':
 'VSS110': CDS_PINID='VSS110';
NODE_NAME     J12 255
 '@S9S_MB_2U_LIB.S9S_MB_2U(SCH_1):PAGE93_I175@PURE_QUANTA.SCONN288_ADR50017P087CC(CHIPS)':
 'VSS111': CDS_PINID='VSS111';
NODE_NAME     J12 257
 '@S9S_MB_2U_LIB.S9S_MB_2U(SCH_1):PAGE93_I175@PURE_QUANTA.SCONN288_ADR50017P087CC(CHIPS)':
 'VSS112': CDS_PINID='VSS112';
NODE_NAME     J12 259
 '@S9S_MB_2U_LIB.S9S_MB_2U(SCH_1):PAGE93_I175@PURE_QUANTA.SCONN288_ADR50017P087CC(CHIPS)':
 'VSS113': CDS_PINID='VSS113';
NODE_NAME     J12 262
 '@S9S_MB_2U_LIB.S9S_MB_2U(SCH_1):PAGE93_I175@PURE_QUANTA.SCONN288_ADR50017P087CC(CHIPS)':
 'VSS114': CDS_PINID='VSS114';
NODE_NAME     J12 264
 '@S9S_MB_2U_LIB.S9S_MB_2U(SCH_1):PAGE93_I175@PURE_QUANTA.SCONN288_ADR50017P087CC(CHIPS)':
 'VSS115': CDS_PINID='VSS115';
NODE_NAME     J12 266
 '@S9S_MB_2U_LIB.S9S_MB_2U(SCH_1):PAGE93_I175@PURE_QUANTA.SCONN288_ADR50017P087CC(CHIPS)':
 'VSS116': CDS_PINID='VSS116';
NODE_NAME     J12 268
 '@S9S_MB_2U_LIB.S9S_MB_2U(SCH_1):PAGE93_I175@PURE_QUANTA.SCONN288_ADR50017P087CC(CHIPS)':
 'VSS117': CDS_PINID='VSS117';
NODE_NAME     J12 270
 '@S9S_MB_2U_LIB.S9S_MB_2U(SCH_1):PAGE93_I175@PURE_QUANTA.SCONN288_ADR50017P087CC(CHIPS)':
 'VSS118': CDS_PINID='VSS118';
NODE_NAME     J12 273
 '@S9S_MB_2U_LIB.S9S_MB_2U(SCH_1):PAGE93_I175@PURE_QUANTA.SCONN288_ADR50017P087CC(CHIPS)':
 'VSS119': CDS_PINID='VSS119';
NODE_NAME     J12 275
 '@S9S_MB_2U_LIB.S9S_MB_2U(SCH_1):PAGE93_I175@PURE_QUANTA.SCONN288_ADR50017P087CC(CHIPS)':
 'VSS120': CDS_PINID='VSS120';
NODE_NAME     J12 277
 '@S9S_MB_2U_LIB.S9S_MB_2U(SCH_1):PAGE93_I175@PURE_QUANTA.SCONN288_ADR50017P087CC(CHIPS)':
 'VSS121': CDS_PINID='VSS121';
NODE_NAME     J12 279
 '@S9S_MB_2U_LIB.S9S_MB_2U(SCH_1):PAGE93_I175@PURE_QUANTA.SCONN288_ADR50017P087CC(CHIPS)':
 'VSS122': CDS_PINID='VSS122';
NODE_NAME     J12 281
 '@S9S_MB_2U_LIB.S9S_MB_2U(SCH_1):PAGE93_I175@PURE_QUANTA.SCONN288_ADR50017P087CC(CHIPS)':
 'VSS123': CDS_PINID='VSS123';
NODE_NAME     J12 284
 '@S9S_MB_2U_LIB.S9S_MB_2U(SCH_1):PAGE93_I175@PURE_QUANTA.SCONN288_ADR50017P087CC(CHIPS)':
 'VSS124': CDS_PINID='VSS124';
NODE_NAME     J12 286
 '@S9S_MB_2U_LIB.S9S_MB_2U(SCH_1):PAGE93_I175@PURE_QUANTA.SCONN288_ADR50017P087CC(CHIPS)':
 'VSS125': CDS_PINID='VSS125';
NODE_NAME     J12 288
 '@S9S_MB_2U_LIB.S9S_MB_2U(SCH_1):PAGE93_I175@PURE_QUANTA.SCONN288_ADR50017P087CC(CHIPS)':
 'VSS126': CDS_PINID='VSS126';
NODE_NAME     R38 2
 '@S9S_MB_2U_LIB.S9S_MB_2U(SCH_1):PAGE94_I10@PURE_QUANTA.Q_RES(CHIPS)':
 'B': CDS_PINID='B';
NODE_NAME     C38 2
 '@S9S_MB_2U_LIB.S9S_MB_2U(SCH_1):PAGE94_I123@PURE_QUANTA.Q_CAP(CHIPS)':
 'B': CDS_PINID='B';
NODE_NAME     C39 2
 '@S9S_MB_2U_LIB.S9S_MB_2U(SCH_1):PAGE94_I125@PURE_QUANTA.Q_CAP(CHIPS)':
 'B': CDS_PINID='B';
NODE_NAME     C40 2
 '@S9S_MB_2U_LIB.S9S_MB_2U(SCH_1):PAGE94_I162@PURE_QUANTA.Q_CAP(CHIPS)':
 'B': CDS_PINID='B';
NODE_NAME     J13 G1
 '@S9S_MB_2U_LIB.S9S_MB_2U(SCH_1):PAGE94_I164@PURE_QUANTA.SCONN288_ADR50017P130CC(CHIPS)':
 'G1': CDS_PINID='G1';
NODE_NAME     J13 G2
 '@S9S_MB_2U_LIB.S9S_MB_2U(SCH_1):PAGE94_I164@PURE_QUANTA.SCONN288_ADR50017P130CC(CHIPS)':
 'G2': CDS_PINID='G2';
NODE_NAME     J13 G3
 '@S9S_MB_2U_LIB.S9S_MB_2U(SCH_1):PAGE94_I164@PURE_QUANTA.SCONN288_ADR50017P130CC(CHIPS)':
 'G3': CDS_PINID='G3';
NODE_NAME     J13 6
 '@S9S_MB_2U_LIB.S9S_MB_2U(SCH_1):PAGE94_I164@PURE_QUANTA.SCONN288_ADR50017P130CC(CHIPS)':
 'VSS0': CDS_PINID='VSS0';
NODE_NAME     J13 8
 '@S9S_MB_2U_LIB.S9S_MB_2U(SCH_1):PAGE94_I164@PURE_QUANTA.SCONN288_ADR50017P130CC(CHIPS)':
 'VSS1': CDS_PINID='VSS1';
NODE_NAME     J13 10
 '@S9S_MB_2U_LIB.S9S_MB_2U(SCH_1):PAGE94_I164@PURE_QUANTA.SCONN288_ADR50017P130CC(CHIPS)':
 'VSS2': CDS_PINID='VSS2';
NODE_NAME     J13 13
 '@S9S_MB_2U_LIB.S9S_MB_2U(SCH_1):PAGE94_I164@PURE_QUANTA.SCONN288_ADR50017P130CC(CHIPS)':
 'VSS3': CDS_PINID='VSS3';
NODE_NAME     J13 15
 '@S9S_MB_2U_LIB.S9S_MB_2U(SCH_1):PAGE94_I164@PURE_QUANTA.SCONN288_ADR50017P130CC(CHIPS)':
 'VSS4': CDS_PINID='VSS4';
NODE_NAME     J13 17
 '@S9S_MB_2U_LIB.S9S_MB_2U(SCH_1):PAGE94_I164@PURE_QUANTA.SCONN288_ADR50017P130CC(CHIPS)':
 'VSS5': CDS_PINID='VSS5';
NODE_NAME     J13 19
 '@S9S_MB_2U_LIB.S9S_MB_2U(SCH_1):PAGE94_I164@PURE_QUANTA.SCONN288_ADR50017P130CC(CHIPS)':
 'VSS6': CDS_PINID='VSS6';
NODE_NAME     J13 21
 '@S9S_MB_2U_LIB.S9S_MB_2U(SCH_1):PAGE94_I164@PURE_QUANTA.SCONN288_ADR50017P130CC(CHIPS)':
 'VSS7': CDS_PINID='VSS7';
NODE_NAME     J13 24
 '@S9S_MB_2U_LIB.S9S_MB_2U(SCH_1):PAGE94_I164@PURE_QUANTA.SCONN288_ADR50017P130CC(CHIPS)':
 'VSS8': CDS_PINID='VSS8';
NODE_NAME     J13 26
 '@S9S_MB_2U_LIB.S9S_MB_2U(SCH_1):PAGE94_I164@PURE_QUANTA.SCONN288_ADR50017P130CC(CHIPS)':
 'VSS9': CDS_PINID='VSS9';
NODE_NAME     J13 28
 '@S9S_MB_2U_LIB.S9S_MB_2U(SCH_1):PAGE94_I164@PURE_QUANTA.SCONN288_ADR50017P130CC(CHIPS)':
 'VSS10': CDS_PINID='VSS10';
NODE_NAME     J13 30
 '@S9S_MB_2U_LIB.S9S_MB_2U(SCH_1):PAGE94_I164@PURE_QUANTA.SCONN288_ADR50017P130CC(CHIPS)':
 'VSS11': CDS_PINID='VSS11';
NODE_NAME     J13 32
 '@S9S_MB_2U_LIB.S9S_MB_2U(SCH_1):PAGE94_I164@PURE_QUANTA.SCONN288_ADR50017P130CC(CHIPS)':
 'VSS12': CDS_PINID='VSS12';
NODE_NAME     J13 35
 '@S9S_MB_2U_LIB.S9S_MB_2U(SCH_1):PAGE94_I164@PURE_QUANTA.SCONN288_ADR50017P130CC(CHIPS)':
 'VSS13': CDS_PINID='VSS13';
NODE_NAME     J13 37
 '@S9S_MB_2U_LIB.S9S_MB_2U(SCH_1):PAGE94_I164@PURE_QUANTA.SCONN288_ADR50017P130CC(CHIPS)':
 'VSS14': CDS_PINID='VSS14';
NODE_NAME     J13 39
 '@S9S_MB_2U_LIB.S9S_MB_2U(SCH_1):PAGE94_I164@PURE_QUANTA.SCONN288_ADR50017P130CC(CHIPS)':
 'VSS15': CDS_PINID='VSS15';
NODE_NAME     J13 41
 '@S9S_MB_2U_LIB.S9S_MB_2U(SCH_1):PAGE94_I164@PURE_QUANTA.SCONN288_ADR50017P130CC(CHIPS)':
 'VSS16': CDS_PINID='VSS16';
NODE_NAME     J13 43
 '@S9S_MB_2U_LIB.S9S_MB_2U(SCH_1):PAGE94_I164@PURE_QUANTA.SCONN288_ADR50017P130CC(CHIPS)':
 'VSS17': CDS_PINID='VSS17';
NODE_NAME     J13 46
 '@S9S_MB_2U_LIB.S9S_MB_2U(SCH_1):PAGE94_I164@PURE_QUANTA.SCONN288_ADR50017P130CC(CHIPS)':
 'VSS18': CDS_PINID='VSS18';
NODE_NAME     J13 48
 '@S9S_MB_2U_LIB.S9S_MB_2U(SCH_1):PAGE94_I164@PURE_QUANTA.SCONN288_ADR50017P130CC(CHIPS)':
 'VSS19': CDS_PINID='VSS19';
NODE_NAME     J13 50
 '@S9S_MB_2U_LIB.S9S_MB_2U(SCH_1):PAGE94_I164@PURE_QUANTA.SCONN288_ADR50017P130CC(CHIPS)':
 'VSS20': CDS_PINID='VSS20';
NODE_NAME     J13 52
 '@S9S_MB_2U_LIB.S9S_MB_2U(SCH_1):PAGE94_I164@PURE_QUANTA.SCONN288_ADR50017P130CC(CHIPS)':
 'VSS21': CDS_PINID='VSS21';
NODE_NAME     J13 54
 '@S9S_MB_2U_LIB.S9S_MB_2U(SCH_1):PAGE94_I164@PURE_QUANTA.SCONN288_ADR50017P130CC(CHIPS)':
 'VSS22': CDS_PINID='VSS22';
NODE_NAME     J13 57
 '@S9S_MB_2U_LIB.S9S_MB_2U(SCH_1):PAGE94_I164@PURE_QUANTA.SCONN288_ADR50017P130CC(CHIPS)':
 'VSS23': CDS_PINID='VSS23';
NODE_NAME     J13 59
 '@S9S_MB_2U_LIB.S9S_MB_2U(SCH_1):PAGE94_I164@PURE_QUANTA.SCONN288_ADR50017P130CC(CHIPS)':
 'VSS24': CDS_PINID='VSS24';
NODE_NAME     J13 61
 '@S9S_MB_2U_LIB.S9S_MB_2U(SCH_1):PAGE94_I164@PURE_QUANTA.SCONN288_ADR50017P130CC(CHIPS)':
 'VSS25': CDS_PINID='VSS25';
NODE_NAME     J13 63
 '@S9S_MB_2U_LIB.S9S_MB_2U(SCH_1):PAGE94_I164@PURE_QUANTA.SCONN288_ADR50017P130CC(CHIPS)':
 'VSS26': CDS_PINID='VSS26';
NODE_NAME     J13 65
 '@S9S_MB_2U_LIB.S9S_MB_2U(SCH_1):PAGE94_I164@PURE_QUANTA.SCONN288_ADR50017P130CC(CHIPS)':
 'VSS27': CDS_PINID='VSS27';
NODE_NAME     J13 67
 '@S9S_MB_2U_LIB.S9S_MB_2U(SCH_1):PAGE94_I164@PURE_QUANTA.SCONN288_ADR50017P130CC(CHIPS)':
 'VSS28': CDS_PINID='VSS28';
NODE_NAME     J13 69
 '@S9S_MB_2U_LIB.S9S_MB_2U(SCH_1):PAGE94_I164@PURE_QUANTA.SCONN288_ADR50017P130CC(CHIPS)':
 'VSS29': CDS_PINID='VSS29';
NODE_NAME     J13 71
 '@S9S_MB_2U_LIB.S9S_MB_2U(SCH_1):PAGE94_I164@PURE_QUANTA.SCONN288_ADR50017P130CC(CHIPS)':
 'VSS30': CDS_PINID='VSS30';
NODE_NAME     J13 73
 '@S9S_MB_2U_LIB.S9S_MB_2U(SCH_1):PAGE94_I164@PURE_QUANTA.SCONN288_ADR50017P130CC(CHIPS)':
 'VSS31': CDS_PINID='VSS31';
NODE_NAME     J13 75
 '@S9S_MB_2U_LIB.S9S_MB_2U(SCH_1):PAGE94_I164@PURE_QUANTA.SCONN288_ADR50017P130CC(CHIPS)':
 'VSS32': CDS_PINID='VSS32';
NODE_NAME     J13 77
 '@S9S_MB_2U_LIB.S9S_MB_2U(SCH_1):PAGE94_I164@PURE_QUANTA.SCONN288_ADR50017P130CC(CHIPS)':
 'VSS33': CDS_PINID='VSS33';
NODE_NAME     J13 79
 '@S9S_MB_2U_LIB.S9S_MB_2U(SCH_1):PAGE94_I164@PURE_QUANTA.SCONN288_ADR50017P130CC(CHIPS)':
 'VSS34': CDS_PINID='VSS34';
NODE_NAME     J13 81
 '@S9S_MB_2U_LIB.S9S_MB_2U(SCH_1):PAGE94_I164@PURE_QUANTA.SCONN288_ADR50017P130CC(CHIPS)':
 'VSS35': CDS_PINID='VSS35';
NODE_NAME     J13 83
 '@S9S_MB_2U_LIB.S9S_MB_2U(SCH_1):PAGE94_I164@PURE_QUANTA.SCONN288_ADR50017P130CC(CHIPS)':
 'VSS36': CDS_PINID='VSS36';
NODE_NAME     J13 85
 '@S9S_MB_2U_LIB.S9S_MB_2U(SCH_1):PAGE94_I164@PURE_QUANTA.SCONN288_ADR50017P130CC(CHIPS)':
 'VSS37': CDS_PINID='VSS37';
NODE_NAME     J13 88
 '@S9S_MB_2U_LIB.S9S_MB_2U(SCH_1):PAGE94_I164@PURE_QUANTA.SCONN288_ADR50017P130CC(CHIPS)':
 'VSS38': CDS_PINID='VSS38';
NODE_NAME     J13 90
 '@S9S_MB_2U_LIB.S9S_MB_2U(SCH_1):PAGE94_I164@PURE_QUANTA.SCONN288_ADR50017P130CC(CHIPS)':
 'VSS39': CDS_PINID='VSS39';
NODE_NAME     J13 92
 '@S9S_MB_2U_LIB.S9S_MB_2U(SCH_1):PAGE94_I164@PURE_QUANTA.SCONN288_ADR50017P130CC(CHIPS)':
 'VSS40': CDS_PINID='VSS40';
NODE_NAME     J13 95
 '@S9S_MB_2U_LIB.S9S_MB_2U(SCH_1):PAGE94_I164@PURE_QUANTA.SCONN288_ADR50017P130CC(CHIPS)':
 'VSS41': CDS_PINID='VSS41';
NODE_NAME     J13 97
 '@S9S_MB_2U_LIB.S9S_MB_2U(SCH_1):PAGE94_I164@PURE_QUANTA.SCONN288_ADR50017P130CC(CHIPS)':
 'VSS42': CDS_PINID='VSS42';
NODE_NAME     J13 99
 '@S9S_MB_2U_LIB.S9S_MB_2U(SCH_1):PAGE94_I164@PURE_QUANTA.SCONN288_ADR50017P130CC(CHIPS)':
 'VSS43': CDS_PINID='VSS43';
NODE_NAME     J13 101
 '@S9S_MB_2U_LIB.S9S_MB_2U(SCH_1):PAGE94_I164@PURE_QUANTA.SCONN288_ADR50017P130CC(CHIPS)':
 'VSS44': CDS_PINID='VSS44';
NODE_NAME     J13 103
 '@S9S_MB_2U_LIB.S9S_MB_2U(SCH_1):PAGE94_I164@PURE_QUANTA.SCONN288_ADR50017P130CC(CHIPS)':
 'VSS45': CDS_PINID='VSS45';
NODE_NAME     J13 106
 '@S9S_MB_2U_LIB.S9S_MB_2U(SCH_1):PAGE94_I164@PURE_QUANTA.SCONN288_ADR50017P130CC(CHIPS)':
 'VSS46': CDS_PINID='VSS46';
NODE_NAME     J13 108
 '@S9S_MB_2U_LIB.S9S_MB_2U(SCH_1):PAGE94_I164@PURE_QUANTA.SCONN288_ADR50017P130CC(CHIPS)':
 'VSS47': CDS_PINID='VSS47';
NODE_NAME     J13 110
 '@S9S_MB_2U_LIB.S9S_MB_2U(SCH_1):PAGE94_I164@PURE_QUANTA.SCONN288_ADR50017P130CC(CHIPS)':
 'VSS48': CDS_PINID='VSS48';
NODE_NAME     J13 112
 '@S9S_MB_2U_LIB.S9S_MB_2U(SCH_1):PAGE94_I164@PURE_QUANTA.SCONN288_ADR50017P130CC(CHIPS)':
 'VSS49': CDS_PINID='VSS49';
NODE_NAME     J13 114
 '@S9S_MB_2U_LIB.S9S_MB_2U(SCH_1):PAGE94_I164@PURE_QUANTA.SCONN288_ADR50017P130CC(CHIPS)':
 'VSS50': CDS_PINID='VSS50';
NODE_NAME     J13 117
 '@S9S_MB_2U_LIB.S9S_MB_2U(SCH_1):PAGE94_I164@PURE_QUANTA.SCONN288_ADR50017P130CC(CHIPS)':
 'VSS51': CDS_PINID='VSS51';
NODE_NAME     J13 119
 '@S9S_MB_2U_LIB.S9S_MB_2U(SCH_1):PAGE94_I164@PURE_QUANTA.SCONN288_ADR50017P130CC(CHIPS)':
 'VSS52': CDS_PINID='VSS52';
NODE_NAME     J13 121
 '@S9S_MB_2U_LIB.S9S_MB_2U(SCH_1):PAGE94_I164@PURE_QUANTA.SCONN288_ADR50017P130CC(CHIPS)':
 'VSS53': CDS_PINID='VSS53';
NODE_NAME     J13 123
 '@S9S_MB_2U_LIB.S9S_MB_2U(SCH_1):PAGE94_I164@PURE_QUANTA.SCONN288_ADR50017P130CC(CHIPS)':
 'VSS54': CDS_PINID='VSS54';
NODE_NAME     J13 125
 '@S9S_MB_2U_LIB.S9S_MB_2U(SCH_1):PAGE94_I164@PURE_QUANTA.SCONN288_ADR50017P130CC(CHIPS)':
 'VSS55': CDS_PINID='VSS55';
NODE_NAME     J13 128
 '@S9S_MB_2U_LIB.S9S_MB_2U(SCH_1):PAGE94_I164@PURE_QUANTA.SCONN288_ADR50017P130CC(CHIPS)':
 'VSS56': CDS_PINID='VSS56';
NODE_NAME     J13 130
 '@S9S_MB_2U_LIB.S9S_MB_2U(SCH_1):PAGE94_I164@PURE_QUANTA.SCONN288_ADR50017P130CC(CHIPS)':
 'VSS57': CDS_PINID='VSS57';
NODE_NAME     J13 132
 '@S9S_MB_2U_LIB.S9S_MB_2U(SCH_1):PAGE94_I164@PURE_QUANTA.SCONN288_ADR50017P130CC(CHIPS)':
 'VSS58': CDS_PINID='VSS58';
NODE_NAME     J13 134
 '@S9S_MB_2U_LIB.S9S_MB_2U(SCH_1):PAGE94_I164@PURE_QUANTA.SCONN288_ADR50017P130CC(CHIPS)':
 'VSS59': CDS_PINID='VSS59';
NODE_NAME     J13 136
 '@S9S_MB_2U_LIB.S9S_MB_2U(SCH_1):PAGE94_I164@PURE_QUANTA.SCONN288_ADR50017P130CC(CHIPS)':
 'VSS60': CDS_PINID='VSS60';
NODE_NAME     J13 139
 '@S9S_MB_2U_LIB.S9S_MB_2U(SCH_1):PAGE94_I164@PURE_QUANTA.SCONN288_ADR50017P130CC(CHIPS)':
 'VSS61': CDS_PINID='VSS61';
NODE_NAME     J13 141
 '@S9S_MB_2U_LIB.S9S_MB_2U(SCH_1):PAGE94_I164@PURE_QUANTA.SCONN288_ADR50017P130CC(CHIPS)':
 'VSS62': CDS_PINID='VSS62';
NODE_NAME     J13 143
 '@S9S_MB_2U_LIB.S9S_MB_2U(SCH_1):PAGE94_I164@PURE_QUANTA.SCONN288_ADR50017P130CC(CHIPS)':
 'VSS63': CDS_PINID='VSS63';
NODE_NAME     J13 151
 '@S9S_MB_2U_LIB.S9S_MB_2U(SCH_1):PAGE94_I164@PURE_QUANTA.SCONN288_ADR50017P130CC(CHIPS)':
 'VSS64': CDS_PINID='VSS64';
NODE_NAME     J13 153
 '@S9S_MB_2U_LIB.S9S_MB_2U(SCH_1):PAGE94_I164@PURE_QUANTA.SCONN288_ADR50017P130CC(CHIPS)':
 'VSS65': CDS_PINID='VSS65';
NODE_NAME     J13 155
 '@S9S_MB_2U_LIB.S9S_MB_2U(SCH_1):PAGE94_I164@PURE_QUANTA.SCONN288_ADR50017P130CC(CHIPS)':
 'VSS66': CDS_PINID='VSS66';
NODE_NAME     J13 158
 '@S9S_MB_2U_LIB.S9S_MB_2U(SCH_1):PAGE94_I164@PURE_QUANTA.SCONN288_ADR50017P130CC(CHIPS)':
 'VSS67': CDS_PINID='VSS67';
NODE_NAME     J13 160
 '@S9S_MB_2U_LIB.S9S_MB_2U(SCH_1):PAGE94_I164@PURE_QUANTA.SCONN288_ADR50017P130CC(CHIPS)':
 'VSS68': CDS_PINID='VSS68';
NODE_NAME     J13 162
 '@S9S_MB_2U_LIB.S9S_MB_2U(SCH_1):PAGE94_I164@PURE_QUANTA.SCONN288_ADR50017P130CC(CHIPS)':
 'VSS69': CDS_PINID='VSS69';
NODE_NAME     J13 164
 '@S9S_MB_2U_LIB.S9S_MB_2U(SCH_1):PAGE94_I164@PURE_QUANTA.SCONN288_ADR50017P130CC(CHIPS)':
 'VSS70': CDS_PINID='VSS70';
NODE_NAME     J13 166
 '@S9S_MB_2U_LIB.S9S_MB_2U(SCH_1):PAGE94_I164@PURE_QUANTA.SCONN288_ADR50017P130CC(CHIPS)':
 'VSS71': CDS_PINID='VSS71';
NODE_NAME     J13 169
 '@S9S_MB_2U_LIB.S9S_MB_2U(SCH_1):PAGE94_I164@PURE_QUANTA.SCONN288_ADR50017P130CC(CHIPS)':
 'VSS72': CDS_PINID='VSS72';
NODE_NAME     J13 171
 '@S9S_MB_2U_LIB.S9S_MB_2U(SCH_1):PAGE94_I164@PURE_QUANTA.SCONN288_ADR50017P130CC(CHIPS)':
 'VSS73': CDS_PINID='VSS73';
NODE_NAME     J13 173
 '@S9S_MB_2U_LIB.S9S_MB_2U(SCH_1):PAGE94_I164@PURE_QUANTA.SCONN288_ADR50017P130CC(CHIPS)':
 'VSS74': CDS_PINID='VSS74';
NODE_NAME     J13 175
 '@S9S_MB_2U_LIB.S9S_MB_2U(SCH_1):PAGE94_I164@PURE_QUANTA.SCONN288_ADR50017P130CC(CHIPS)':
 'VSS75': CDS_PINID='VSS75';
NODE_NAME     J13 177
 '@S9S_MB_2U_LIB.S9S_MB_2U(SCH_1):PAGE94_I164@PURE_QUANTA.SCONN288_ADR50017P130CC(CHIPS)':
 'VSS76': CDS_PINID='VSS76';
NODE_NAME     J13 180
 '@S9S_MB_2U_LIB.S9S_MB_2U(SCH_1):PAGE94_I164@PURE_QUANTA.SCONN288_ADR50017P130CC(CHIPS)':
 'VSS77': CDS_PINID='VSS77';
NODE_NAME     J13 182
 '@S9S_MB_2U_LIB.S9S_MB_2U(SCH_1):PAGE94_I164@PURE_QUANTA.SCONN288_ADR50017P130CC(CHIPS)':
 'VSS78': CDS_PINID='VSS78';
NODE_NAME     J13 184
 '@S9S_MB_2U_LIB.S9S_MB_2U(SCH_1):PAGE94_I164@PURE_QUANTA.SCONN288_ADR50017P130CC(CHIPS)':
 'VSS79': CDS_PINID='VSS79';
NODE_NAME     J13 186
 '@S9S_MB_2U_LIB.S9S_MB_2U(SCH_1):PAGE94_I164@PURE_QUANTA.SCONN288_ADR50017P130CC(CHIPS)':
 'VSS80': CDS_PINID='VSS80';
NODE_NAME     J13 188
 '@S9S_MB_2U_LIB.S9S_MB_2U(SCH_1):PAGE94_I164@PURE_QUANTA.SCONN288_ADR50017P130CC(CHIPS)':
 'VSS81': CDS_PINID='VSS81';
NODE_NAME     J13 191
 '@S9S_MB_2U_LIB.S9S_MB_2U(SCH_1):PAGE94_I164@PURE_QUANTA.SCONN288_ADR50017P130CC(CHIPS)':
 'VSS82': CDS_PINID='VSS82';
NODE_NAME     J13 193
 '@S9S_MB_2U_LIB.S9S_MB_2U(SCH_1):PAGE94_I164@PURE_QUANTA.SCONN288_ADR50017P130CC(CHIPS)':
 'VSS83': CDS_PINID='VSS83';
NODE_NAME     J13 195
 '@S9S_MB_2U_LIB.S9S_MB_2U(SCH_1):PAGE94_I164@PURE_QUANTA.SCONN288_ADR50017P130CC(CHIPS)':
 'VSS84': CDS_PINID='VSS84';
NODE_NAME     J13 197
 '@S9S_MB_2U_LIB.S9S_MB_2U(SCH_1):PAGE94_I164@PURE_QUANTA.SCONN288_ADR50017P130CC(CHIPS)':
 'VSS85': CDS_PINID='VSS85';
NODE_NAME     J13 199
 '@S9S_MB_2U_LIB.S9S_MB_2U(SCH_1):PAGE94_I164@PURE_QUANTA.SCONN288_ADR50017P130CC(CHIPS)':
 'VSS86': CDS_PINID='VSS86';
NODE_NAME     J13 202
 '@S9S_MB_2U_LIB.S9S_MB_2U(SCH_1):PAGE94_I164@PURE_QUANTA.SCONN288_ADR50017P130CC(CHIPS)':
 'VSS87': CDS_PINID='VSS87';
NODE_NAME     J13 204
 '@S9S_MB_2U_LIB.S9S_MB_2U(SCH_1):PAGE94_I164@PURE_QUANTA.SCONN288_ADR50017P130CC(CHIPS)':
 'VSS88': CDS_PINID='VSS88';
NODE_NAME     J13 206
 '@S9S_MB_2U_LIB.S9S_MB_2U(SCH_1):PAGE94_I164@PURE_QUANTA.SCONN288_ADR50017P130CC(CHIPS)':
 'VSS89': CDS_PINID='VSS89';
NODE_NAME     J13 208
 '@S9S_MB_2U_LIB.S9S_MB_2U(SCH_1):PAGE94_I164@PURE_QUANTA.SCONN288_ADR50017P130CC(CHIPS)':
 'VSS90': CDS_PINID='VSS90';
NODE_NAME     J13 210
 '@S9S_MB_2U_LIB.S9S_MB_2U(SCH_1):PAGE94_I164@PURE_QUANTA.SCONN288_ADR50017P130CC(CHIPS)':
 'VSS91': CDS_PINID='VSS91';
NODE_NAME     J13 212
 '@S9S_MB_2U_LIB.S9S_MB_2U(SCH_1):PAGE94_I164@PURE_QUANTA.SCONN288_ADR50017P130CC(CHIPS)':
 'VSS92': CDS_PINID='VSS92';
NODE_NAME     J13 214
 '@S9S_MB_2U_LIB.S9S_MB_2U(SCH_1):PAGE94_I164@PURE_QUANTA.SCONN288_ADR50017P130CC(CHIPS)':
 'VSS93': CDS_PINID='VSS93';
NODE_NAME     J13 216
 '@S9S_MB_2U_LIB.S9S_MB_2U(SCH_1):PAGE94_I164@PURE_QUANTA.SCONN288_ADR50017P130CC(CHIPS)':
 'VSS94': CDS_PINID='VSS94';
NODE_NAME     J13 219
 '@S9S_MB_2U_LIB.S9S_MB_2U(SCH_1):PAGE94_I164@PURE_QUANTA.SCONN288_ADR50017P130CC(CHIPS)':
 'VSS95': CDS_PINID='VSS95';
NODE_NAME     J13 222
 '@S9S_MB_2U_LIB.S9S_MB_2U(SCH_1):PAGE94_I164@PURE_QUANTA.SCONN288_ADR50017P130CC(CHIPS)':
 'VSS96': CDS_PINID='VSS96';
NODE_NAME     J13 224
 '@S9S_MB_2U_LIB.S9S_MB_2U(SCH_1):PAGE94_I164@PURE_QUANTA.SCONN288_ADR50017P130CC(CHIPS)':
 'VSS97': CDS_PINID='VSS97';
NODE_NAME     J13 226
 '@S9S_MB_2U_LIB.S9S_MB_2U(SCH_1):PAGE94_I164@PURE_QUANTA.SCONN288_ADR50017P130CC(CHIPS)':
 'VSS98': CDS_PINID='VSS98';
NODE_NAME     J13 228
 '@S9S_MB_2U_LIB.S9S_MB_2U(SCH_1):PAGE94_I164@PURE_QUANTA.SCONN288_ADR50017P130CC(CHIPS)':
 'VSS99': CDS_PINID='VSS99';
NODE_NAME     J13 230
 '@S9S_MB_2U_LIB.S9S_MB_2U(SCH_1):PAGE94_I164@PURE_QUANTA.SCONN288_ADR50017P130CC(CHIPS)':
 'VSS100': CDS_PINID='VSS100';
NODE_NAME     J13 233
 '@S9S_MB_2U_LIB.S9S_MB_2U(SCH_1):PAGE94_I164@PURE_QUANTA.SCONN288_ADR50017P130CC(CHIPS)':
 'VSS101': CDS_PINID='VSS101';
NODE_NAME     J13 235
 '@S9S_MB_2U_LIB.S9S_MB_2U(SCH_1):PAGE94_I164@PURE_QUANTA.SCONN288_ADR50017P130CC(CHIPS)':
 'VSS102': CDS_PINID='VSS102';
NODE_NAME     J13 237
 '@S9S_MB_2U_LIB.S9S_MB_2U(SCH_1):PAGE94_I164@PURE_QUANTA.SCONN288_ADR50017P130CC(CHIPS)':
 'VSS103': CDS_PINID='VSS103';
NODE_NAME     J13 240
 '@S9S_MB_2U_LIB.S9S_MB_2U(SCH_1):PAGE94_I164@PURE_QUANTA.SCONN288_ADR50017P130CC(CHIPS)':
 'VSS104': CDS_PINID='VSS104';
NODE_NAME     J13 242
 '@S9S_MB_2U_LIB.S9S_MB_2U(SCH_1):PAGE94_I164@PURE_QUANTA.SCONN288_ADR50017P130CC(CHIPS)':
 'VSS105': CDS_PINID='VSS105';
NODE_NAME     J13 244
 '@S9S_MB_2U_LIB.S9S_MB_2U(SCH_1):PAGE94_I164@PURE_QUANTA.SCONN288_ADR50017P130CC(CHIPS)':
 'VSS106': CDS_PINID='VSS106';
NODE_NAME     J13 246
 '@S9S_MB_2U_LIB.S9S_MB_2U(SCH_1):PAGE94_I164@PURE_QUANTA.SCONN288_ADR50017P130CC(CHIPS)':
 'VSS107': CDS_PINID='VSS107';
NODE_NAME     J13 248
 '@S9S_MB_2U_LIB.S9S_MB_2U(SCH_1):PAGE94_I164@PURE_QUANTA.SCONN288_ADR50017P130CC(CHIPS)':
 'VSS108': CDS_PINID='VSS108';
NODE_NAME     J13 251
 '@S9S_MB_2U_LIB.S9S_MB_2U(SCH_1):PAGE94_I164@PURE_QUANTA.SCONN288_ADR50017P130CC(CHIPS)':
 'VSS109': CDS_PINID='VSS109';
NODE_NAME     J13 253
 '@S9S_MB_2U_LIB.S9S_MB_2U(SCH_1):PAGE94_I164@PURE_QUANTA.SCONN288_ADR50017P130CC(CHIPS)':
 'VSS110': CDS_PINID='VSS110';
NODE_NAME     J13 255
 '@S9S_MB_2U_LIB.S9S_MB_2U(SCH_1):PAGE94_I164@PURE_QUANTA.SCONN288_ADR50017P130CC(CHIPS)':
 'VSS111': CDS_PINID='VSS111';
NODE_NAME     J13 257
 '@S9S_MB_2U_LIB.S9S_MB_2U(SCH_1):PAGE94_I164@PURE_QUANTA.SCONN288_ADR50017P130CC(CHIPS)':
 'VSS112': CDS_PINID='VSS112';
NODE_NAME     J13 259
 '@S9S_MB_2U_LIB.S9S_MB_2U(SCH_1):PAGE94_I164@PURE_QUANTA.SCONN288_ADR50017P130CC(CHIPS)':
 'VSS113': CDS_PINID='VSS113';
NODE_NAME     J13 262
 '@S9S_MB_2U_LIB.S9S_MB_2U(SCH_1):PAGE94_I164@PURE_QUANTA.SCONN288_ADR50017P130CC(CHIPS)':
 'VSS114': CDS_PINID='VSS114';
NODE_NAME     J13 264
 '@S9S_MB_2U_LIB.S9S_MB_2U(SCH_1):PAGE94_I164@PURE_QUANTA.SCONN288_ADR50017P130CC(CHIPS)':
 'VSS115': CDS_PINID='VSS115';
NODE_NAME     J13 266
 '@S9S_MB_2U_LIB.S9S_MB_2U(SCH_1):PAGE94_I164@PURE_QUANTA.SCONN288_ADR50017P130CC(CHIPS)':
 'VSS116': CDS_PINID='VSS116';
NODE_NAME     J13 268
 '@S9S_MB_2U_LIB.S9S_MB_2U(SCH_1):PAGE94_I164@PURE_QUANTA.SCONN288_ADR50017P130CC(CHIPS)':
 'VSS117': CDS_PINID='VSS117';
NODE_NAME     J13 270
 '@S9S_MB_2U_LIB.S9S_MB_2U(SCH_1):PAGE94_I164@PURE_QUANTA.SCONN288_ADR50017P130CC(CHIPS)':
 'VSS118': CDS_PINID='VSS118';
NODE_NAME     J13 273
 '@S9S_MB_2U_LIB.S9S_MB_2U(SCH_1):PAGE94_I164@PURE_QUANTA.SCONN288_ADR50017P130CC(CHIPS)':
 'VSS119': CDS_PINID='VSS119';
NODE_NAME     J13 275
 '@S9S_MB_2U_LIB.S9S_MB_2U(SCH_1):PAGE94_I164@PURE_QUANTA.SCONN288_ADR50017P130CC(CHIPS)':
 'VSS120': CDS_PINID='VSS120';
NODE_NAME     J13 277
 '@S9S_MB_2U_LIB.S9S_MB_2U(SCH_1):PAGE94_I164@PURE_QUANTA.SCONN288_ADR50017P130CC(CHIPS)':
 'VSS121': CDS_PINID='VSS121';
NODE_NAME     J13 279
 '@S9S_MB_2U_LIB.S9S_MB_2U(SCH_1):PAGE94_I164@PURE_QUANTA.SCONN288_ADR50017P130CC(CHIPS)':
 'VSS122': CDS_PINID='VSS122';
NODE_NAME     J13 281
 '@S9S_MB_2U_LIB.S9S_MB_2U(SCH_1):PAGE94_I164@PURE_QUANTA.SCONN288_ADR50017P130CC(CHIPS)':
 'VSS123': CDS_PINID='VSS123';
NODE_NAME     J13 284
 '@S9S_MB_2U_LIB.S9S_MB_2U(SCH_1):PAGE94_I164@PURE_QUANTA.SCONN288_ADR50017P130CC(CHIPS)':
 'VSS124': CDS_PINID='VSS124';
NODE_NAME     J13 286
 '@S9S_MB_2U_LIB.S9S_MB_2U(SCH_1):PAGE94_I164@PURE_QUANTA.SCONN288_ADR50017P130CC(CHIPS)':
 'VSS125': CDS_PINID='VSS125';
NODE_NAME     J13 288
 '@S9S_MB_2U_LIB.S9S_MB_2U(SCH_1):PAGE94_I164@PURE_QUANTA.SCONN288_ADR50017P130CC(CHIPS)':
 'VSS126': CDS_PINID='VSS126';
NODE_NAME     R39 2
 '@S9S_MB_2U_LIB.S9S_MB_2U(SCH_1):PAGE95_I46@PURE_QUANTA.Q_RES(CHIPS)':
 'B': CDS_PINID='B';
NODE_NAME     C41 2
 '@S9S_MB_2U_LIB.S9S_MB_2U(SCH_1):PAGE95_I121@PURE_QUANTA.Q_CAP(CHIPS)':
 'B': CDS_PINID='B';
NODE_NAME     C42 2
 '@S9S_MB_2U_LIB.S9S_MB_2U(SCH_1):PAGE95_I125@PURE_QUANTA.Q_CAP(CHIPS)':
 'B': CDS_PINID='B';
NODE_NAME     C43 2
 '@S9S_MB_2U_LIB.S9S_MB_2U(SCH_1):PAGE95_I128@PURE_QUANTA.Q_CAP(CHIPS)':
 'B': CDS_PINID='B';
NODE_NAME     J14 G1
 '@S9S_MB_2U_LIB.S9S_MB_2U(SCH_1):PAGE95_I176@PURE_QUANTA.SCONN288_ADR50017P087CC(CHIPS)':
 'G1': CDS_PINID='G1';
NODE_NAME     J14 G2
 '@S9S_MB_2U_LIB.S9S_MB_2U(SCH_1):PAGE95_I176@PURE_QUANTA.SCONN288_ADR50017P087CC(CHIPS)':
 'G2': CDS_PINID='G2';
NODE_NAME     J14 G3
 '@S9S_MB_2U_LIB.S9S_MB_2U(SCH_1):PAGE95_I176@PURE_QUANTA.SCONN288_ADR50017P087CC(CHIPS)':
 'G3': CDS_PINID='G3';
NODE_NAME     J14 6
 '@S9S_MB_2U_LIB.S9S_MB_2U(SCH_1):PAGE95_I176@PURE_QUANTA.SCONN288_ADR50017P087CC(CHIPS)':
 'VSS0': CDS_PINID='VSS0';
NODE_NAME     J14 8
 '@S9S_MB_2U_LIB.S9S_MB_2U(SCH_1):PAGE95_I176@PURE_QUANTA.SCONN288_ADR50017P087CC(CHIPS)':
 'VSS1': CDS_PINID='VSS1';
NODE_NAME     J14 10
 '@S9S_MB_2U_LIB.S9S_MB_2U(SCH_1):PAGE95_I176@PURE_QUANTA.SCONN288_ADR50017P087CC(CHIPS)':
 'VSS2': CDS_PINID='VSS2';
NODE_NAME     J14 13
 '@S9S_MB_2U_LIB.S9S_MB_2U(SCH_1):PAGE95_I176@PURE_QUANTA.SCONN288_ADR50017P087CC(CHIPS)':
 'VSS3': CDS_PINID='VSS3';
NODE_NAME     J14 15
 '@S9S_MB_2U_LIB.S9S_MB_2U(SCH_1):PAGE95_I176@PURE_QUANTA.SCONN288_ADR50017P087CC(CHIPS)':
 'VSS4': CDS_PINID='VSS4';
NODE_NAME     J14 17
 '@S9S_MB_2U_LIB.S9S_MB_2U(SCH_1):PAGE95_I176@PURE_QUANTA.SCONN288_ADR50017P087CC(CHIPS)':
 'VSS5': CDS_PINID='VSS5';
NODE_NAME     J14 19
 '@S9S_MB_2U_LIB.S9S_MB_2U(SCH_1):PAGE95_I176@PURE_QUANTA.SCONN288_ADR50017P087CC(CHIPS)':
 'VSS6': CDS_PINID='VSS6';
NODE_NAME     J14 21
 '@S9S_MB_2U_LIB.S9S_MB_2U(SCH_1):PAGE95_I176@PURE_QUANTA.SCONN288_ADR50017P087CC(CHIPS)':
 'VSS7': CDS_PINID='VSS7';
NODE_NAME     J14 24
 '@S9S_MB_2U_LIB.S9S_MB_2U(SCH_1):PAGE95_I176@PURE_QUANTA.SCONN288_ADR50017P087CC(CHIPS)':
 'VSS8': CDS_PINID='VSS8';
NODE_NAME     J14 26
 '@S9S_MB_2U_LIB.S9S_MB_2U(SCH_1):PAGE95_I176@PURE_QUANTA.SCONN288_ADR50017P087CC(CHIPS)':
 'VSS9': CDS_PINID='VSS9';
NODE_NAME     J14 28
 '@S9S_MB_2U_LIB.S9S_MB_2U(SCH_1):PAGE95_I176@PURE_QUANTA.SCONN288_ADR50017P087CC(CHIPS)':
 'VSS10': CDS_PINID='VSS10';
NODE_NAME     J14 30
 '@S9S_MB_2U_LIB.S9S_MB_2U(SCH_1):PAGE95_I176@PURE_QUANTA.SCONN288_ADR50017P087CC(CHIPS)':
 'VSS11': CDS_PINID='VSS11';
NODE_NAME     J14 32
 '@S9S_MB_2U_LIB.S9S_MB_2U(SCH_1):PAGE95_I176@PURE_QUANTA.SCONN288_ADR50017P087CC(CHIPS)':
 'VSS12': CDS_PINID='VSS12';
NODE_NAME     J14 35
 '@S9S_MB_2U_LIB.S9S_MB_2U(SCH_1):PAGE95_I176@PURE_QUANTA.SCONN288_ADR50017P087CC(CHIPS)':
 'VSS13': CDS_PINID='VSS13';
NODE_NAME     J14 37
 '@S9S_MB_2U_LIB.S9S_MB_2U(SCH_1):PAGE95_I176@PURE_QUANTA.SCONN288_ADR50017P087CC(CHIPS)':
 'VSS14': CDS_PINID='VSS14';
NODE_NAME     J14 39
 '@S9S_MB_2U_LIB.S9S_MB_2U(SCH_1):PAGE95_I176@PURE_QUANTA.SCONN288_ADR50017P087CC(CHIPS)':
 'VSS15': CDS_PINID='VSS15';
NODE_NAME     J14 41
 '@S9S_MB_2U_LIB.S9S_MB_2U(SCH_1):PAGE95_I176@PURE_QUANTA.SCONN288_ADR50017P087CC(CHIPS)':
 'VSS16': CDS_PINID='VSS16';
NODE_NAME     J14 43
 '@S9S_MB_2U_LIB.S9S_MB_2U(SCH_1):PAGE95_I176@PURE_QUANTA.SCONN288_ADR50017P087CC(CHIPS)':
 'VSS17': CDS_PINID='VSS17';
NODE_NAME     J14 46
 '@S9S_MB_2U_LIB.S9S_MB_2U(SCH_1):PAGE95_I176@PURE_QUANTA.SCONN288_ADR50017P087CC(CHIPS)':
 'VSS18': CDS_PINID='VSS18';
NODE_NAME     J14 48
 '@S9S_MB_2U_LIB.S9S_MB_2U(SCH_1):PAGE95_I176@PURE_QUANTA.SCONN288_ADR50017P087CC(CHIPS)':
 'VSS19': CDS_PINID='VSS19';
NODE_NAME     J14 50
 '@S9S_MB_2U_LIB.S9S_MB_2U(SCH_1):PAGE95_I176@PURE_QUANTA.SCONN288_ADR50017P087CC(CHIPS)':
 'VSS20': CDS_PINID='VSS20';
NODE_NAME     J14 52
 '@S9S_MB_2U_LIB.S9S_MB_2U(SCH_1):PAGE95_I176@PURE_QUANTA.SCONN288_ADR50017P087CC(CHIPS)':
 'VSS21': CDS_PINID='VSS21';
NODE_NAME     J14 54
 '@S9S_MB_2U_LIB.S9S_MB_2U(SCH_1):PAGE95_I176@PURE_QUANTA.SCONN288_ADR50017P087CC(CHIPS)':
 'VSS22': CDS_PINID='VSS22';
NODE_NAME     J14 57
 '@S9S_MB_2U_LIB.S9S_MB_2U(SCH_1):PAGE95_I176@PURE_QUANTA.SCONN288_ADR50017P087CC(CHIPS)':
 'VSS23': CDS_PINID='VSS23';
NODE_NAME     J14 59
 '@S9S_MB_2U_LIB.S9S_MB_2U(SCH_1):PAGE95_I176@PURE_QUANTA.SCONN288_ADR50017P087CC(CHIPS)':
 'VSS24': CDS_PINID='VSS24';
NODE_NAME     J14 61
 '@S9S_MB_2U_LIB.S9S_MB_2U(SCH_1):PAGE95_I176@PURE_QUANTA.SCONN288_ADR50017P087CC(CHIPS)':
 'VSS25': CDS_PINID='VSS25';
NODE_NAME     J14 63
 '@S9S_MB_2U_LIB.S9S_MB_2U(SCH_1):PAGE95_I176@PURE_QUANTA.SCONN288_ADR50017P087CC(CHIPS)':
 'VSS26': CDS_PINID='VSS26';
NODE_NAME     J14 65
 '@S9S_MB_2U_LIB.S9S_MB_2U(SCH_1):PAGE95_I176@PURE_QUANTA.SCONN288_ADR50017P087CC(CHIPS)':
 'VSS27': CDS_PINID='VSS27';
NODE_NAME     J14 67
 '@S9S_MB_2U_LIB.S9S_MB_2U(SCH_1):PAGE95_I176@PURE_QUANTA.SCONN288_ADR50017P087CC(CHIPS)':
 'VSS28': CDS_PINID='VSS28';
NODE_NAME     J14 69
 '@S9S_MB_2U_LIB.S9S_MB_2U(SCH_1):PAGE95_I176@PURE_QUANTA.SCONN288_ADR50017P087CC(CHIPS)':
 'VSS29': CDS_PINID='VSS29';
NODE_NAME     J14 71
 '@S9S_MB_2U_LIB.S9S_MB_2U(SCH_1):PAGE95_I176@PURE_QUANTA.SCONN288_ADR50017P087CC(CHIPS)':
 'VSS30': CDS_PINID='VSS30';
NODE_NAME     J14 73
 '@S9S_MB_2U_LIB.S9S_MB_2U(SCH_1):PAGE95_I176@PURE_QUANTA.SCONN288_ADR50017P087CC(CHIPS)':
 'VSS31': CDS_PINID='VSS31';
NODE_NAME     J14 75
 '@S9S_MB_2U_LIB.S9S_MB_2U(SCH_1):PAGE95_I176@PURE_QUANTA.SCONN288_ADR50017P087CC(CHIPS)':
 'VSS32': CDS_PINID='VSS32';
NODE_NAME     J14 77
 '@S9S_MB_2U_LIB.S9S_MB_2U(SCH_1):PAGE95_I176@PURE_QUANTA.SCONN288_ADR50017P087CC(CHIPS)':
 'VSS33': CDS_PINID='VSS33';
NODE_NAME     J14 79
 '@S9S_MB_2U_LIB.S9S_MB_2U(SCH_1):PAGE95_I176@PURE_QUANTA.SCONN288_ADR50017P087CC(CHIPS)':
 'VSS34': CDS_PINID='VSS34';
NODE_NAME     J14 81
 '@S9S_MB_2U_LIB.S9S_MB_2U(SCH_1):PAGE95_I176@PURE_QUANTA.SCONN288_ADR50017P087CC(CHIPS)':
 'VSS35': CDS_PINID='VSS35';
NODE_NAME     J14 83
 '@S9S_MB_2U_LIB.S9S_MB_2U(SCH_1):PAGE95_I176@PURE_QUANTA.SCONN288_ADR50017P087CC(CHIPS)':
 'VSS36': CDS_PINID='VSS36';
NODE_NAME     J14 85
 '@S9S_MB_2U_LIB.S9S_MB_2U(SCH_1):PAGE95_I176@PURE_QUANTA.SCONN288_ADR50017P087CC(CHIPS)':
 'VSS37': CDS_PINID='VSS37';
NODE_NAME     J14 88
 '@S9S_MB_2U_LIB.S9S_MB_2U(SCH_1):PAGE95_I176@PURE_QUANTA.SCONN288_ADR50017P087CC(CHIPS)':
 'VSS38': CDS_PINID='VSS38';
NODE_NAME     J14 90
 '@S9S_MB_2U_LIB.S9S_MB_2U(SCH_1):PAGE95_I176@PURE_QUANTA.SCONN288_ADR50017P087CC(CHIPS)':
 'VSS39': CDS_PINID='VSS39';
NODE_NAME     J14 92
 '@S9S_MB_2U_LIB.S9S_MB_2U(SCH_1):PAGE95_I176@PURE_QUANTA.SCONN288_ADR50017P087CC(CHIPS)':
 'VSS40': CDS_PINID='VSS40';
NODE_NAME     J14 95
 '@S9S_MB_2U_LIB.S9S_MB_2U(SCH_1):PAGE95_I176@PURE_QUANTA.SCONN288_ADR50017P087CC(CHIPS)':
 'VSS41': CDS_PINID='VSS41';
NODE_NAME     J14 97
 '@S9S_MB_2U_LIB.S9S_MB_2U(SCH_1):PAGE95_I176@PURE_QUANTA.SCONN288_ADR50017P087CC(CHIPS)':
 'VSS42': CDS_PINID='VSS42';
NODE_NAME     J14 99
 '@S9S_MB_2U_LIB.S9S_MB_2U(SCH_1):PAGE95_I176@PURE_QUANTA.SCONN288_ADR50017P087CC(CHIPS)':
 'VSS43': CDS_PINID='VSS43';
NODE_NAME     J14 101
 '@S9S_MB_2U_LIB.S9S_MB_2U(SCH_1):PAGE95_I176@PURE_QUANTA.SCONN288_ADR50017P087CC(CHIPS)':
 'VSS44': CDS_PINID='VSS44';
NODE_NAME     J14 103
 '@S9S_MB_2U_LIB.S9S_MB_2U(SCH_1):PAGE95_I176@PURE_QUANTA.SCONN288_ADR50017P087CC(CHIPS)':
 'VSS45': CDS_PINID='VSS45';
NODE_NAME     J14 106
 '@S9S_MB_2U_LIB.S9S_MB_2U(SCH_1):PAGE95_I176@PURE_QUANTA.SCONN288_ADR50017P087CC(CHIPS)':
 'VSS46': CDS_PINID='VSS46';
NODE_NAME     J14 108
 '@S9S_MB_2U_LIB.S9S_MB_2U(SCH_1):PAGE95_I176@PURE_QUANTA.SCONN288_ADR50017P087CC(CHIPS)':
 'VSS47': CDS_PINID='VSS47';
NODE_NAME     J14 110
 '@S9S_MB_2U_LIB.S9S_MB_2U(SCH_1):PAGE95_I176@PURE_QUANTA.SCONN288_ADR50017P087CC(CHIPS)':
 'VSS48': CDS_PINID='VSS48';
NODE_NAME     J14 112
 '@S9S_MB_2U_LIB.S9S_MB_2U(SCH_1):PAGE95_I176@PURE_QUANTA.SCONN288_ADR50017P087CC(CHIPS)':
 'VSS49': CDS_PINID='VSS49';
NODE_NAME     J14 114
 '@S9S_MB_2U_LIB.S9S_MB_2U(SCH_1):PAGE95_I176@PURE_QUANTA.SCONN288_ADR50017P087CC(CHIPS)':
 'VSS50': CDS_PINID='VSS50';
NODE_NAME     J14 117
 '@S9S_MB_2U_LIB.S9S_MB_2U(SCH_1):PAGE95_I176@PURE_QUANTA.SCONN288_ADR50017P087CC(CHIPS)':
 'VSS51': CDS_PINID='VSS51';
NODE_NAME     J14 119
 '@S9S_MB_2U_LIB.S9S_MB_2U(SCH_1):PAGE95_I176@PURE_QUANTA.SCONN288_ADR50017P087CC(CHIPS)':
 'VSS52': CDS_PINID='VSS52';
NODE_NAME     J14 121
 '@S9S_MB_2U_LIB.S9S_MB_2U(SCH_1):PAGE95_I176@PURE_QUANTA.SCONN288_ADR50017P087CC(CHIPS)':
 'VSS53': CDS_PINID='VSS53';
NODE_NAME     J14 123
 '@S9S_MB_2U_LIB.S9S_MB_2U(SCH_1):PAGE95_I176@PURE_QUANTA.SCONN288_ADR50017P087CC(CHIPS)':
 'VSS54': CDS_PINID='VSS54';
NODE_NAME     J14 125
 '@S9S_MB_2U_LIB.S9S_MB_2U(SCH_1):PAGE95_I176@PURE_QUANTA.SCONN288_ADR50017P087CC(CHIPS)':
 'VSS55': CDS_PINID='VSS55';
NODE_NAME     J14 128
 '@S9S_MB_2U_LIB.S9S_MB_2U(SCH_1):PAGE95_I176@PURE_QUANTA.SCONN288_ADR50017P087CC(CHIPS)':
 'VSS56': CDS_PINID='VSS56';
NODE_NAME     J14 130
 '@S9S_MB_2U_LIB.S9S_MB_2U(SCH_1):PAGE95_I176@PURE_QUANTA.SCONN288_ADR50017P087CC(CHIPS)':
 'VSS57': CDS_PINID='VSS57';
NODE_NAME     J14 132
 '@S9S_MB_2U_LIB.S9S_MB_2U(SCH_1):PAGE95_I176@PURE_QUANTA.SCONN288_ADR50017P087CC(CHIPS)':
 'VSS58': CDS_PINID='VSS58';
NODE_NAME     J14 134
 '@S9S_MB_2U_LIB.S9S_MB_2U(SCH_1):PAGE95_I176@PURE_QUANTA.SCONN288_ADR50017P087CC(CHIPS)':
 'VSS59': CDS_PINID='VSS59';
NODE_NAME     J14 136
 '@S9S_MB_2U_LIB.S9S_MB_2U(SCH_1):PAGE95_I176@PURE_QUANTA.SCONN288_ADR50017P087CC(CHIPS)':
 'VSS60': CDS_PINID='VSS60';
NODE_NAME     J14 139
 '@S9S_MB_2U_LIB.S9S_MB_2U(SCH_1):PAGE95_I176@PURE_QUANTA.SCONN288_ADR50017P087CC(CHIPS)':
 'VSS61': CDS_PINID='VSS61';
NODE_NAME     J14 141
 '@S9S_MB_2U_LIB.S9S_MB_2U(SCH_1):PAGE95_I176@PURE_QUANTA.SCONN288_ADR50017P087CC(CHIPS)':
 'VSS62': CDS_PINID='VSS62';
NODE_NAME     J14 143
 '@S9S_MB_2U_LIB.S9S_MB_2U(SCH_1):PAGE95_I176@PURE_QUANTA.SCONN288_ADR50017P087CC(CHIPS)':
 'VSS63': CDS_PINID='VSS63';
NODE_NAME     J14 151
 '@S9S_MB_2U_LIB.S9S_MB_2U(SCH_1):PAGE95_I176@PURE_QUANTA.SCONN288_ADR50017P087CC(CHIPS)':
 'VSS64': CDS_PINID='VSS64';
NODE_NAME     J14 153
 '@S9S_MB_2U_LIB.S9S_MB_2U(SCH_1):PAGE95_I176@PURE_QUANTA.SCONN288_ADR50017P087CC(CHIPS)':
 'VSS65': CDS_PINID='VSS65';
NODE_NAME     J14 155
 '@S9S_MB_2U_LIB.S9S_MB_2U(SCH_1):PAGE95_I176@PURE_QUANTA.SCONN288_ADR50017P087CC(CHIPS)':
 'VSS66': CDS_PINID='VSS66';
NODE_NAME     J14 158
 '@S9S_MB_2U_LIB.S9S_MB_2U(SCH_1):PAGE95_I176@PURE_QUANTA.SCONN288_ADR50017P087CC(CHIPS)':
 'VSS67': CDS_PINID='VSS67';
NODE_NAME     J14 160
 '@S9S_MB_2U_LIB.S9S_MB_2U(SCH_1):PAGE95_I176@PURE_QUANTA.SCONN288_ADR50017P087CC(CHIPS)':
 'VSS68': CDS_PINID='VSS68';
NODE_NAME     J14 162
 '@S9S_MB_2U_LIB.S9S_MB_2U(SCH_1):PAGE95_I176@PURE_QUANTA.SCONN288_ADR50017P087CC(CHIPS)':
 'VSS69': CDS_PINID='VSS69';
NODE_NAME     J14 164
 '@S9S_MB_2U_LIB.S9S_MB_2U(SCH_1):PAGE95_I176@PURE_QUANTA.SCONN288_ADR50017P087CC(CHIPS)':
 'VSS70': CDS_PINID='VSS70';
NODE_NAME     J14 166
 '@S9S_MB_2U_LIB.S9S_MB_2U(SCH_1):PAGE95_I176@PURE_QUANTA.SCONN288_ADR50017P087CC(CHIPS)':
 'VSS71': CDS_PINID='VSS71';
NODE_NAME     J14 169
 '@S9S_MB_2U_LIB.S9S_MB_2U(SCH_1):PAGE95_I176@PURE_QUANTA.SCONN288_ADR50017P087CC(CHIPS)':
 'VSS72': CDS_PINID='VSS72';
NODE_NAME     J14 171
 '@S9S_MB_2U_LIB.S9S_MB_2U(SCH_1):PAGE95_I176@PURE_QUANTA.SCONN288_ADR50017P087CC(CHIPS)':
 'VSS73': CDS_PINID='VSS73';
NODE_NAME     J14 173
 '@S9S_MB_2U_LIB.S9S_MB_2U(SCH_1):PAGE95_I176@PURE_QUANTA.SCONN288_ADR50017P087CC(CHIPS)':
 'VSS74': CDS_PINID='VSS74';
NODE_NAME     J14 175
 '@S9S_MB_2U_LIB.S9S_MB_2U(SCH_1):PAGE95_I176@PURE_QUANTA.SCONN288_ADR50017P087CC(CHIPS)':
 'VSS75': CDS_PINID='VSS75';
NODE_NAME     J14 177
 '@S9S_MB_2U_LIB.S9S_MB_2U(SCH_1):PAGE95_I176@PURE_QUANTA.SCONN288_ADR50017P087CC(CHIPS)':
 'VSS76': CDS_PINID='VSS76';
NODE_NAME     J14 180
 '@S9S_MB_2U_LIB.S9S_MB_2U(SCH_1):PAGE95_I176@PURE_QUANTA.SCONN288_ADR50017P087CC(CHIPS)':
 'VSS77': CDS_PINID='VSS77';
NODE_NAME     J14 182
 '@S9S_MB_2U_LIB.S9S_MB_2U(SCH_1):PAGE95_I176@PURE_QUANTA.SCONN288_ADR50017P087CC(CHIPS)':
 'VSS78': CDS_PINID='VSS78';
NODE_NAME     J14 184
 '@S9S_MB_2U_LIB.S9S_MB_2U(SCH_1):PAGE95_I176@PURE_QUANTA.SCONN288_ADR50017P087CC(CHIPS)':
 'VSS79': CDS_PINID='VSS79';
NODE_NAME     J14 186
 '@S9S_MB_2U_LIB.S9S_MB_2U(SCH_1):PAGE95_I176@PURE_QUANTA.SCONN288_ADR50017P087CC(CHIPS)':
 'VSS80': CDS_PINID='VSS80';
NODE_NAME     J14 188
 '@S9S_MB_2U_LIB.S9S_MB_2U(SCH_1):PAGE95_I176@PURE_QUANTA.SCONN288_ADR50017P087CC(CHIPS)':
 'VSS81': CDS_PINID='VSS81';
NODE_NAME     J14 191
 '@S9S_MB_2U_LIB.S9S_MB_2U(SCH_1):PAGE95_I176@PURE_QUANTA.SCONN288_ADR50017P087CC(CHIPS)':
 'VSS82': CDS_PINID='VSS82';
NODE_NAME     J14 193
 '@S9S_MB_2U_LIB.S9S_MB_2U(SCH_1):PAGE95_I176@PURE_QUANTA.SCONN288_ADR50017P087CC(CHIPS)':
 'VSS83': CDS_PINID='VSS83';
NODE_NAME     J14 195
 '@S9S_MB_2U_LIB.S9S_MB_2U(SCH_1):PAGE95_I176@PURE_QUANTA.SCONN288_ADR50017P087CC(CHIPS)':
 'VSS84': CDS_PINID='VSS84';
NODE_NAME     J14 197
 '@S9S_MB_2U_LIB.S9S_MB_2U(SCH_1):PAGE95_I176@PURE_QUANTA.SCONN288_ADR50017P087CC(CHIPS)':
 'VSS85': CDS_PINID='VSS85';
NODE_NAME     J14 199
 '@S9S_MB_2U_LIB.S9S_MB_2U(SCH_1):PAGE95_I176@PURE_QUANTA.SCONN288_ADR50017P087CC(CHIPS)':
 'VSS86': CDS_PINID='VSS86';
NODE_NAME     J14 202
 '@S9S_MB_2U_LIB.S9S_MB_2U(SCH_1):PAGE95_I176@PURE_QUANTA.SCONN288_ADR50017P087CC(CHIPS)':
 'VSS87': CDS_PINID='VSS87';
NODE_NAME     J14 204
 '@S9S_MB_2U_LIB.S9S_MB_2U(SCH_1):PAGE95_I176@PURE_QUANTA.SCONN288_ADR50017P087CC(CHIPS)':
 'VSS88': CDS_PINID='VSS88';
NODE_NAME     J14 206
 '@S9S_MB_2U_LIB.S9S_MB_2U(SCH_1):PAGE95_I176@PURE_QUANTA.SCONN288_ADR50017P087CC(CHIPS)':
 'VSS89': CDS_PINID='VSS89';
NODE_NAME     J14 208
 '@S9S_MB_2U_LIB.S9S_MB_2U(SCH_1):PAGE95_I176@PURE_QUANTA.SCONN288_ADR50017P087CC(CHIPS)':
 'VSS90': CDS_PINID='VSS90';
NODE_NAME     J14 210
 '@S9S_MB_2U_LIB.S9S_MB_2U(SCH_1):PAGE95_I176@PURE_QUANTA.SCONN288_ADR50017P087CC(CHIPS)':
 'VSS91': CDS_PINID='VSS91';
NODE_NAME     J14 212
 '@S9S_MB_2U_LIB.S9S_MB_2U(SCH_1):PAGE95_I176@PURE_QUANTA.SCONN288_ADR50017P087CC(CHIPS)':
 'VSS92': CDS_PINID='VSS92';
NODE_NAME     J14 214
 '@S9S_MB_2U_LIB.S9S_MB_2U(SCH_1):PAGE95_I176@PURE_QUANTA.SCONN288_ADR50017P087CC(CHIPS)':
 'VSS93': CDS_PINID='VSS93';
NODE_NAME     J14 216
 '@S9S_MB_2U_LIB.S9S_MB_2U(SCH_1):PAGE95_I176@PURE_QUANTA.SCONN288_ADR50017P087CC(CHIPS)':
 'VSS94': CDS_PINID='VSS94';
NODE_NAME     J14 219
 '@S9S_MB_2U_LIB.S9S_MB_2U(SCH_1):PAGE95_I176@PURE_QUANTA.SCONN288_ADR50017P087CC(CHIPS)':
 'VSS95': CDS_PINID='VSS95';
NODE_NAME     J14 222
 '@S9S_MB_2U_LIB.S9S_MB_2U(SCH_1):PAGE95_I176@PURE_QUANTA.SCONN288_ADR50017P087CC(CHIPS)':
 'VSS96': CDS_PINID='VSS96';
NODE_NAME     J14 224
 '@S9S_MB_2U_LIB.S9S_MB_2U(SCH_1):PAGE95_I176@PURE_QUANTA.SCONN288_ADR50017P087CC(CHIPS)':
 'VSS97': CDS_PINID='VSS97';
NODE_NAME     J14 226
 '@S9S_MB_2U_LIB.S9S_MB_2U(SCH_1):PAGE95_I176@PURE_QUANTA.SCONN288_ADR50017P087CC(CHIPS)':
 'VSS98': CDS_PINID='VSS98';
NODE_NAME     J14 228
 '@S9S_MB_2U_LIB.S9S_MB_2U(SCH_1):PAGE95_I176@PURE_QUANTA.SCONN288_ADR50017P087CC(CHIPS)':
 'VSS99': CDS_PINID='VSS99';
NODE_NAME     J14 230
 '@S9S_MB_2U_LIB.S9S_MB_2U(SCH_1):PAGE95_I176@PURE_QUANTA.SCONN288_ADR50017P087CC(CHIPS)':
 'VSS100': CDS_PINID='VSS100';
NODE_NAME     J14 233
 '@S9S_MB_2U_LIB.S9S_MB_2U(SCH_1):PAGE95_I176@PURE_QUANTA.SCONN288_ADR50017P087CC(CHIPS)':
 'VSS101': CDS_PINID='VSS101';
NODE_NAME     J14 235
 '@S9S_MB_2U_LIB.S9S_MB_2U(SCH_1):PAGE95_I176@PURE_QUANTA.SCONN288_ADR50017P087CC(CHIPS)':
 'VSS102': CDS_PINID='VSS102';
NODE_NAME     J14 237
 '@S9S_MB_2U_LIB.S9S_MB_2U(SCH_1):PAGE95_I176@PURE_QUANTA.SCONN288_ADR50017P087CC(CHIPS)':
 'VSS103': CDS_PINID='VSS103';
NODE_NAME     J14 240
 '@S9S_MB_2U_LIB.S9S_MB_2U(SCH_1):PAGE95_I176@PURE_QUANTA.SCONN288_ADR50017P087CC(CHIPS)':
 'VSS104': CDS_PINID='VSS104';
NODE_NAME     J14 242
 '@S9S_MB_2U_LIB.S9S_MB_2U(SCH_1):PAGE95_I176@PURE_QUANTA.SCONN288_ADR50017P087CC(CHIPS)':
 'VSS105': CDS_PINID='VSS105';
NODE_NAME     J14 244
 '@S9S_MB_2U_LIB.S9S_MB_2U(SCH_1):PAGE95_I176@PURE_QUANTA.SCONN288_ADR50017P087CC(CHIPS)':
 'VSS106': CDS_PINID='VSS106';
NODE_NAME     J14 246
 '@S9S_MB_2U_LIB.S9S_MB_2U(SCH_1):PAGE95_I176@PURE_QUANTA.SCONN288_ADR50017P087CC(CHIPS)':
 'VSS107': CDS_PINID='VSS107';
NODE_NAME     J14 248
 '@S9S_MB_2U_LIB.S9S_MB_2U(SCH_1):PAGE95_I176@PURE_QUANTA.SCONN288_ADR50017P087CC(CHIPS)':
 'VSS108': CDS_PINID='VSS108';
NODE_NAME     J14 251
 '@S9S_MB_2U_LIB.S9S_MB_2U(SCH_1):PAGE95_I176@PURE_QUANTA.SCONN288_ADR50017P087CC(CHIPS)':
 'VSS109': CDS_PINID='VSS109';
NODE_NAME     J14 253
 '@S9S_MB_2U_LIB.S9S_MB_2U(SCH_1):PAGE95_I176@PURE_QUANTA.SCONN288_ADR50017P087CC(CHIPS)':
 'VSS110': CDS_PINID='VSS110';
NODE_NAME     J14 255
 '@S9S_MB_2U_LIB.S9S_MB_2U(SCH_1):PAGE95_I176@PURE_QUANTA.SCONN288_ADR50017P087CC(CHIPS)':
 'VSS111': CDS_PINID='VSS111';
NODE_NAME     J14 257
 '@S9S_MB_2U_LIB.S9S_MB_2U(SCH_1):PAGE95_I176@PURE_QUANTA.SCONN288_ADR50017P087CC(CHIPS)':
 'VSS112': CDS_PINID='VSS112';
NODE_NAME     J14 259
 '@S9S_MB_2U_LIB.S9S_MB_2U(SCH_1):PAGE95_I176@PURE_QUANTA.SCONN288_ADR50017P087CC(CHIPS)':
 'VSS113': CDS_PINID='VSS113';
NODE_NAME     J14 262
 '@S9S_MB_2U_LIB.S9S_MB_2U(SCH_1):PAGE95_I176@PURE_QUANTA.SCONN288_ADR50017P087CC(CHIPS)':
 'VSS114': CDS_PINID='VSS114';
NODE_NAME     J14 264
 '@S9S_MB_2U_LIB.S9S_MB_2U(SCH_1):PAGE95_I176@PURE_QUANTA.SCONN288_ADR50017P087CC(CHIPS)':
 'VSS115': CDS_PINID='VSS115';
NODE_NAME     J14 266
 '@S9S_MB_2U_LIB.S9S_MB_2U(SCH_1):PAGE95_I176@PURE_QUANTA.SCONN288_ADR50017P087CC(CHIPS)':
 'VSS116': CDS_PINID='VSS116';
NODE_NAME     J14 268
 '@S9S_MB_2U_LIB.S9S_MB_2U(SCH_1):PAGE95_I176@PURE_QUANTA.SCONN288_ADR50017P087CC(CHIPS)':
 'VSS117': CDS_PINID='VSS117';
NODE_NAME     J14 270
 '@S9S_MB_2U_LIB.S9S_MB_2U(SCH_1):PAGE95_I176@PURE_QUANTA.SCONN288_ADR50017P087CC(CHIPS)':
 'VSS118': CDS_PINID='VSS118';
NODE_NAME     J14 273
 '@S9S_MB_2U_LIB.S9S_MB_2U(SCH_1):PAGE95_I176@PURE_QUANTA.SCONN288_ADR50017P087CC(CHIPS)':
 'VSS119': CDS_PINID='VSS119';
NODE_NAME     J14 275
 '@S9S_MB_2U_LIB.S9S_MB_2U(SCH_1):PAGE95_I176@PURE_QUANTA.SCONN288_ADR50017P087CC(CHIPS)':
 'VSS120': CDS_PINID='VSS120';
NODE_NAME     J14 277
 '@S9S_MB_2U_LIB.S9S_MB_2U(SCH_1):PAGE95_I176@PURE_QUANTA.SCONN288_ADR50017P087CC(CHIPS)':
 'VSS121': CDS_PINID='VSS121';
NODE_NAME     J14 279
 '@S9S_MB_2U_LIB.S9S_MB_2U(SCH_1):PAGE95_I176@PURE_QUANTA.SCONN288_ADR50017P087CC(CHIPS)':
 'VSS122': CDS_PINID='VSS122';
NODE_NAME     J14 281
 '@S9S_MB_2U_LIB.S9S_MB_2U(SCH_1):PAGE95_I176@PURE_QUANTA.SCONN288_ADR50017P087CC(CHIPS)':
 'VSS123': CDS_PINID='VSS123';
NODE_NAME     J14 284
 '@S9S_MB_2U_LIB.S9S_MB_2U(SCH_1):PAGE95_I176@PURE_QUANTA.SCONN288_ADR50017P087CC(CHIPS)':
 'VSS124': CDS_PINID='VSS124';
NODE_NAME     J14 286
 '@S9S_MB_2U_LIB.S9S_MB_2U(SCH_1):PAGE95_I176@PURE_QUANTA.SCONN288_ADR50017P087CC(CHIPS)':
 'VSS125': CDS_PINID='VSS125';
NODE_NAME     J14 288
 '@S9S_MB_2U_LIB.S9S_MB_2U(SCH_1):PAGE95_I176@PURE_QUANTA.SCONN288_ADR50017P087CC(CHIPS)':
 'VSS126': CDS_PINID='VSS126';
NODE_NAME     R40 2
 '@S9S_MB_2U_LIB.S9S_MB_2U(SCH_1):PAGE96_I47@PURE_QUANTA.Q_RES(CHIPS)':
 'B': CDS_PINID='B';
NODE_NAME     C44 2
 '@S9S_MB_2U_LIB.S9S_MB_2U(SCH_1):PAGE96_I121@PURE_QUANTA.Q_CAP(CHIPS)':
 'B': CDS_PINID='B';
NODE_NAME     C45 2
 '@S9S_MB_2U_LIB.S9S_MB_2U(SCH_1):PAGE96_I125@PURE_QUANTA.Q_CAP(CHIPS)':
 'B': CDS_PINID='B';
NODE_NAME     C46 2
 '@S9S_MB_2U_LIB.S9S_MB_2U(SCH_1):PAGE96_I127@PURE_QUANTA.Q_CAP(CHIPS)':
 'B': CDS_PINID='B';
NODE_NAME     J15 G1
 '@S9S_MB_2U_LIB.S9S_MB_2U(SCH_1):PAGE96_I176@PURE_QUANTA.SCONN288_ADR50017P130CC(CHIPS)':
 'G1': CDS_PINID='G1';
NODE_NAME     J15 G2
 '@S9S_MB_2U_LIB.S9S_MB_2U(SCH_1):PAGE96_I176@PURE_QUANTA.SCONN288_ADR50017P130CC(CHIPS)':
 'G2': CDS_PINID='G2';
NODE_NAME     J15 G3
 '@S9S_MB_2U_LIB.S9S_MB_2U(SCH_1):PAGE96_I176@PURE_QUANTA.SCONN288_ADR50017P130CC(CHIPS)':
 'G3': CDS_PINID='G3';
NODE_NAME     J15 6
 '@S9S_MB_2U_LIB.S9S_MB_2U(SCH_1):PAGE96_I176@PURE_QUANTA.SCONN288_ADR50017P130CC(CHIPS)':
 'VSS0': CDS_PINID='VSS0';
NODE_NAME     J15 8
 '@S9S_MB_2U_LIB.S9S_MB_2U(SCH_1):PAGE96_I176@PURE_QUANTA.SCONN288_ADR50017P130CC(CHIPS)':
 'VSS1': CDS_PINID='VSS1';
NODE_NAME     J15 10
 '@S9S_MB_2U_LIB.S9S_MB_2U(SCH_1):PAGE96_I176@PURE_QUANTA.SCONN288_ADR50017P130CC(CHIPS)':
 'VSS2': CDS_PINID='VSS2';
NODE_NAME     J15 13
 '@S9S_MB_2U_LIB.S9S_MB_2U(SCH_1):PAGE96_I176@PURE_QUANTA.SCONN288_ADR50017P130CC(CHIPS)':
 'VSS3': CDS_PINID='VSS3';
NODE_NAME     J15 15
 '@S9S_MB_2U_LIB.S9S_MB_2U(SCH_1):PAGE96_I176@PURE_QUANTA.SCONN288_ADR50017P130CC(CHIPS)':
 'VSS4': CDS_PINID='VSS4';
NODE_NAME     J15 17
 '@S9S_MB_2U_LIB.S9S_MB_2U(SCH_1):PAGE96_I176@PURE_QUANTA.SCONN288_ADR50017P130CC(CHIPS)':
 'VSS5': CDS_PINID='VSS5';
NODE_NAME     J15 19
 '@S9S_MB_2U_LIB.S9S_MB_2U(SCH_1):PAGE96_I176@PURE_QUANTA.SCONN288_ADR50017P130CC(CHIPS)':
 'VSS6': CDS_PINID='VSS6';
NODE_NAME     J15 21
 '@S9S_MB_2U_LIB.S9S_MB_2U(SCH_1):PAGE96_I176@PURE_QUANTA.SCONN288_ADR50017P130CC(CHIPS)':
 'VSS7': CDS_PINID='VSS7';
NODE_NAME     J15 24
 '@S9S_MB_2U_LIB.S9S_MB_2U(SCH_1):PAGE96_I176@PURE_QUANTA.SCONN288_ADR50017P130CC(CHIPS)':
 'VSS8': CDS_PINID='VSS8';
NODE_NAME     J15 26
 '@S9S_MB_2U_LIB.S9S_MB_2U(SCH_1):PAGE96_I176@PURE_QUANTA.SCONN288_ADR50017P130CC(CHIPS)':
 'VSS9': CDS_PINID='VSS9';
NODE_NAME     J15 28
 '@S9S_MB_2U_LIB.S9S_MB_2U(SCH_1):PAGE96_I176@PURE_QUANTA.SCONN288_ADR50017P130CC(CHIPS)':
 'VSS10': CDS_PINID='VSS10';
NODE_NAME     J15 30
 '@S9S_MB_2U_LIB.S9S_MB_2U(SCH_1):PAGE96_I176@PURE_QUANTA.SCONN288_ADR50017P130CC(CHIPS)':
 'VSS11': CDS_PINID='VSS11';
NODE_NAME     J15 32
 '@S9S_MB_2U_LIB.S9S_MB_2U(SCH_1):PAGE96_I176@PURE_QUANTA.SCONN288_ADR50017P130CC(CHIPS)':
 'VSS12': CDS_PINID='VSS12';
NODE_NAME     J15 35
 '@S9S_MB_2U_LIB.S9S_MB_2U(SCH_1):PAGE96_I176@PURE_QUANTA.SCONN288_ADR50017P130CC(CHIPS)':
 'VSS13': CDS_PINID='VSS13';
NODE_NAME     J15 37
 '@S9S_MB_2U_LIB.S9S_MB_2U(SCH_1):PAGE96_I176@PURE_QUANTA.SCONN288_ADR50017P130CC(CHIPS)':
 'VSS14': CDS_PINID='VSS14';
NODE_NAME     J15 39
 '@S9S_MB_2U_LIB.S9S_MB_2U(SCH_1):PAGE96_I176@PURE_QUANTA.SCONN288_ADR50017P130CC(CHIPS)':
 'VSS15': CDS_PINID='VSS15';
NODE_NAME     J15 41
 '@S9S_MB_2U_LIB.S9S_MB_2U(SCH_1):PAGE96_I176@PURE_QUANTA.SCONN288_ADR50017P130CC(CHIPS)':
 'VSS16': CDS_PINID='VSS16';
NODE_NAME     J15 43
 '@S9S_MB_2U_LIB.S9S_MB_2U(SCH_1):PAGE96_I176@PURE_QUANTA.SCONN288_ADR50017P130CC(CHIPS)':
 'VSS17': CDS_PINID='VSS17';
NODE_NAME     J15 46
 '@S9S_MB_2U_LIB.S9S_MB_2U(SCH_1):PAGE96_I176@PURE_QUANTA.SCONN288_ADR50017P130CC(CHIPS)':
 'VSS18': CDS_PINID='VSS18';
NODE_NAME     J15 48
 '@S9S_MB_2U_LIB.S9S_MB_2U(SCH_1):PAGE96_I176@PURE_QUANTA.SCONN288_ADR50017P130CC(CHIPS)':
 'VSS19': CDS_PINID='VSS19';
NODE_NAME     J15 50
 '@S9S_MB_2U_LIB.S9S_MB_2U(SCH_1):PAGE96_I176@PURE_QUANTA.SCONN288_ADR50017P130CC(CHIPS)':
 'VSS20': CDS_PINID='VSS20';
NODE_NAME     J15 52
 '@S9S_MB_2U_LIB.S9S_MB_2U(SCH_1):PAGE96_I176@PURE_QUANTA.SCONN288_ADR50017P130CC(CHIPS)':
 'VSS21': CDS_PINID='VSS21';
NODE_NAME     J15 54
 '@S9S_MB_2U_LIB.S9S_MB_2U(SCH_1):PAGE96_I176@PURE_QUANTA.SCONN288_ADR50017P130CC(CHIPS)':
 'VSS22': CDS_PINID='VSS22';
NODE_NAME     J15 57
 '@S9S_MB_2U_LIB.S9S_MB_2U(SCH_1):PAGE96_I176@PURE_QUANTA.SCONN288_ADR50017P130CC(CHIPS)':
 'VSS23': CDS_PINID='VSS23';
NODE_NAME     J15 59
 '@S9S_MB_2U_LIB.S9S_MB_2U(SCH_1):PAGE96_I176@PURE_QUANTA.SCONN288_ADR50017P130CC(CHIPS)':
 'VSS24': CDS_PINID='VSS24';
NODE_NAME     J15 61
 '@S9S_MB_2U_LIB.S9S_MB_2U(SCH_1):PAGE96_I176@PURE_QUANTA.SCONN288_ADR50017P130CC(CHIPS)':
 'VSS25': CDS_PINID='VSS25';
NODE_NAME     J15 63
 '@S9S_MB_2U_LIB.S9S_MB_2U(SCH_1):PAGE96_I176@PURE_QUANTA.SCONN288_ADR50017P130CC(CHIPS)':
 'VSS26': CDS_PINID='VSS26';
NODE_NAME     J15 65
 '@S9S_MB_2U_LIB.S9S_MB_2U(SCH_1):PAGE96_I176@PURE_QUANTA.SCONN288_ADR50017P130CC(CHIPS)':
 'VSS27': CDS_PINID='VSS27';
NODE_NAME     J15 67
 '@S9S_MB_2U_LIB.S9S_MB_2U(SCH_1):PAGE96_I176@PURE_QUANTA.SCONN288_ADR50017P130CC(CHIPS)':
 'VSS28': CDS_PINID='VSS28';
NODE_NAME     J15 69
 '@S9S_MB_2U_LIB.S9S_MB_2U(SCH_1):PAGE96_I176@PURE_QUANTA.SCONN288_ADR50017P130CC(CHIPS)':
 'VSS29': CDS_PINID='VSS29';
NODE_NAME     J15 71
 '@S9S_MB_2U_LIB.S9S_MB_2U(SCH_1):PAGE96_I176@PURE_QUANTA.SCONN288_ADR50017P130CC(CHIPS)':
 'VSS30': CDS_PINID='VSS30';
NODE_NAME     J15 73
 '@S9S_MB_2U_LIB.S9S_MB_2U(SCH_1):PAGE96_I176@PURE_QUANTA.SCONN288_ADR50017P130CC(CHIPS)':
 'VSS31': CDS_PINID='VSS31';
NODE_NAME     J15 75
 '@S9S_MB_2U_LIB.S9S_MB_2U(SCH_1):PAGE96_I176@PURE_QUANTA.SCONN288_ADR50017P130CC(CHIPS)':
 'VSS32': CDS_PINID='VSS32';
NODE_NAME     J15 77
 '@S9S_MB_2U_LIB.S9S_MB_2U(SCH_1):PAGE96_I176@PURE_QUANTA.SCONN288_ADR50017P130CC(CHIPS)':
 'VSS33': CDS_PINID='VSS33';
NODE_NAME     J15 79
 '@S9S_MB_2U_LIB.S9S_MB_2U(SCH_1):PAGE96_I176@PURE_QUANTA.SCONN288_ADR50017P130CC(CHIPS)':
 'VSS34': CDS_PINID='VSS34';
NODE_NAME     J15 81
 '@S9S_MB_2U_LIB.S9S_MB_2U(SCH_1):PAGE96_I176@PURE_QUANTA.SCONN288_ADR50017P130CC(CHIPS)':
 'VSS35': CDS_PINID='VSS35';
NODE_NAME     J15 83
 '@S9S_MB_2U_LIB.S9S_MB_2U(SCH_1):PAGE96_I176@PURE_QUANTA.SCONN288_ADR50017P130CC(CHIPS)':
 'VSS36': CDS_PINID='VSS36';
NODE_NAME     J15 85
 '@S9S_MB_2U_LIB.S9S_MB_2U(SCH_1):PAGE96_I176@PURE_QUANTA.SCONN288_ADR50017P130CC(CHIPS)':
 'VSS37': CDS_PINID='VSS37';
NODE_NAME     J15 88
 '@S9S_MB_2U_LIB.S9S_MB_2U(SCH_1):PAGE96_I176@PURE_QUANTA.SCONN288_ADR50017P130CC(CHIPS)':
 'VSS38': CDS_PINID='VSS38';
NODE_NAME     J15 90
 '@S9S_MB_2U_LIB.S9S_MB_2U(SCH_1):PAGE96_I176@PURE_QUANTA.SCONN288_ADR50017P130CC(CHIPS)':
 'VSS39': CDS_PINID='VSS39';
NODE_NAME     J15 92
 '@S9S_MB_2U_LIB.S9S_MB_2U(SCH_1):PAGE96_I176@PURE_QUANTA.SCONN288_ADR50017P130CC(CHIPS)':
 'VSS40': CDS_PINID='VSS40';
NODE_NAME     J15 95
 '@S9S_MB_2U_LIB.S9S_MB_2U(SCH_1):PAGE96_I176@PURE_QUANTA.SCONN288_ADR50017P130CC(CHIPS)':
 'VSS41': CDS_PINID='VSS41';
NODE_NAME     J15 97
 '@S9S_MB_2U_LIB.S9S_MB_2U(SCH_1):PAGE96_I176@PURE_QUANTA.SCONN288_ADR50017P130CC(CHIPS)':
 'VSS42': CDS_PINID='VSS42';
NODE_NAME     J15 99
 '@S9S_MB_2U_LIB.S9S_MB_2U(SCH_1):PAGE96_I176@PURE_QUANTA.SCONN288_ADR50017P130CC(CHIPS)':
 'VSS43': CDS_PINID='VSS43';
NODE_NAME     J15 101
 '@S9S_MB_2U_LIB.S9S_MB_2U(SCH_1):PAGE96_I176@PURE_QUANTA.SCONN288_ADR50017P130CC(CHIPS)':
 'VSS44': CDS_PINID='VSS44';
NODE_NAME     J15 103
 '@S9S_MB_2U_LIB.S9S_MB_2U(SCH_1):PAGE96_I176@PURE_QUANTA.SCONN288_ADR50017P130CC(CHIPS)':
 'VSS45': CDS_PINID='VSS45';
NODE_NAME     J15 106
 '@S9S_MB_2U_LIB.S9S_MB_2U(SCH_1):PAGE96_I176@PURE_QUANTA.SCONN288_ADR50017P130CC(CHIPS)':
 'VSS46': CDS_PINID='VSS46';
NODE_NAME     J15 108
 '@S9S_MB_2U_LIB.S9S_MB_2U(SCH_1):PAGE96_I176@PURE_QUANTA.SCONN288_ADR50017P130CC(CHIPS)':
 'VSS47': CDS_PINID='VSS47';
NODE_NAME     J15 110
 '@S9S_MB_2U_LIB.S9S_MB_2U(SCH_1):PAGE96_I176@PURE_QUANTA.SCONN288_ADR50017P130CC(CHIPS)':
 'VSS48': CDS_PINID='VSS48';
NODE_NAME     J15 112
 '@S9S_MB_2U_LIB.S9S_MB_2U(SCH_1):PAGE96_I176@PURE_QUANTA.SCONN288_ADR50017P130CC(CHIPS)':
 'VSS49': CDS_PINID='VSS49';
NODE_NAME     J15 114
 '@S9S_MB_2U_LIB.S9S_MB_2U(SCH_1):PAGE96_I176@PURE_QUANTA.SCONN288_ADR50017P130CC(CHIPS)':
 'VSS50': CDS_PINID='VSS50';
NODE_NAME     J15 117
 '@S9S_MB_2U_LIB.S9S_MB_2U(SCH_1):PAGE96_I176@PURE_QUANTA.SCONN288_ADR50017P130CC(CHIPS)':
 'VSS51': CDS_PINID='VSS51';
NODE_NAME     J15 119
 '@S9S_MB_2U_LIB.S9S_MB_2U(SCH_1):PAGE96_I176@PURE_QUANTA.SCONN288_ADR50017P130CC(CHIPS)':
 'VSS52': CDS_PINID='VSS52';
NODE_NAME     J15 121
 '@S9S_MB_2U_LIB.S9S_MB_2U(SCH_1):PAGE96_I176@PURE_QUANTA.SCONN288_ADR50017P130CC(CHIPS)':
 'VSS53': CDS_PINID='VSS53';
NODE_NAME     J15 123
 '@S9S_MB_2U_LIB.S9S_MB_2U(SCH_1):PAGE96_I176@PURE_QUANTA.SCONN288_ADR50017P130CC(CHIPS)':
 'VSS54': CDS_PINID='VSS54';
NODE_NAME     J15 125
 '@S9S_MB_2U_LIB.S9S_MB_2U(SCH_1):PAGE96_I176@PURE_QUANTA.SCONN288_ADR50017P130CC(CHIPS)':
 'VSS55': CDS_PINID='VSS55';
NODE_NAME     J15 128
 '@S9S_MB_2U_LIB.S9S_MB_2U(SCH_1):PAGE96_I176@PURE_QUANTA.SCONN288_ADR50017P130CC(CHIPS)':
 'VSS56': CDS_PINID='VSS56';
NODE_NAME     J15 130
 '@S9S_MB_2U_LIB.S9S_MB_2U(SCH_1):PAGE96_I176@PURE_QUANTA.SCONN288_ADR50017P130CC(CHIPS)':
 'VSS57': CDS_PINID='VSS57';
NODE_NAME     J15 132
 '@S9S_MB_2U_LIB.S9S_MB_2U(SCH_1):PAGE96_I176@PURE_QUANTA.SCONN288_ADR50017P130CC(CHIPS)':
 'VSS58': CDS_PINID='VSS58';
NODE_NAME     J15 134
 '@S9S_MB_2U_LIB.S9S_MB_2U(SCH_1):PAGE96_I176@PURE_QUANTA.SCONN288_ADR50017P130CC(CHIPS)':
 'VSS59': CDS_PINID='VSS59';
NODE_NAME     J15 136
 '@S9S_MB_2U_LIB.S9S_MB_2U(SCH_1):PAGE96_I176@PURE_QUANTA.SCONN288_ADR50017P130CC(CHIPS)':
 'VSS60': CDS_PINID='VSS60';
NODE_NAME     J15 139
 '@S9S_MB_2U_LIB.S9S_MB_2U(SCH_1):PAGE96_I176@PURE_QUANTA.SCONN288_ADR50017P130CC(CHIPS)':
 'VSS61': CDS_PINID='VSS61';
NODE_NAME     J15 141
 '@S9S_MB_2U_LIB.S9S_MB_2U(SCH_1):PAGE96_I176@PURE_QUANTA.SCONN288_ADR50017P130CC(CHIPS)':
 'VSS62': CDS_PINID='VSS62';
NODE_NAME     J15 143
 '@S9S_MB_2U_LIB.S9S_MB_2U(SCH_1):PAGE96_I176@PURE_QUANTA.SCONN288_ADR50017P130CC(CHIPS)':
 'VSS63': CDS_PINID='VSS63';
NODE_NAME     J15 151
 '@S9S_MB_2U_LIB.S9S_MB_2U(SCH_1):PAGE96_I176@PURE_QUANTA.SCONN288_ADR50017P130CC(CHIPS)':
 'VSS64': CDS_PINID='VSS64';
NODE_NAME     J15 153
 '@S9S_MB_2U_LIB.S9S_MB_2U(SCH_1):PAGE96_I176@PURE_QUANTA.SCONN288_ADR50017P130CC(CHIPS)':
 'VSS65': CDS_PINID='VSS65';
NODE_NAME     J15 155
 '@S9S_MB_2U_LIB.S9S_MB_2U(SCH_1):PAGE96_I176@PURE_QUANTA.SCONN288_ADR50017P130CC(CHIPS)':
 'VSS66': CDS_PINID='VSS66';
NODE_NAME     J15 158
 '@S9S_MB_2U_LIB.S9S_MB_2U(SCH_1):PAGE96_I176@PURE_QUANTA.SCONN288_ADR50017P130CC(CHIPS)':
 'VSS67': CDS_PINID='VSS67';
NODE_NAME     J15 160
 '@S9S_MB_2U_LIB.S9S_MB_2U(SCH_1):PAGE96_I176@PURE_QUANTA.SCONN288_ADR50017P130CC(CHIPS)':
 'VSS68': CDS_PINID='VSS68';
NODE_NAME     J15 162
 '@S9S_MB_2U_LIB.S9S_MB_2U(SCH_1):PAGE96_I176@PURE_QUANTA.SCONN288_ADR50017P130CC(CHIPS)':
 'VSS69': CDS_PINID='VSS69';
NODE_NAME     J15 164
 '@S9S_MB_2U_LIB.S9S_MB_2U(SCH_1):PAGE96_I176@PURE_QUANTA.SCONN288_ADR50017P130CC(CHIPS)':
 'VSS70': CDS_PINID='VSS70';
NODE_NAME     J15 166
 '@S9S_MB_2U_LIB.S9S_MB_2U(SCH_1):PAGE96_I176@PURE_QUANTA.SCONN288_ADR50017P130CC(CHIPS)':
 'VSS71': CDS_PINID='VSS71';
NODE_NAME     J15 169
 '@S9S_MB_2U_LIB.S9S_MB_2U(SCH_1):PAGE96_I176@PURE_QUANTA.SCONN288_ADR50017P130CC(CHIPS)':
 'VSS72': CDS_PINID='VSS72';
NODE_NAME     J15 171
 '@S9S_MB_2U_LIB.S9S_MB_2U(SCH_1):PAGE96_I176@PURE_QUANTA.SCONN288_ADR50017P130CC(CHIPS)':
 'VSS73': CDS_PINID='VSS73';
NODE_NAME     J15 173
 '@S9S_MB_2U_LIB.S9S_MB_2U(SCH_1):PAGE96_I176@PURE_QUANTA.SCONN288_ADR50017P130CC(CHIPS)':
 'VSS74': CDS_PINID='VSS74';
NODE_NAME     J15 175
 '@S9S_MB_2U_LIB.S9S_MB_2U(SCH_1):PAGE96_I176@PURE_QUANTA.SCONN288_ADR50017P130CC(CHIPS)':
 'VSS75': CDS_PINID='VSS75';
NODE_NAME     J15 177
 '@S9S_MB_2U_LIB.S9S_MB_2U(SCH_1):PAGE96_I176@PURE_QUANTA.SCONN288_ADR50017P130CC(CHIPS)':
 'VSS76': CDS_PINID='VSS76';
NODE_NAME     J15 180
 '@S9S_MB_2U_LIB.S9S_MB_2U(SCH_1):PAGE96_I176@PURE_QUANTA.SCONN288_ADR50017P130CC(CHIPS)':
 'VSS77': CDS_PINID='VSS77';
NODE_NAME     J15 182
 '@S9S_MB_2U_LIB.S9S_MB_2U(SCH_1):PAGE96_I176@PURE_QUANTA.SCONN288_ADR50017P130CC(CHIPS)':
 'VSS78': CDS_PINID='VSS78';
NODE_NAME     J15 184
 '@S9S_MB_2U_LIB.S9S_MB_2U(SCH_1):PAGE96_I176@PURE_QUANTA.SCONN288_ADR50017P130CC(CHIPS)':
 'VSS79': CDS_PINID='VSS79';
NODE_NAME     J15 186
 '@S9S_MB_2U_LIB.S9S_MB_2U(SCH_1):PAGE96_I176@PURE_QUANTA.SCONN288_ADR50017P130CC(CHIPS)':
 'VSS80': CDS_PINID='VSS80';
NODE_NAME     J15 188
 '@S9S_MB_2U_LIB.S9S_MB_2U(SCH_1):PAGE96_I176@PURE_QUANTA.SCONN288_ADR50017P130CC(CHIPS)':
 'VSS81': CDS_PINID='VSS81';
NODE_NAME     J15 191
 '@S9S_MB_2U_LIB.S9S_MB_2U(SCH_1):PAGE96_I176@PURE_QUANTA.SCONN288_ADR50017P130CC(CHIPS)':
 'VSS82': CDS_PINID='VSS82';
NODE_NAME     J15 193
 '@S9S_MB_2U_LIB.S9S_MB_2U(SCH_1):PAGE96_I176@PURE_QUANTA.SCONN288_ADR50017P130CC(CHIPS)':
 'VSS83': CDS_PINID='VSS83';
NODE_NAME     J15 195
 '@S9S_MB_2U_LIB.S9S_MB_2U(SCH_1):PAGE96_I176@PURE_QUANTA.SCONN288_ADR50017P130CC(CHIPS)':
 'VSS84': CDS_PINID='VSS84';
NODE_NAME     J15 197
 '@S9S_MB_2U_LIB.S9S_MB_2U(SCH_1):PAGE96_I176@PURE_QUANTA.SCONN288_ADR50017P130CC(CHIPS)':
 'VSS85': CDS_PINID='VSS85';
NODE_NAME     J15 199
 '@S9S_MB_2U_LIB.S9S_MB_2U(SCH_1):PAGE96_I176@PURE_QUANTA.SCONN288_ADR50017P130CC(CHIPS)':
 'VSS86': CDS_PINID='VSS86';
NODE_NAME     J15 202
 '@S9S_MB_2U_LIB.S9S_MB_2U(SCH_1):PAGE96_I176@PURE_QUANTA.SCONN288_ADR50017P130CC(CHIPS)':
 'VSS87': CDS_PINID='VSS87';
NODE_NAME     J15 204
 '@S9S_MB_2U_LIB.S9S_MB_2U(SCH_1):PAGE96_I176@PURE_QUANTA.SCONN288_ADR50017P130CC(CHIPS)':
 'VSS88': CDS_PINID='VSS88';
NODE_NAME     J15 206
 '@S9S_MB_2U_LIB.S9S_MB_2U(SCH_1):PAGE96_I176@PURE_QUANTA.SCONN288_ADR50017P130CC(CHIPS)':
 'VSS89': CDS_PINID='VSS89';
NODE_NAME     J15 208
 '@S9S_MB_2U_LIB.S9S_MB_2U(SCH_1):PAGE96_I176@PURE_QUANTA.SCONN288_ADR50017P130CC(CHIPS)':
 'VSS90': CDS_PINID='VSS90';
NODE_NAME     J15 210
 '@S9S_MB_2U_LIB.S9S_MB_2U(SCH_1):PAGE96_I176@PURE_QUANTA.SCONN288_ADR50017P130CC(CHIPS)':
 'VSS91': CDS_PINID='VSS91';
NODE_NAME     J15 212
 '@S9S_MB_2U_LIB.S9S_MB_2U(SCH_1):PAGE96_I176@PURE_QUANTA.SCONN288_ADR50017P130CC(CHIPS)':
 'VSS92': CDS_PINID='VSS92';
NODE_NAME     J15 214
 '@S9S_MB_2U_LIB.S9S_MB_2U(SCH_1):PAGE96_I176@PURE_QUANTA.SCONN288_ADR50017P130CC(CHIPS)':
 'VSS93': CDS_PINID='VSS93';
NODE_NAME     J15 216
 '@S9S_MB_2U_LIB.S9S_MB_2U(SCH_1):PAGE96_I176@PURE_QUANTA.SCONN288_ADR50017P130CC(CHIPS)':
 'VSS94': CDS_PINID='VSS94';
NODE_NAME     J15 219
 '@S9S_MB_2U_LIB.S9S_MB_2U(SCH_1):PAGE96_I176@PURE_QUANTA.SCONN288_ADR50017P130CC(CHIPS)':
 'VSS95': CDS_PINID='VSS95';
NODE_NAME     J15 222
 '@S9S_MB_2U_LIB.S9S_MB_2U(SCH_1):PAGE96_I176@PURE_QUANTA.SCONN288_ADR50017P130CC(CHIPS)':
 'VSS96': CDS_PINID='VSS96';
NODE_NAME     J15 224
 '@S9S_MB_2U_LIB.S9S_MB_2U(SCH_1):PAGE96_I176@PURE_QUANTA.SCONN288_ADR50017P130CC(CHIPS)':
 'VSS97': CDS_PINID='VSS97';
NODE_NAME     J15 226
 '@S9S_MB_2U_LIB.S9S_MB_2U(SCH_1):PAGE96_I176@PURE_QUANTA.SCONN288_ADR50017P130CC(CHIPS)':
 'VSS98': CDS_PINID='VSS98';
NODE_NAME     J15 228
 '@S9S_MB_2U_LIB.S9S_MB_2U(SCH_1):PAGE96_I176@PURE_QUANTA.SCONN288_ADR50017P130CC(CHIPS)':
 'VSS99': CDS_PINID='VSS99';
NODE_NAME     J15 230
 '@S9S_MB_2U_LIB.S9S_MB_2U(SCH_1):PAGE96_I176@PURE_QUANTA.SCONN288_ADR50017P130CC(CHIPS)':
 'VSS100': CDS_PINID='VSS100';
NODE_NAME     J15 233
 '@S9S_MB_2U_LIB.S9S_MB_2U(SCH_1):PAGE96_I176@PURE_QUANTA.SCONN288_ADR50017P130CC(CHIPS)':
 'VSS101': CDS_PINID='VSS101';
NODE_NAME     J15 235
 '@S9S_MB_2U_LIB.S9S_MB_2U(SCH_1):PAGE96_I176@PURE_QUANTA.SCONN288_ADR50017P130CC(CHIPS)':
 'VSS102': CDS_PINID='VSS102';
NODE_NAME     J15 237
 '@S9S_MB_2U_LIB.S9S_MB_2U(SCH_1):PAGE96_I176@PURE_QUANTA.SCONN288_ADR50017P130CC(CHIPS)':
 'VSS103': CDS_PINID='VSS103';
NODE_NAME     J15 240
 '@S9S_MB_2U_LIB.S9S_MB_2U(SCH_1):PAGE96_I176@PURE_QUANTA.SCONN288_ADR50017P130CC(CHIPS)':
 'VSS104': CDS_PINID='VSS104';
NODE_NAME     J15 242
 '@S9S_MB_2U_LIB.S9S_MB_2U(SCH_1):PAGE96_I176@PURE_QUANTA.SCONN288_ADR50017P130CC(CHIPS)':
 'VSS105': CDS_PINID='VSS105';
NODE_NAME     J15 244
 '@S9S_MB_2U_LIB.S9S_MB_2U(SCH_1):PAGE96_I176@PURE_QUANTA.SCONN288_ADR50017P130CC(CHIPS)':
 'VSS106': CDS_PINID='VSS106';
NODE_NAME     J15 246
 '@S9S_MB_2U_LIB.S9S_MB_2U(SCH_1):PAGE96_I176@PURE_QUANTA.SCONN288_ADR50017P130CC(CHIPS)':
 'VSS107': CDS_PINID='VSS107';
NODE_NAME     J15 248
 '@S9S_MB_2U_LIB.S9S_MB_2U(SCH_1):PAGE96_I176@PURE_QUANTA.SCONN288_ADR50017P130CC(CHIPS)':
 'VSS108': CDS_PINID='VSS108';
NODE_NAME     J15 251
 '@S9S_MB_2U_LIB.S9S_MB_2U(SCH_1):PAGE96_I176@PURE_QUANTA.SCONN288_ADR50017P130CC(CHIPS)':
 'VSS109': CDS_PINID='VSS109';
NODE_NAME     J15 253
 '@S9S_MB_2U_LIB.S9S_MB_2U(SCH_1):PAGE96_I176@PURE_QUANTA.SCONN288_ADR50017P130CC(CHIPS)':
 'VSS110': CDS_PINID='VSS110';
NODE_NAME     J15 255
 '@S9S_MB_2U_LIB.S9S_MB_2U(SCH_1):PAGE96_I176@PURE_QUANTA.SCONN288_ADR50017P130CC(CHIPS)':
 'VSS111': CDS_PINID='VSS111';
NODE_NAME     J15 257
 '@S9S_MB_2U_LIB.S9S_MB_2U(SCH_1):PAGE96_I176@PURE_QUANTA.SCONN288_ADR50017P130CC(CHIPS)':
 'VSS112': CDS_PINID='VSS112';
NODE_NAME     J15 259
 '@S9S_MB_2U_LIB.S9S_MB_2U(SCH_1):PAGE96_I176@PURE_QUANTA.SCONN288_ADR50017P130CC(CHIPS)':
 'VSS113': CDS_PINID='VSS113';
NODE_NAME     J15 262
 '@S9S_MB_2U_LIB.S9S_MB_2U(SCH_1):PAGE96_I176@PURE_QUANTA.SCONN288_ADR50017P130CC(CHIPS)':
 'VSS114': CDS_PINID='VSS114';
NODE_NAME     J15 264
 '@S9S_MB_2U_LIB.S9S_MB_2U(SCH_1):PAGE96_I176@PURE_QUANTA.SCONN288_ADR50017P130CC(CHIPS)':
 'VSS115': CDS_PINID='VSS115';
NODE_NAME     J15 266
 '@S9S_MB_2U_LIB.S9S_MB_2U(SCH_1):PAGE96_I176@PURE_QUANTA.SCONN288_ADR50017P130CC(CHIPS)':
 'VSS116': CDS_PINID='VSS116';
NODE_NAME     J15 268
 '@S9S_MB_2U_LIB.S9S_MB_2U(SCH_1):PAGE96_I176@PURE_QUANTA.SCONN288_ADR50017P130CC(CHIPS)':
 'VSS117': CDS_PINID='VSS117';
NODE_NAME     J15 270
 '@S9S_MB_2U_LIB.S9S_MB_2U(SCH_1):PAGE96_I176@PURE_QUANTA.SCONN288_ADR50017P130CC(CHIPS)':
 'VSS118': CDS_PINID='VSS118';
NODE_NAME     J15 273
 '@S9S_MB_2U_LIB.S9S_MB_2U(SCH_1):PAGE96_I176@PURE_QUANTA.SCONN288_ADR50017P130CC(CHIPS)':
 'VSS119': CDS_PINID='VSS119';
NODE_NAME     J15 275
 '@S9S_MB_2U_LIB.S9S_MB_2U(SCH_1):PAGE96_I176@PURE_QUANTA.SCONN288_ADR50017P130CC(CHIPS)':
 'VSS120': CDS_PINID='VSS120';
NODE_NAME     J15 277
 '@S9S_MB_2U_LIB.S9S_MB_2U(SCH_1):PAGE96_I176@PURE_QUANTA.SCONN288_ADR50017P130CC(CHIPS)':
 'VSS121': CDS_PINID='VSS121';
NODE_NAME     J15 279
 '@S9S_MB_2U_LIB.S9S_MB_2U(SCH_1):PAGE96_I176@PURE_QUANTA.SCONN288_ADR50017P130CC(CHIPS)':
 'VSS122': CDS_PINID='VSS122';
NODE_NAME     J15 281
 '@S9S_MB_2U_LIB.S9S_MB_2U(SCH_1):PAGE96_I176@PURE_QUANTA.SCONN288_ADR50017P130CC(CHIPS)':
 'VSS123': CDS_PINID='VSS123';
NODE_NAME     J15 284
 '@S9S_MB_2U_LIB.S9S_MB_2U(SCH_1):PAGE96_I176@PURE_QUANTA.SCONN288_ADR50017P130CC(CHIPS)':
 'VSS124': CDS_PINID='VSS124';
NODE_NAME     J15 286
 '@S9S_MB_2U_LIB.S9S_MB_2U(SCH_1):PAGE96_I176@PURE_QUANTA.SCONN288_ADR50017P130CC(CHIPS)':
 'VSS125': CDS_PINID='VSS125';
NODE_NAME     J15 288
 '@S9S_MB_2U_LIB.S9S_MB_2U(SCH_1):PAGE96_I176@PURE_QUANTA.SCONN288_ADR50017P130CC(CHIPS)':
 'VSS126': CDS_PINID='VSS126';
NODE_NAME     R41 2
 '@S9S_MB_2U_LIB.S9S_MB_2U(SCH_1):PAGE97_I5@PURE_QUANTA.Q_RES(CHIPS)':
 'B': CDS_PINID='B';
NODE_NAME     C47 2
 '@S9S_MB_2U_LIB.S9S_MB_2U(SCH_1):PAGE97_I56@PURE_QUANTA.Q_CAP(CHIPS)':
 'B': CDS_PINID='B';
NODE_NAME     C48 2
 '@S9S_MB_2U_LIB.S9S_MB_2U(SCH_1):PAGE97_I59@PURE_QUANTA.Q_CAP(CHIPS)':
 'B': CDS_PINID='B';
NODE_NAME     C49 2
 '@S9S_MB_2U_LIB.S9S_MB_2U(SCH_1):PAGE97_I62@PURE_QUANTA.Q_CAP(CHIPS)':
 'B': CDS_PINID='B';
NODE_NAME     J16 G1
 '@S9S_MB_2U_LIB.S9S_MB_2U(SCH_1):PAGE97_I64@PURE_QUANTA.SCONN288_ADR50017P087CC(CHIPS)':
 'G1': CDS_PINID='G1';
NODE_NAME     J16 G2
 '@S9S_MB_2U_LIB.S9S_MB_2U(SCH_1):PAGE97_I64@PURE_QUANTA.SCONN288_ADR50017P087CC(CHIPS)':
 'G2': CDS_PINID='G2';
NODE_NAME     J16 G3
 '@S9S_MB_2U_LIB.S9S_MB_2U(SCH_1):PAGE97_I64@PURE_QUANTA.SCONN288_ADR50017P087CC(CHIPS)':
 'G3': CDS_PINID='G3';
NODE_NAME     J16 6
 '@S9S_MB_2U_LIB.S9S_MB_2U(SCH_1):PAGE97_I64@PURE_QUANTA.SCONN288_ADR50017P087CC(CHIPS)':
 'VSS0': CDS_PINID='VSS0';
NODE_NAME     J16 8
 '@S9S_MB_2U_LIB.S9S_MB_2U(SCH_1):PAGE97_I64@PURE_QUANTA.SCONN288_ADR50017P087CC(CHIPS)':
 'VSS1': CDS_PINID='VSS1';
NODE_NAME     J16 10
 '@S9S_MB_2U_LIB.S9S_MB_2U(SCH_1):PAGE97_I64@PURE_QUANTA.SCONN288_ADR50017P087CC(CHIPS)':
 'VSS2': CDS_PINID='VSS2';
NODE_NAME     J16 13
 '@S9S_MB_2U_LIB.S9S_MB_2U(SCH_1):PAGE97_I64@PURE_QUANTA.SCONN288_ADR50017P087CC(CHIPS)':
 'VSS3': CDS_PINID='VSS3';
NODE_NAME     J16 15
 '@S9S_MB_2U_LIB.S9S_MB_2U(SCH_1):PAGE97_I64@PURE_QUANTA.SCONN288_ADR50017P087CC(CHIPS)':
 'VSS4': CDS_PINID='VSS4';
NODE_NAME     J16 17
 '@S9S_MB_2U_LIB.S9S_MB_2U(SCH_1):PAGE97_I64@PURE_QUANTA.SCONN288_ADR50017P087CC(CHIPS)':
 'VSS5': CDS_PINID='VSS5';
NODE_NAME     J16 19
 '@S9S_MB_2U_LIB.S9S_MB_2U(SCH_1):PAGE97_I64@PURE_QUANTA.SCONN288_ADR50017P087CC(CHIPS)':
 'VSS6': CDS_PINID='VSS6';
NODE_NAME     J16 21
 '@S9S_MB_2U_LIB.S9S_MB_2U(SCH_1):PAGE97_I64@PURE_QUANTA.SCONN288_ADR50017P087CC(CHIPS)':
 'VSS7': CDS_PINID='VSS7';
NODE_NAME     J16 24
 '@S9S_MB_2U_LIB.S9S_MB_2U(SCH_1):PAGE97_I64@PURE_QUANTA.SCONN288_ADR50017P087CC(CHIPS)':
 'VSS8': CDS_PINID='VSS8';
NODE_NAME     J16 26
 '@S9S_MB_2U_LIB.S9S_MB_2U(SCH_1):PAGE97_I64@PURE_QUANTA.SCONN288_ADR50017P087CC(CHIPS)':
 'VSS9': CDS_PINID='VSS9';
NODE_NAME     J16 28
 '@S9S_MB_2U_LIB.S9S_MB_2U(SCH_1):PAGE97_I64@PURE_QUANTA.SCONN288_ADR50017P087CC(CHIPS)':
 'VSS10': CDS_PINID='VSS10';
NODE_NAME     J16 30
 '@S9S_MB_2U_LIB.S9S_MB_2U(SCH_1):PAGE97_I64@PURE_QUANTA.SCONN288_ADR50017P087CC(CHIPS)':
 'VSS11': CDS_PINID='VSS11';
NODE_NAME     J16 32
 '@S9S_MB_2U_LIB.S9S_MB_2U(SCH_1):PAGE97_I64@PURE_QUANTA.SCONN288_ADR50017P087CC(CHIPS)':
 'VSS12': CDS_PINID='VSS12';
NODE_NAME     J16 35
 '@S9S_MB_2U_LIB.S9S_MB_2U(SCH_1):PAGE97_I64@PURE_QUANTA.SCONN288_ADR50017P087CC(CHIPS)':
 'VSS13': CDS_PINID='VSS13';
NODE_NAME     J16 37
 '@S9S_MB_2U_LIB.S9S_MB_2U(SCH_1):PAGE97_I64@PURE_QUANTA.SCONN288_ADR50017P087CC(CHIPS)':
 'VSS14': CDS_PINID='VSS14';
NODE_NAME     J16 39
 '@S9S_MB_2U_LIB.S9S_MB_2U(SCH_1):PAGE97_I64@PURE_QUANTA.SCONN288_ADR50017P087CC(CHIPS)':
 'VSS15': CDS_PINID='VSS15';
NODE_NAME     J16 41
 '@S9S_MB_2U_LIB.S9S_MB_2U(SCH_1):PAGE97_I64@PURE_QUANTA.SCONN288_ADR50017P087CC(CHIPS)':
 'VSS16': CDS_PINID='VSS16';
NODE_NAME     J16 43
 '@S9S_MB_2U_LIB.S9S_MB_2U(SCH_1):PAGE97_I64@PURE_QUANTA.SCONN288_ADR50017P087CC(CHIPS)':
 'VSS17': CDS_PINID='VSS17';
NODE_NAME     J16 46
 '@S9S_MB_2U_LIB.S9S_MB_2U(SCH_1):PAGE97_I64@PURE_QUANTA.SCONN288_ADR50017P087CC(CHIPS)':
 'VSS18': CDS_PINID='VSS18';
NODE_NAME     J16 48
 '@S9S_MB_2U_LIB.S9S_MB_2U(SCH_1):PAGE97_I64@PURE_QUANTA.SCONN288_ADR50017P087CC(CHIPS)':
 'VSS19': CDS_PINID='VSS19';
NODE_NAME     J16 50
 '@S9S_MB_2U_LIB.S9S_MB_2U(SCH_1):PAGE97_I64@PURE_QUANTA.SCONN288_ADR50017P087CC(CHIPS)':
 'VSS20': CDS_PINID='VSS20';
NODE_NAME     J16 52
 '@S9S_MB_2U_LIB.S9S_MB_2U(SCH_1):PAGE97_I64@PURE_QUANTA.SCONN288_ADR50017P087CC(CHIPS)':
 'VSS21': CDS_PINID='VSS21';
NODE_NAME     J16 54
 '@S9S_MB_2U_LIB.S9S_MB_2U(SCH_1):PAGE97_I64@PURE_QUANTA.SCONN288_ADR50017P087CC(CHIPS)':
 'VSS22': CDS_PINID='VSS22';
NODE_NAME     J16 57
 '@S9S_MB_2U_LIB.S9S_MB_2U(SCH_1):PAGE97_I64@PURE_QUANTA.SCONN288_ADR50017P087CC(CHIPS)':
 'VSS23': CDS_PINID='VSS23';
NODE_NAME     J16 59
 '@S9S_MB_2U_LIB.S9S_MB_2U(SCH_1):PAGE97_I64@PURE_QUANTA.SCONN288_ADR50017P087CC(CHIPS)':
 'VSS24': CDS_PINID='VSS24';
NODE_NAME     J16 61
 '@S9S_MB_2U_LIB.S9S_MB_2U(SCH_1):PAGE97_I64@PURE_QUANTA.SCONN288_ADR50017P087CC(CHIPS)':
 'VSS25': CDS_PINID='VSS25';
NODE_NAME     J16 63
 '@S9S_MB_2U_LIB.S9S_MB_2U(SCH_1):PAGE97_I64@PURE_QUANTA.SCONN288_ADR50017P087CC(CHIPS)':
 'VSS26': CDS_PINID='VSS26';
NODE_NAME     J16 65
 '@S9S_MB_2U_LIB.S9S_MB_2U(SCH_1):PAGE97_I64@PURE_QUANTA.SCONN288_ADR50017P087CC(CHIPS)':
 'VSS27': CDS_PINID='VSS27';
NODE_NAME     J16 67
 '@S9S_MB_2U_LIB.S9S_MB_2U(SCH_1):PAGE97_I64@PURE_QUANTA.SCONN288_ADR50017P087CC(CHIPS)':
 'VSS28': CDS_PINID='VSS28';
NODE_NAME     J16 69
 '@S9S_MB_2U_LIB.S9S_MB_2U(SCH_1):PAGE97_I64@PURE_QUANTA.SCONN288_ADR50017P087CC(CHIPS)':
 'VSS29': CDS_PINID='VSS29';
NODE_NAME     J16 71
 '@S9S_MB_2U_LIB.S9S_MB_2U(SCH_1):PAGE97_I64@PURE_QUANTA.SCONN288_ADR50017P087CC(CHIPS)':
 'VSS30': CDS_PINID='VSS30';
NODE_NAME     J16 73
 '@S9S_MB_2U_LIB.S9S_MB_2U(SCH_1):PAGE97_I64@PURE_QUANTA.SCONN288_ADR50017P087CC(CHIPS)':
 'VSS31': CDS_PINID='VSS31';
NODE_NAME     J16 75
 '@S9S_MB_2U_LIB.S9S_MB_2U(SCH_1):PAGE97_I64@PURE_QUANTA.SCONN288_ADR50017P087CC(CHIPS)':
 'VSS32': CDS_PINID='VSS32';
NODE_NAME     J16 77
 '@S9S_MB_2U_LIB.S9S_MB_2U(SCH_1):PAGE97_I64@PURE_QUANTA.SCONN288_ADR50017P087CC(CHIPS)':
 'VSS33': CDS_PINID='VSS33';
NODE_NAME     J16 79
 '@S9S_MB_2U_LIB.S9S_MB_2U(SCH_1):PAGE97_I64@PURE_QUANTA.SCONN288_ADR50017P087CC(CHIPS)':
 'VSS34': CDS_PINID='VSS34';
NODE_NAME     J16 81
 '@S9S_MB_2U_LIB.S9S_MB_2U(SCH_1):PAGE97_I64@PURE_QUANTA.SCONN288_ADR50017P087CC(CHIPS)':
 'VSS35': CDS_PINID='VSS35';
NODE_NAME     J16 83
 '@S9S_MB_2U_LIB.S9S_MB_2U(SCH_1):PAGE97_I64@PURE_QUANTA.SCONN288_ADR50017P087CC(CHIPS)':
 'VSS36': CDS_PINID='VSS36';
NODE_NAME     J16 85
 '@S9S_MB_2U_LIB.S9S_MB_2U(SCH_1):PAGE97_I64@PURE_QUANTA.SCONN288_ADR50017P087CC(CHIPS)':
 'VSS37': CDS_PINID='VSS37';
NODE_NAME     J16 88
 '@S9S_MB_2U_LIB.S9S_MB_2U(SCH_1):PAGE97_I64@PURE_QUANTA.SCONN288_ADR50017P087CC(CHIPS)':
 'VSS38': CDS_PINID='VSS38';
NODE_NAME     J16 90
 '@S9S_MB_2U_LIB.S9S_MB_2U(SCH_1):PAGE97_I64@PURE_QUANTA.SCONN288_ADR50017P087CC(CHIPS)':
 'VSS39': CDS_PINID='VSS39';
NODE_NAME     J16 92
 '@S9S_MB_2U_LIB.S9S_MB_2U(SCH_1):PAGE97_I64@PURE_QUANTA.SCONN288_ADR50017P087CC(CHIPS)':
 'VSS40': CDS_PINID='VSS40';
NODE_NAME     J16 95
 '@S9S_MB_2U_LIB.S9S_MB_2U(SCH_1):PAGE97_I64@PURE_QUANTA.SCONN288_ADR50017P087CC(CHIPS)':
 'VSS41': CDS_PINID='VSS41';
NODE_NAME     J16 97
 '@S9S_MB_2U_LIB.S9S_MB_2U(SCH_1):PAGE97_I64@PURE_QUANTA.SCONN288_ADR50017P087CC(CHIPS)':
 'VSS42': CDS_PINID='VSS42';
NODE_NAME     J16 99
 '@S9S_MB_2U_LIB.S9S_MB_2U(SCH_1):PAGE97_I64@PURE_QUANTA.SCONN288_ADR50017P087CC(CHIPS)':
 'VSS43': CDS_PINID='VSS43';
NODE_NAME     J16 101
 '@S9S_MB_2U_LIB.S9S_MB_2U(SCH_1):PAGE97_I64@PURE_QUANTA.SCONN288_ADR50017P087CC(CHIPS)':
 'VSS44': CDS_PINID='VSS44';
NODE_NAME     J16 103
 '@S9S_MB_2U_LIB.S9S_MB_2U(SCH_1):PAGE97_I64@PURE_QUANTA.SCONN288_ADR50017P087CC(CHIPS)':
 'VSS45': CDS_PINID='VSS45';
NODE_NAME     J16 106
 '@S9S_MB_2U_LIB.S9S_MB_2U(SCH_1):PAGE97_I64@PURE_QUANTA.SCONN288_ADR50017P087CC(CHIPS)':
 'VSS46': CDS_PINID='VSS46';
NODE_NAME     J16 108
 '@S9S_MB_2U_LIB.S9S_MB_2U(SCH_1):PAGE97_I64@PURE_QUANTA.SCONN288_ADR50017P087CC(CHIPS)':
 'VSS47': CDS_PINID='VSS47';
NODE_NAME     J16 110
 '@S9S_MB_2U_LIB.S9S_MB_2U(SCH_1):PAGE97_I64@PURE_QUANTA.SCONN288_ADR50017P087CC(CHIPS)':
 'VSS48': CDS_PINID='VSS48';
NODE_NAME     J16 112
 '@S9S_MB_2U_LIB.S9S_MB_2U(SCH_1):PAGE97_I64@PURE_QUANTA.SCONN288_ADR50017P087CC(CHIPS)':
 'VSS49': CDS_PINID='VSS49';
NODE_NAME     J16 114
 '@S9S_MB_2U_LIB.S9S_MB_2U(SCH_1):PAGE97_I64@PURE_QUANTA.SCONN288_ADR50017P087CC(CHIPS)':
 'VSS50': CDS_PINID='VSS50';
NODE_NAME     J16 117
 '@S9S_MB_2U_LIB.S9S_MB_2U(SCH_1):PAGE97_I64@PURE_QUANTA.SCONN288_ADR50017P087CC(CHIPS)':
 'VSS51': CDS_PINID='VSS51';
NODE_NAME     J16 119
 '@S9S_MB_2U_LIB.S9S_MB_2U(SCH_1):PAGE97_I64@PURE_QUANTA.SCONN288_ADR50017P087CC(CHIPS)':
 'VSS52': CDS_PINID='VSS52';
NODE_NAME     J16 121
 '@S9S_MB_2U_LIB.S9S_MB_2U(SCH_1):PAGE97_I64@PURE_QUANTA.SCONN288_ADR50017P087CC(CHIPS)':
 'VSS53': CDS_PINID='VSS53';
NODE_NAME     J16 123
 '@S9S_MB_2U_LIB.S9S_MB_2U(SCH_1):PAGE97_I64@PURE_QUANTA.SCONN288_ADR50017P087CC(CHIPS)':
 'VSS54': CDS_PINID='VSS54';
NODE_NAME     J16 125
 '@S9S_MB_2U_LIB.S9S_MB_2U(SCH_1):PAGE97_I64@PURE_QUANTA.SCONN288_ADR50017P087CC(CHIPS)':
 'VSS55': CDS_PINID='VSS55';
NODE_NAME     J16 128
 '@S9S_MB_2U_LIB.S9S_MB_2U(SCH_1):PAGE97_I64@PURE_QUANTA.SCONN288_ADR50017P087CC(CHIPS)':
 'VSS56': CDS_PINID='VSS56';
NODE_NAME     J16 130
 '@S9S_MB_2U_LIB.S9S_MB_2U(SCH_1):PAGE97_I64@PURE_QUANTA.SCONN288_ADR50017P087CC(CHIPS)':
 'VSS57': CDS_PINID='VSS57';
NODE_NAME     J16 132
 '@S9S_MB_2U_LIB.S9S_MB_2U(SCH_1):PAGE97_I64@PURE_QUANTA.SCONN288_ADR50017P087CC(CHIPS)':
 'VSS58': CDS_PINID='VSS58';
NODE_NAME     J16 134
 '@S9S_MB_2U_LIB.S9S_MB_2U(SCH_1):PAGE97_I64@PURE_QUANTA.SCONN288_ADR50017P087CC(CHIPS)':
 'VSS59': CDS_PINID='VSS59';
NODE_NAME     J16 136
 '@S9S_MB_2U_LIB.S9S_MB_2U(SCH_1):PAGE97_I64@PURE_QUANTA.SCONN288_ADR50017P087CC(CHIPS)':
 'VSS60': CDS_PINID='VSS60';
NODE_NAME     J16 139
 '@S9S_MB_2U_LIB.S9S_MB_2U(SCH_1):PAGE97_I64@PURE_QUANTA.SCONN288_ADR50017P087CC(CHIPS)':
 'VSS61': CDS_PINID='VSS61';
NODE_NAME     J16 141
 '@S9S_MB_2U_LIB.S9S_MB_2U(SCH_1):PAGE97_I64@PURE_QUANTA.SCONN288_ADR50017P087CC(CHIPS)':
 'VSS62': CDS_PINID='VSS62';
NODE_NAME     J16 143
 '@S9S_MB_2U_LIB.S9S_MB_2U(SCH_1):PAGE97_I64@PURE_QUANTA.SCONN288_ADR50017P087CC(CHIPS)':
 'VSS63': CDS_PINID='VSS63';
NODE_NAME     J16 151
 '@S9S_MB_2U_LIB.S9S_MB_2U(SCH_1):PAGE97_I64@PURE_QUANTA.SCONN288_ADR50017P087CC(CHIPS)':
 'VSS64': CDS_PINID='VSS64';
NODE_NAME     J16 153
 '@S9S_MB_2U_LIB.S9S_MB_2U(SCH_1):PAGE97_I64@PURE_QUANTA.SCONN288_ADR50017P087CC(CHIPS)':
 'VSS65': CDS_PINID='VSS65';
NODE_NAME     J16 155
 '@S9S_MB_2U_LIB.S9S_MB_2U(SCH_1):PAGE97_I64@PURE_QUANTA.SCONN288_ADR50017P087CC(CHIPS)':
 'VSS66': CDS_PINID='VSS66';
NODE_NAME     J16 158
 '@S9S_MB_2U_LIB.S9S_MB_2U(SCH_1):PAGE97_I64@PURE_QUANTA.SCONN288_ADR50017P087CC(CHIPS)':
 'VSS67': CDS_PINID='VSS67';
NODE_NAME     J16 160
 '@S9S_MB_2U_LIB.S9S_MB_2U(SCH_1):PAGE97_I64@PURE_QUANTA.SCONN288_ADR50017P087CC(CHIPS)':
 'VSS68': CDS_PINID='VSS68';
NODE_NAME     J16 162
 '@S9S_MB_2U_LIB.S9S_MB_2U(SCH_1):PAGE97_I64@PURE_QUANTA.SCONN288_ADR50017P087CC(CHIPS)':
 'VSS69': CDS_PINID='VSS69';
NODE_NAME     J16 164
 '@S9S_MB_2U_LIB.S9S_MB_2U(SCH_1):PAGE97_I64@PURE_QUANTA.SCONN288_ADR50017P087CC(CHIPS)':
 'VSS70': CDS_PINID='VSS70';
NODE_NAME     J16 166
 '@S9S_MB_2U_LIB.S9S_MB_2U(SCH_1):PAGE97_I64@PURE_QUANTA.SCONN288_ADR50017P087CC(CHIPS)':
 'VSS71': CDS_PINID='VSS71';
NODE_NAME     J16 169
 '@S9S_MB_2U_LIB.S9S_MB_2U(SCH_1):PAGE97_I64@PURE_QUANTA.SCONN288_ADR50017P087CC(CHIPS)':
 'VSS72': CDS_PINID='VSS72';
NODE_NAME     J16 171
 '@S9S_MB_2U_LIB.S9S_MB_2U(SCH_1):PAGE97_I64@PURE_QUANTA.SCONN288_ADR50017P087CC(CHIPS)':
 'VSS73': CDS_PINID='VSS73';
NODE_NAME     J16 173
 '@S9S_MB_2U_LIB.S9S_MB_2U(SCH_1):PAGE97_I64@PURE_QUANTA.SCONN288_ADR50017P087CC(CHIPS)':
 'VSS74': CDS_PINID='VSS74';
NODE_NAME     J16 175
 '@S9S_MB_2U_LIB.S9S_MB_2U(SCH_1):PAGE97_I64@PURE_QUANTA.SCONN288_ADR50017P087CC(CHIPS)':
 'VSS75': CDS_PINID='VSS75';
NODE_NAME     J16 177
 '@S9S_MB_2U_LIB.S9S_MB_2U(SCH_1):PAGE97_I64@PURE_QUANTA.SCONN288_ADR50017P087CC(CHIPS)':
 'VSS76': CDS_PINID='VSS76';
NODE_NAME     J16 180
 '@S9S_MB_2U_LIB.S9S_MB_2U(SCH_1):PAGE97_I64@PURE_QUANTA.SCONN288_ADR50017P087CC(CHIPS)':
 'VSS77': CDS_PINID='VSS77';
NODE_NAME     J16 182
 '@S9S_MB_2U_LIB.S9S_MB_2U(SCH_1):PAGE97_I64@PURE_QUANTA.SCONN288_ADR50017P087CC(CHIPS)':
 'VSS78': CDS_PINID='VSS78';
NODE_NAME     J16 184
 '@S9S_MB_2U_LIB.S9S_MB_2U(SCH_1):PAGE97_I64@PURE_QUANTA.SCONN288_ADR50017P087CC(CHIPS)':
 'VSS79': CDS_PINID='VSS79';
NODE_NAME     J16 186
 '@S9S_MB_2U_LIB.S9S_MB_2U(SCH_1):PAGE97_I64@PURE_QUANTA.SCONN288_ADR50017P087CC(CHIPS)':
 'VSS80': CDS_PINID='VSS80';
NODE_NAME     J16 188
 '@S9S_MB_2U_LIB.S9S_MB_2U(SCH_1):PAGE97_I64@PURE_QUANTA.SCONN288_ADR50017P087CC(CHIPS)':
 'VSS81': CDS_PINID='VSS81';
NODE_NAME     J16 191
 '@S9S_MB_2U_LIB.S9S_MB_2U(SCH_1):PAGE97_I64@PURE_QUANTA.SCONN288_ADR50017P087CC(CHIPS)':
 'VSS82': CDS_PINID='VSS82';
NODE_NAME     J16 193
 '@S9S_MB_2U_LIB.S9S_MB_2U(SCH_1):PAGE97_I64@PURE_QUANTA.SCONN288_ADR50017P087CC(CHIPS)':
 'VSS83': CDS_PINID='VSS83';
NODE_NAME     J16 195
 '@S9S_MB_2U_LIB.S9S_MB_2U(SCH_1):PAGE97_I64@PURE_QUANTA.SCONN288_ADR50017P087CC(CHIPS)':
 'VSS84': CDS_PINID='VSS84';
NODE_NAME     J16 197
 '@S9S_MB_2U_LIB.S9S_MB_2U(SCH_1):PAGE97_I64@PURE_QUANTA.SCONN288_ADR50017P087CC(CHIPS)':
 'VSS85': CDS_PINID='VSS85';
NODE_NAME     J16 199
 '@S9S_MB_2U_LIB.S9S_MB_2U(SCH_1):PAGE97_I64@PURE_QUANTA.SCONN288_ADR50017P087CC(CHIPS)':
 'VSS86': CDS_PINID='VSS86';
NODE_NAME     J16 202
 '@S9S_MB_2U_LIB.S9S_MB_2U(SCH_1):PAGE97_I64@PURE_QUANTA.SCONN288_ADR50017P087CC(CHIPS)':
 'VSS87': CDS_PINID='VSS87';
NODE_NAME     J16 204
 '@S9S_MB_2U_LIB.S9S_MB_2U(SCH_1):PAGE97_I64@PURE_QUANTA.SCONN288_ADR50017P087CC(CHIPS)':
 'VSS88': CDS_PINID='VSS88';
NODE_NAME     J16 206
 '@S9S_MB_2U_LIB.S9S_MB_2U(SCH_1):PAGE97_I64@PURE_QUANTA.SCONN288_ADR50017P087CC(CHIPS)':
 'VSS89': CDS_PINID='VSS89';
NODE_NAME     J16 208
 '@S9S_MB_2U_LIB.S9S_MB_2U(SCH_1):PAGE97_I64@PURE_QUANTA.SCONN288_ADR50017P087CC(CHIPS)':
 'VSS90': CDS_PINID='VSS90';
NODE_NAME     J16 210
 '@S9S_MB_2U_LIB.S9S_MB_2U(SCH_1):PAGE97_I64@PURE_QUANTA.SCONN288_ADR50017P087CC(CHIPS)':
 'VSS91': CDS_PINID='VSS91';
NODE_NAME     J16 212
 '@S9S_MB_2U_LIB.S9S_MB_2U(SCH_1):PAGE97_I64@PURE_QUANTA.SCONN288_ADR50017P087CC(CHIPS)':
 'VSS92': CDS_PINID='VSS92';
NODE_NAME     J16 214
 '@S9S_MB_2U_LIB.S9S_MB_2U(SCH_1):PAGE97_I64@PURE_QUANTA.SCONN288_ADR50017P087CC(CHIPS)':
 'VSS93': CDS_PINID='VSS93';
NODE_NAME     J16 216
 '@S9S_MB_2U_LIB.S9S_MB_2U(SCH_1):PAGE97_I64@PURE_QUANTA.SCONN288_ADR50017P087CC(CHIPS)':
 'VSS94': CDS_PINID='VSS94';
NODE_NAME     J16 219
 '@S9S_MB_2U_LIB.S9S_MB_2U(SCH_1):PAGE97_I64@PURE_QUANTA.SCONN288_ADR50017P087CC(CHIPS)':
 'VSS95': CDS_PINID='VSS95';
NODE_NAME     J16 222
 '@S9S_MB_2U_LIB.S9S_MB_2U(SCH_1):PAGE97_I64@PURE_QUANTA.SCONN288_ADR50017P087CC(CHIPS)':
 'VSS96': CDS_PINID='VSS96';
NODE_NAME     J16 224
 '@S9S_MB_2U_LIB.S9S_MB_2U(SCH_1):PAGE97_I64@PURE_QUANTA.SCONN288_ADR50017P087CC(CHIPS)':
 'VSS97': CDS_PINID='VSS97';
NODE_NAME     J16 226
 '@S9S_MB_2U_LIB.S9S_MB_2U(SCH_1):PAGE97_I64@PURE_QUANTA.SCONN288_ADR50017P087CC(CHIPS)':
 'VSS98': CDS_PINID='VSS98';
NODE_NAME     J16 228
 '@S9S_MB_2U_LIB.S9S_MB_2U(SCH_1):PAGE97_I64@PURE_QUANTA.SCONN288_ADR50017P087CC(CHIPS)':
 'VSS99': CDS_PINID='VSS99';
NODE_NAME     J16 230
 '@S9S_MB_2U_LIB.S9S_MB_2U(SCH_1):PAGE97_I64@PURE_QUANTA.SCONN288_ADR50017P087CC(CHIPS)':
 'VSS100': CDS_PINID='VSS100';
NODE_NAME     J16 233
 '@S9S_MB_2U_LIB.S9S_MB_2U(SCH_1):PAGE97_I64@PURE_QUANTA.SCONN288_ADR50017P087CC(CHIPS)':
 'VSS101': CDS_PINID='VSS101';
NODE_NAME     J16 235
 '@S9S_MB_2U_LIB.S9S_MB_2U(SCH_1):PAGE97_I64@PURE_QUANTA.SCONN288_ADR50017P087CC(CHIPS)':
 'VSS102': CDS_PINID='VSS102';
NODE_NAME     J16 237
 '@S9S_MB_2U_LIB.S9S_MB_2U(SCH_1):PAGE97_I64@PURE_QUANTA.SCONN288_ADR50017P087CC(CHIPS)':
 'VSS103': CDS_PINID='VSS103';
NODE_NAME     J16 240
 '@S9S_MB_2U_LIB.S9S_MB_2U(SCH_1):PAGE97_I64@PURE_QUANTA.SCONN288_ADR50017P087CC(CHIPS)':
 'VSS104': CDS_PINID='VSS104';
NODE_NAME     J16 242
 '@S9S_MB_2U_LIB.S9S_MB_2U(SCH_1):PAGE97_I64@PURE_QUANTA.SCONN288_ADR50017P087CC(CHIPS)':
 'VSS105': CDS_PINID='VSS105';
NODE_NAME     J16 244
 '@S9S_MB_2U_LIB.S9S_MB_2U(SCH_1):PAGE97_I64@PURE_QUANTA.SCONN288_ADR50017P087CC(CHIPS)':
 'VSS106': CDS_PINID='VSS106';
NODE_NAME     J16 246
 '@S9S_MB_2U_LIB.S9S_MB_2U(SCH_1):PAGE97_I64@PURE_QUANTA.SCONN288_ADR50017P087CC(CHIPS)':
 'VSS107': CDS_PINID='VSS107';
NODE_NAME     J16 248
 '@S9S_MB_2U_LIB.S9S_MB_2U(SCH_1):PAGE97_I64@PURE_QUANTA.SCONN288_ADR50017P087CC(CHIPS)':
 'VSS108': CDS_PINID='VSS108';
NODE_NAME     J16 251
 '@S9S_MB_2U_LIB.S9S_MB_2U(SCH_1):PAGE97_I64@PURE_QUANTA.SCONN288_ADR50017P087CC(CHIPS)':
 'VSS109': CDS_PINID='VSS109';
NODE_NAME     J16 253
 '@S9S_MB_2U_LIB.S9S_MB_2U(SCH_1):PAGE97_I64@PURE_QUANTA.SCONN288_ADR50017P087CC(CHIPS)':
 'VSS110': CDS_PINID='VSS110';
NODE_NAME     J16 255
 '@S9S_MB_2U_LIB.S9S_MB_2U(SCH_1):PAGE97_I64@PURE_QUANTA.SCONN288_ADR50017P087CC(CHIPS)':
 'VSS111': CDS_PINID='VSS111';
NODE_NAME     J16 257
 '@S9S_MB_2U_LIB.S9S_MB_2U(SCH_1):PAGE97_I64@PURE_QUANTA.SCONN288_ADR50017P087CC(CHIPS)':
 'VSS112': CDS_PINID='VSS112';
NODE_NAME     J16 259
 '@S9S_MB_2U_LIB.S9S_MB_2U(SCH_1):PAGE97_I64@PURE_QUANTA.SCONN288_ADR50017P087CC(CHIPS)':
 'VSS113': CDS_PINID='VSS113';
NODE_NAME     J16 262
 '@S9S_MB_2U_LIB.S9S_MB_2U(SCH_1):PAGE97_I64@PURE_QUANTA.SCONN288_ADR50017P087CC(CHIPS)':
 'VSS114': CDS_PINID='VSS114';
NODE_NAME     J16 264
 '@S9S_MB_2U_LIB.S9S_MB_2U(SCH_1):PAGE97_I64@PURE_QUANTA.SCONN288_ADR50017P087CC(CHIPS)':
 'VSS115': CDS_PINID='VSS115';
NODE_NAME     J16 266
 '@S9S_MB_2U_LIB.S9S_MB_2U(SCH_1):PAGE97_I64@PURE_QUANTA.SCONN288_ADR50017P087CC(CHIPS)':
 'VSS116': CDS_PINID='VSS116';
NODE_NAME     J16 268
 '@S9S_MB_2U_LIB.S9S_MB_2U(SCH_1):PAGE97_I64@PURE_QUANTA.SCONN288_ADR50017P087CC(CHIPS)':
 'VSS117': CDS_PINID='VSS117';
NODE_NAME     J16 270
 '@S9S_MB_2U_LIB.S9S_MB_2U(SCH_1):PAGE97_I64@PURE_QUANTA.SCONN288_ADR50017P087CC(CHIPS)':
 'VSS118': CDS_PINID='VSS118';
NODE_NAME     J16 273
 '@S9S_MB_2U_LIB.S9S_MB_2U(SCH_1):PAGE97_I64@PURE_QUANTA.SCONN288_ADR50017P087CC(CHIPS)':
 'VSS119': CDS_PINID='VSS119';
NODE_NAME     J16 275
 '@S9S_MB_2U_LIB.S9S_MB_2U(SCH_1):PAGE97_I64@PURE_QUANTA.SCONN288_ADR50017P087CC(CHIPS)':
 'VSS120': CDS_PINID='VSS120';
NODE_NAME     J16 277
 '@S9S_MB_2U_LIB.S9S_MB_2U(SCH_1):PAGE97_I64@PURE_QUANTA.SCONN288_ADR50017P087CC(CHIPS)':
 'VSS121': CDS_PINID='VSS121';
NODE_NAME     J16 279
 '@S9S_MB_2U_LIB.S9S_MB_2U(SCH_1):PAGE97_I64@PURE_QUANTA.SCONN288_ADR50017P087CC(CHIPS)':
 'VSS122': CDS_PINID='VSS122';
NODE_NAME     J16 281
 '@S9S_MB_2U_LIB.S9S_MB_2U(SCH_1):PAGE97_I64@PURE_QUANTA.SCONN288_ADR50017P087CC(CHIPS)':
 'VSS123': CDS_PINID='VSS123';
NODE_NAME     J16 284
 '@S9S_MB_2U_LIB.S9S_MB_2U(SCH_1):PAGE97_I64@PURE_QUANTA.SCONN288_ADR50017P087CC(CHIPS)':
 'VSS124': CDS_PINID='VSS124';
NODE_NAME     J16 286
 '@S9S_MB_2U_LIB.S9S_MB_2U(SCH_1):PAGE97_I64@PURE_QUANTA.SCONN288_ADR50017P087CC(CHIPS)':
 'VSS125': CDS_PINID='VSS125';
NODE_NAME     J16 288
 '@S9S_MB_2U_LIB.S9S_MB_2U(SCH_1):PAGE97_I64@PURE_QUANTA.SCONN288_ADR50017P087CC(CHIPS)':
 'VSS126': CDS_PINID='VSS126';
NODE_NAME     R42 2
 '@S9S_MB_2U_LIB.S9S_MB_2U(SCH_1):PAGE98_I11@PURE_QUANTA.Q_RES(CHIPS)':
 'B': CDS_PINID='B';
NODE_NAME     C50 2
 '@S9S_MB_2U_LIB.S9S_MB_2U(SCH_1):PAGE98_I122@PURE_QUANTA.Q_CAP(CHIPS)':
 'B': CDS_PINID='B';
NODE_NAME     C51 2
 '@S9S_MB_2U_LIB.S9S_MB_2U(SCH_1):PAGE98_I123@PURE_QUANTA.Q_CAP(CHIPS)':
 'B': CDS_PINID='B';
NODE_NAME     C52 2
 '@S9S_MB_2U_LIB.S9S_MB_2U(SCH_1):PAGE98_I145@PURE_QUANTA.Q_CAP(CHIPS)':
 'B': CDS_PINID='B';
NODE_NAME     J17 G1
 '@S9S_MB_2U_LIB.S9S_MB_2U(SCH_1):PAGE98_I147@PURE_QUANTA.SCONN288_ADR50017P130CC(CHIPS)':
 'G1': CDS_PINID='G1';
NODE_NAME     J17 G2
 '@S9S_MB_2U_LIB.S9S_MB_2U(SCH_1):PAGE98_I147@PURE_QUANTA.SCONN288_ADR50017P130CC(CHIPS)':
 'G2': CDS_PINID='G2';
NODE_NAME     J17 G3
 '@S9S_MB_2U_LIB.S9S_MB_2U(SCH_1):PAGE98_I147@PURE_QUANTA.SCONN288_ADR50017P130CC(CHIPS)':
 'G3': CDS_PINID='G3';
NODE_NAME     J17 6
 '@S9S_MB_2U_LIB.S9S_MB_2U(SCH_1):PAGE98_I147@PURE_QUANTA.SCONN288_ADR50017P130CC(CHIPS)':
 'VSS0': CDS_PINID='VSS0';
NODE_NAME     J17 8
 '@S9S_MB_2U_LIB.S9S_MB_2U(SCH_1):PAGE98_I147@PURE_QUANTA.SCONN288_ADR50017P130CC(CHIPS)':
 'VSS1': CDS_PINID='VSS1';
NODE_NAME     J17 10
 '@S9S_MB_2U_LIB.S9S_MB_2U(SCH_1):PAGE98_I147@PURE_QUANTA.SCONN288_ADR50017P130CC(CHIPS)':
 'VSS2': CDS_PINID='VSS2';
NODE_NAME     J17 13
 '@S9S_MB_2U_LIB.S9S_MB_2U(SCH_1):PAGE98_I147@PURE_QUANTA.SCONN288_ADR50017P130CC(CHIPS)':
 'VSS3': CDS_PINID='VSS3';
NODE_NAME     J17 15
 '@S9S_MB_2U_LIB.S9S_MB_2U(SCH_1):PAGE98_I147@PURE_QUANTA.SCONN288_ADR50017P130CC(CHIPS)':
 'VSS4': CDS_PINID='VSS4';
NODE_NAME     J17 17
 '@S9S_MB_2U_LIB.S9S_MB_2U(SCH_1):PAGE98_I147@PURE_QUANTA.SCONN288_ADR50017P130CC(CHIPS)':
 'VSS5': CDS_PINID='VSS5';
NODE_NAME     J17 19
 '@S9S_MB_2U_LIB.S9S_MB_2U(SCH_1):PAGE98_I147@PURE_QUANTA.SCONN288_ADR50017P130CC(CHIPS)':
 'VSS6': CDS_PINID='VSS6';
NODE_NAME     J17 21
 '@S9S_MB_2U_LIB.S9S_MB_2U(SCH_1):PAGE98_I147@PURE_QUANTA.SCONN288_ADR50017P130CC(CHIPS)':
 'VSS7': CDS_PINID='VSS7';
NODE_NAME     J17 24
 '@S9S_MB_2U_LIB.S9S_MB_2U(SCH_1):PAGE98_I147@PURE_QUANTA.SCONN288_ADR50017P130CC(CHIPS)':
 'VSS8': CDS_PINID='VSS8';
NODE_NAME     J17 26
 '@S9S_MB_2U_LIB.S9S_MB_2U(SCH_1):PAGE98_I147@PURE_QUANTA.SCONN288_ADR50017P130CC(CHIPS)':
 'VSS9': CDS_PINID='VSS9';
NODE_NAME     J17 28
 '@S9S_MB_2U_LIB.S9S_MB_2U(SCH_1):PAGE98_I147@PURE_QUANTA.SCONN288_ADR50017P130CC(CHIPS)':
 'VSS10': CDS_PINID='VSS10';
NODE_NAME     J17 30
 '@S9S_MB_2U_LIB.S9S_MB_2U(SCH_1):PAGE98_I147@PURE_QUANTA.SCONN288_ADR50017P130CC(CHIPS)':
 'VSS11': CDS_PINID='VSS11';
NODE_NAME     J17 32
 '@S9S_MB_2U_LIB.S9S_MB_2U(SCH_1):PAGE98_I147@PURE_QUANTA.SCONN288_ADR50017P130CC(CHIPS)':
 'VSS12': CDS_PINID='VSS12';
NODE_NAME     J17 35
 '@S9S_MB_2U_LIB.S9S_MB_2U(SCH_1):PAGE98_I147@PURE_QUANTA.SCONN288_ADR50017P130CC(CHIPS)':
 'VSS13': CDS_PINID='VSS13';
NODE_NAME     J17 37
 '@S9S_MB_2U_LIB.S9S_MB_2U(SCH_1):PAGE98_I147@PURE_QUANTA.SCONN288_ADR50017P130CC(CHIPS)':
 'VSS14': CDS_PINID='VSS14';
NODE_NAME     J17 39
 '@S9S_MB_2U_LIB.S9S_MB_2U(SCH_1):PAGE98_I147@PURE_QUANTA.SCONN288_ADR50017P130CC(CHIPS)':
 'VSS15': CDS_PINID='VSS15';
NODE_NAME     J17 41
 '@S9S_MB_2U_LIB.S9S_MB_2U(SCH_1):PAGE98_I147@PURE_QUANTA.SCONN288_ADR50017P130CC(CHIPS)':
 'VSS16': CDS_PINID='VSS16';
NODE_NAME     J17 43
 '@S9S_MB_2U_LIB.S9S_MB_2U(SCH_1):PAGE98_I147@PURE_QUANTA.SCONN288_ADR50017P130CC(CHIPS)':
 'VSS17': CDS_PINID='VSS17';
NODE_NAME     J17 46
 '@S9S_MB_2U_LIB.S9S_MB_2U(SCH_1):PAGE98_I147@PURE_QUANTA.SCONN288_ADR50017P130CC(CHIPS)':
 'VSS18': CDS_PINID='VSS18';
NODE_NAME     J17 48
 '@S9S_MB_2U_LIB.S9S_MB_2U(SCH_1):PAGE98_I147@PURE_QUANTA.SCONN288_ADR50017P130CC(CHIPS)':
 'VSS19': CDS_PINID='VSS19';
NODE_NAME     J17 50
 '@S9S_MB_2U_LIB.S9S_MB_2U(SCH_1):PAGE98_I147@PURE_QUANTA.SCONN288_ADR50017P130CC(CHIPS)':
 'VSS20': CDS_PINID='VSS20';
NODE_NAME     J17 52
 '@S9S_MB_2U_LIB.S9S_MB_2U(SCH_1):PAGE98_I147@PURE_QUANTA.SCONN288_ADR50017P130CC(CHIPS)':
 'VSS21': CDS_PINID='VSS21';
NODE_NAME     J17 54
 '@S9S_MB_2U_LIB.S9S_MB_2U(SCH_1):PAGE98_I147@PURE_QUANTA.SCONN288_ADR50017P130CC(CHIPS)':
 'VSS22': CDS_PINID='VSS22';
NODE_NAME     J17 57
 '@S9S_MB_2U_LIB.S9S_MB_2U(SCH_1):PAGE98_I147@PURE_QUANTA.SCONN288_ADR50017P130CC(CHIPS)':
 'VSS23': CDS_PINID='VSS23';
NODE_NAME     J17 59
 '@S9S_MB_2U_LIB.S9S_MB_2U(SCH_1):PAGE98_I147@PURE_QUANTA.SCONN288_ADR50017P130CC(CHIPS)':
 'VSS24': CDS_PINID='VSS24';
NODE_NAME     J17 61
 '@S9S_MB_2U_LIB.S9S_MB_2U(SCH_1):PAGE98_I147@PURE_QUANTA.SCONN288_ADR50017P130CC(CHIPS)':
 'VSS25': CDS_PINID='VSS25';
NODE_NAME     J17 63
 '@S9S_MB_2U_LIB.S9S_MB_2U(SCH_1):PAGE98_I147@PURE_QUANTA.SCONN288_ADR50017P130CC(CHIPS)':
 'VSS26': CDS_PINID='VSS26';
NODE_NAME     J17 65
 '@S9S_MB_2U_LIB.S9S_MB_2U(SCH_1):PAGE98_I147@PURE_QUANTA.SCONN288_ADR50017P130CC(CHIPS)':
 'VSS27': CDS_PINID='VSS27';
NODE_NAME     J17 67
 '@S9S_MB_2U_LIB.S9S_MB_2U(SCH_1):PAGE98_I147@PURE_QUANTA.SCONN288_ADR50017P130CC(CHIPS)':
 'VSS28': CDS_PINID='VSS28';
NODE_NAME     J17 69
 '@S9S_MB_2U_LIB.S9S_MB_2U(SCH_1):PAGE98_I147@PURE_QUANTA.SCONN288_ADR50017P130CC(CHIPS)':
 'VSS29': CDS_PINID='VSS29';
NODE_NAME     J17 71
 '@S9S_MB_2U_LIB.S9S_MB_2U(SCH_1):PAGE98_I147@PURE_QUANTA.SCONN288_ADR50017P130CC(CHIPS)':
 'VSS30': CDS_PINID='VSS30';
NODE_NAME     J17 73
 '@S9S_MB_2U_LIB.S9S_MB_2U(SCH_1):PAGE98_I147@PURE_QUANTA.SCONN288_ADR50017P130CC(CHIPS)':
 'VSS31': CDS_PINID='VSS31';
NODE_NAME     J17 75
 '@S9S_MB_2U_LIB.S9S_MB_2U(SCH_1):PAGE98_I147@PURE_QUANTA.SCONN288_ADR50017P130CC(CHIPS)':
 'VSS32': CDS_PINID='VSS32';
NODE_NAME     J17 77
 '@S9S_MB_2U_LIB.S9S_MB_2U(SCH_1):PAGE98_I147@PURE_QUANTA.SCONN288_ADR50017P130CC(CHIPS)':
 'VSS33': CDS_PINID='VSS33';
NODE_NAME     J17 79
 '@S9S_MB_2U_LIB.S9S_MB_2U(SCH_1):PAGE98_I147@PURE_QUANTA.SCONN288_ADR50017P130CC(CHIPS)':
 'VSS34': CDS_PINID='VSS34';
NODE_NAME     J17 81
 '@S9S_MB_2U_LIB.S9S_MB_2U(SCH_1):PAGE98_I147@PURE_QUANTA.SCONN288_ADR50017P130CC(CHIPS)':
 'VSS35': CDS_PINID='VSS35';
NODE_NAME     J17 83
 '@S9S_MB_2U_LIB.S9S_MB_2U(SCH_1):PAGE98_I147@PURE_QUANTA.SCONN288_ADR50017P130CC(CHIPS)':
 'VSS36': CDS_PINID='VSS36';
NODE_NAME     J17 85
 '@S9S_MB_2U_LIB.S9S_MB_2U(SCH_1):PAGE98_I147@PURE_QUANTA.SCONN288_ADR50017P130CC(CHIPS)':
 'VSS37': CDS_PINID='VSS37';
NODE_NAME     J17 88
 '@S9S_MB_2U_LIB.S9S_MB_2U(SCH_1):PAGE98_I147@PURE_QUANTA.SCONN288_ADR50017P130CC(CHIPS)':
 'VSS38': CDS_PINID='VSS38';
NODE_NAME     J17 90
 '@S9S_MB_2U_LIB.S9S_MB_2U(SCH_1):PAGE98_I147@PURE_QUANTA.SCONN288_ADR50017P130CC(CHIPS)':
 'VSS39': CDS_PINID='VSS39';
NODE_NAME     J17 92
 '@S9S_MB_2U_LIB.S9S_MB_2U(SCH_1):PAGE98_I147@PURE_QUANTA.SCONN288_ADR50017P130CC(CHIPS)':
 'VSS40': CDS_PINID='VSS40';
NODE_NAME     J17 95
 '@S9S_MB_2U_LIB.S9S_MB_2U(SCH_1):PAGE98_I147@PURE_QUANTA.SCONN288_ADR50017P130CC(CHIPS)':
 'VSS41': CDS_PINID='VSS41';
NODE_NAME     J17 97
 '@S9S_MB_2U_LIB.S9S_MB_2U(SCH_1):PAGE98_I147@PURE_QUANTA.SCONN288_ADR50017P130CC(CHIPS)':
 'VSS42': CDS_PINID='VSS42';
NODE_NAME     J17 99
 '@S9S_MB_2U_LIB.S9S_MB_2U(SCH_1):PAGE98_I147@PURE_QUANTA.SCONN288_ADR50017P130CC(CHIPS)':
 'VSS43': CDS_PINID='VSS43';
NODE_NAME     J17 101
 '@S9S_MB_2U_LIB.S9S_MB_2U(SCH_1):PAGE98_I147@PURE_QUANTA.SCONN288_ADR50017P130CC(CHIPS)':
 'VSS44': CDS_PINID='VSS44';
NODE_NAME     J17 103
 '@S9S_MB_2U_LIB.S9S_MB_2U(SCH_1):PAGE98_I147@PURE_QUANTA.SCONN288_ADR50017P130CC(CHIPS)':
 'VSS45': CDS_PINID='VSS45';
NODE_NAME     J17 106
 '@S9S_MB_2U_LIB.S9S_MB_2U(SCH_1):PAGE98_I147@PURE_QUANTA.SCONN288_ADR50017P130CC(CHIPS)':
 'VSS46': CDS_PINID='VSS46';
NODE_NAME     J17 108
 '@S9S_MB_2U_LIB.S9S_MB_2U(SCH_1):PAGE98_I147@PURE_QUANTA.SCONN288_ADR50017P130CC(CHIPS)':
 'VSS47': CDS_PINID='VSS47';
NODE_NAME     J17 110
 '@S9S_MB_2U_LIB.S9S_MB_2U(SCH_1):PAGE98_I147@PURE_QUANTA.SCONN288_ADR50017P130CC(CHIPS)':
 'VSS48': CDS_PINID='VSS48';
NODE_NAME     J17 112
 '@S9S_MB_2U_LIB.S9S_MB_2U(SCH_1):PAGE98_I147@PURE_QUANTA.SCONN288_ADR50017P130CC(CHIPS)':
 'VSS49': CDS_PINID='VSS49';
NODE_NAME     J17 114
 '@S9S_MB_2U_LIB.S9S_MB_2U(SCH_1):PAGE98_I147@PURE_QUANTA.SCONN288_ADR50017P130CC(CHIPS)':
 'VSS50': CDS_PINID='VSS50';
NODE_NAME     J17 117
 '@S9S_MB_2U_LIB.S9S_MB_2U(SCH_1):PAGE98_I147@PURE_QUANTA.SCONN288_ADR50017P130CC(CHIPS)':
 'VSS51': CDS_PINID='VSS51';
NODE_NAME     J17 119
 '@S9S_MB_2U_LIB.S9S_MB_2U(SCH_1):PAGE98_I147@PURE_QUANTA.SCONN288_ADR50017P130CC(CHIPS)':
 'VSS52': CDS_PINID='VSS52';
NODE_NAME     J17 121
 '@S9S_MB_2U_LIB.S9S_MB_2U(SCH_1):PAGE98_I147@PURE_QUANTA.SCONN288_ADR50017P130CC(CHIPS)':
 'VSS53': CDS_PINID='VSS53';
NODE_NAME     J17 123
 '@S9S_MB_2U_LIB.S9S_MB_2U(SCH_1):PAGE98_I147@PURE_QUANTA.SCONN288_ADR50017P130CC(CHIPS)':
 'VSS54': CDS_PINID='VSS54';
NODE_NAME     J17 125
 '@S9S_MB_2U_LIB.S9S_MB_2U(SCH_1):PAGE98_I147@PURE_QUANTA.SCONN288_ADR50017P130CC(CHIPS)':
 'VSS55': CDS_PINID='VSS55';
NODE_NAME     J17 128
 '@S9S_MB_2U_LIB.S9S_MB_2U(SCH_1):PAGE98_I147@PURE_QUANTA.SCONN288_ADR50017P130CC(CHIPS)':
 'VSS56': CDS_PINID='VSS56';
NODE_NAME     J17 130
 '@S9S_MB_2U_LIB.S9S_MB_2U(SCH_1):PAGE98_I147@PURE_QUANTA.SCONN288_ADR50017P130CC(CHIPS)':
 'VSS57': CDS_PINID='VSS57';
NODE_NAME     J17 132
 '@S9S_MB_2U_LIB.S9S_MB_2U(SCH_1):PAGE98_I147@PURE_QUANTA.SCONN288_ADR50017P130CC(CHIPS)':
 'VSS58': CDS_PINID='VSS58';
NODE_NAME     J17 134
 '@S9S_MB_2U_LIB.S9S_MB_2U(SCH_1):PAGE98_I147@PURE_QUANTA.SCONN288_ADR50017P130CC(CHIPS)':
 'VSS59': CDS_PINID='VSS59';
NODE_NAME     J17 136
 '@S9S_MB_2U_LIB.S9S_MB_2U(SCH_1):PAGE98_I147@PURE_QUANTA.SCONN288_ADR50017P130CC(CHIPS)':
 'VSS60': CDS_PINID='VSS60';
NODE_NAME     J17 139
 '@S9S_MB_2U_LIB.S9S_MB_2U(SCH_1):PAGE98_I147@PURE_QUANTA.SCONN288_ADR50017P130CC(CHIPS)':
 'VSS61': CDS_PINID='VSS61';
NODE_NAME     J17 141
 '@S9S_MB_2U_LIB.S9S_MB_2U(SCH_1):PAGE98_I147@PURE_QUANTA.SCONN288_ADR50017P130CC(CHIPS)':
 'VSS62': CDS_PINID='VSS62';
NODE_NAME     J17 143
 '@S9S_MB_2U_LIB.S9S_MB_2U(SCH_1):PAGE98_I147@PURE_QUANTA.SCONN288_ADR50017P130CC(CHIPS)':
 'VSS63': CDS_PINID='VSS63';
NODE_NAME     J17 151
 '@S9S_MB_2U_LIB.S9S_MB_2U(SCH_1):PAGE98_I147@PURE_QUANTA.SCONN288_ADR50017P130CC(CHIPS)':
 'VSS64': CDS_PINID='VSS64';
NODE_NAME     J17 153
 '@S9S_MB_2U_LIB.S9S_MB_2U(SCH_1):PAGE98_I147@PURE_QUANTA.SCONN288_ADR50017P130CC(CHIPS)':
 'VSS65': CDS_PINID='VSS65';
NODE_NAME     J17 155
 '@S9S_MB_2U_LIB.S9S_MB_2U(SCH_1):PAGE98_I147@PURE_QUANTA.SCONN288_ADR50017P130CC(CHIPS)':
 'VSS66': CDS_PINID='VSS66';
NODE_NAME     J17 158
 '@S9S_MB_2U_LIB.S9S_MB_2U(SCH_1):PAGE98_I147@PURE_QUANTA.SCONN288_ADR50017P130CC(CHIPS)':
 'VSS67': CDS_PINID='VSS67';
NODE_NAME     J17 160
 '@S9S_MB_2U_LIB.S9S_MB_2U(SCH_1):PAGE98_I147@PURE_QUANTA.SCONN288_ADR50017P130CC(CHIPS)':
 'VSS68': CDS_PINID='VSS68';
NODE_NAME     J17 162
 '@S9S_MB_2U_LIB.S9S_MB_2U(SCH_1):PAGE98_I147@PURE_QUANTA.SCONN288_ADR50017P130CC(CHIPS)':
 'VSS69': CDS_PINID='VSS69';
NODE_NAME     J17 164
 '@S9S_MB_2U_LIB.S9S_MB_2U(SCH_1):PAGE98_I147@PURE_QUANTA.SCONN288_ADR50017P130CC(CHIPS)':
 'VSS70': CDS_PINID='VSS70';
NODE_NAME     J17 166
 '@S9S_MB_2U_LIB.S9S_MB_2U(SCH_1):PAGE98_I147@PURE_QUANTA.SCONN288_ADR50017P130CC(CHIPS)':
 'VSS71': CDS_PINID='VSS71';
NODE_NAME     J17 169
 '@S9S_MB_2U_LIB.S9S_MB_2U(SCH_1):PAGE98_I147@PURE_QUANTA.SCONN288_ADR50017P130CC(CHIPS)':
 'VSS72': CDS_PINID='VSS72';
NODE_NAME     J17 171
 '@S9S_MB_2U_LIB.S9S_MB_2U(SCH_1):PAGE98_I147@PURE_QUANTA.SCONN288_ADR50017P130CC(CHIPS)':
 'VSS73': CDS_PINID='VSS73';
NODE_NAME     J17 173
 '@S9S_MB_2U_LIB.S9S_MB_2U(SCH_1):PAGE98_I147@PURE_QUANTA.SCONN288_ADR50017P130CC(CHIPS)':
 'VSS74': CDS_PINID='VSS74';
NODE_NAME     J17 175
 '@S9S_MB_2U_LIB.S9S_MB_2U(SCH_1):PAGE98_I147@PURE_QUANTA.SCONN288_ADR50017P130CC(CHIPS)':
 'VSS75': CDS_PINID='VSS75';
NODE_NAME     J17 177
 '@S9S_MB_2U_LIB.S9S_MB_2U(SCH_1):PAGE98_I147@PURE_QUANTA.SCONN288_ADR50017P130CC(CHIPS)':
 'VSS76': CDS_PINID='VSS76';
NODE_NAME     J17 180
 '@S9S_MB_2U_LIB.S9S_MB_2U(SCH_1):PAGE98_I147@PURE_QUANTA.SCONN288_ADR50017P130CC(CHIPS)':
 'VSS77': CDS_PINID='VSS77';
NODE_NAME     J17 182
 '@S9S_MB_2U_LIB.S9S_MB_2U(SCH_1):PAGE98_I147@PURE_QUANTA.SCONN288_ADR50017P130CC(CHIPS)':
 'VSS78': CDS_PINID='VSS78';
NODE_NAME     J17 184
 '@S9S_MB_2U_LIB.S9S_MB_2U(SCH_1):PAGE98_I147@PURE_QUANTA.SCONN288_ADR50017P130CC(CHIPS)':
 'VSS79': CDS_PINID='VSS79';
NODE_NAME     J17 186
 '@S9S_MB_2U_LIB.S9S_MB_2U(SCH_1):PAGE98_I147@PURE_QUANTA.SCONN288_ADR50017P130CC(CHIPS)':
 'VSS80': CDS_PINID='VSS80';
NODE_NAME     J17 188
 '@S9S_MB_2U_LIB.S9S_MB_2U(SCH_1):PAGE98_I147@PURE_QUANTA.SCONN288_ADR50017P130CC(CHIPS)':
 'VSS81': CDS_PINID='VSS81';
NODE_NAME     J17 191
 '@S9S_MB_2U_LIB.S9S_MB_2U(SCH_1):PAGE98_I147@PURE_QUANTA.SCONN288_ADR50017P130CC(CHIPS)':
 'VSS82': CDS_PINID='VSS82';
NODE_NAME     J17 193
 '@S9S_MB_2U_LIB.S9S_MB_2U(SCH_1):PAGE98_I147@PURE_QUANTA.SCONN288_ADR50017P130CC(CHIPS)':
 'VSS83': CDS_PINID='VSS83';
NODE_NAME     J17 195
 '@S9S_MB_2U_LIB.S9S_MB_2U(SCH_1):PAGE98_I147@PURE_QUANTA.SCONN288_ADR50017P130CC(CHIPS)':
 'VSS84': CDS_PINID='VSS84';
NODE_NAME     J17 197
 '@S9S_MB_2U_LIB.S9S_MB_2U(SCH_1):PAGE98_I147@PURE_QUANTA.SCONN288_ADR50017P130CC(CHIPS)':
 'VSS85': CDS_PINID='VSS85';
NODE_NAME     J17 199
 '@S9S_MB_2U_LIB.S9S_MB_2U(SCH_1):PAGE98_I147@PURE_QUANTA.SCONN288_ADR50017P130CC(CHIPS)':
 'VSS86': CDS_PINID='VSS86';
NODE_NAME     J17 202
 '@S9S_MB_2U_LIB.S9S_MB_2U(SCH_1):PAGE98_I147@PURE_QUANTA.SCONN288_ADR50017P130CC(CHIPS)':
 'VSS87': CDS_PINID='VSS87';
NODE_NAME     J17 204
 '@S9S_MB_2U_LIB.S9S_MB_2U(SCH_1):PAGE98_I147@PURE_QUANTA.SCONN288_ADR50017P130CC(CHIPS)':
 'VSS88': CDS_PINID='VSS88';
NODE_NAME     J17 206
 '@S9S_MB_2U_LIB.S9S_MB_2U(SCH_1):PAGE98_I147@PURE_QUANTA.SCONN288_ADR50017P130CC(CHIPS)':
 'VSS89': CDS_PINID='VSS89';
NODE_NAME     J17 208
 '@S9S_MB_2U_LIB.S9S_MB_2U(SCH_1):PAGE98_I147@PURE_QUANTA.SCONN288_ADR50017P130CC(CHIPS)':
 'VSS90': CDS_PINID='VSS90';
NODE_NAME     J17 210
 '@S9S_MB_2U_LIB.S9S_MB_2U(SCH_1):PAGE98_I147@PURE_QUANTA.SCONN288_ADR50017P130CC(CHIPS)':
 'VSS91': CDS_PINID='VSS91';
NODE_NAME     J17 212
 '@S9S_MB_2U_LIB.S9S_MB_2U(SCH_1):PAGE98_I147@PURE_QUANTA.SCONN288_ADR50017P130CC(CHIPS)':
 'VSS92': CDS_PINID='VSS92';
NODE_NAME     J17 214
 '@S9S_MB_2U_LIB.S9S_MB_2U(SCH_1):PAGE98_I147@PURE_QUANTA.SCONN288_ADR50017P130CC(CHIPS)':
 'VSS93': CDS_PINID='VSS93';
NODE_NAME     J17 216
 '@S9S_MB_2U_LIB.S9S_MB_2U(SCH_1):PAGE98_I147@PURE_QUANTA.SCONN288_ADR50017P130CC(CHIPS)':
 'VSS94': CDS_PINID='VSS94';
NODE_NAME     J17 219
 '@S9S_MB_2U_LIB.S9S_MB_2U(SCH_1):PAGE98_I147@PURE_QUANTA.SCONN288_ADR50017P130CC(CHIPS)':
 'VSS95': CDS_PINID='VSS95';
NODE_NAME     J17 222
 '@S9S_MB_2U_LIB.S9S_MB_2U(SCH_1):PAGE98_I147@PURE_QUANTA.SCONN288_ADR50017P130CC(CHIPS)':
 'VSS96': CDS_PINID='VSS96';
NODE_NAME     J17 224
 '@S9S_MB_2U_LIB.S9S_MB_2U(SCH_1):PAGE98_I147@PURE_QUANTA.SCONN288_ADR50017P130CC(CHIPS)':
 'VSS97': CDS_PINID='VSS97';
NODE_NAME     J17 226
 '@S9S_MB_2U_LIB.S9S_MB_2U(SCH_1):PAGE98_I147@PURE_QUANTA.SCONN288_ADR50017P130CC(CHIPS)':
 'VSS98': CDS_PINID='VSS98';
NODE_NAME     J17 228
 '@S9S_MB_2U_LIB.S9S_MB_2U(SCH_1):PAGE98_I147@PURE_QUANTA.SCONN288_ADR50017P130CC(CHIPS)':
 'VSS99': CDS_PINID='VSS99';
NODE_NAME     J17 230
 '@S9S_MB_2U_LIB.S9S_MB_2U(SCH_1):PAGE98_I147@PURE_QUANTA.SCONN288_ADR50017P130CC(CHIPS)':
 'VSS100': CDS_PINID='VSS100';
NODE_NAME     J17 233
 '@S9S_MB_2U_LIB.S9S_MB_2U(SCH_1):PAGE98_I147@PURE_QUANTA.SCONN288_ADR50017P130CC(CHIPS)':
 'VSS101': CDS_PINID='VSS101';
NODE_NAME     J17 235
 '@S9S_MB_2U_LIB.S9S_MB_2U(SCH_1):PAGE98_I147@PURE_QUANTA.SCONN288_ADR50017P130CC(CHIPS)':
 'VSS102': CDS_PINID='VSS102';
NODE_NAME     J17 237
 '@S9S_MB_2U_LIB.S9S_MB_2U(SCH_1):PAGE98_I147@PURE_QUANTA.SCONN288_ADR50017P130CC(CHIPS)':
 'VSS103': CDS_PINID='VSS103';
NODE_NAME     J17 240
 '@S9S_MB_2U_LIB.S9S_MB_2U(SCH_1):PAGE98_I147@PURE_QUANTA.SCONN288_ADR50017P130CC(CHIPS)':
 'VSS104': CDS_PINID='VSS104';
NODE_NAME     J17 242
 '@S9S_MB_2U_LIB.S9S_MB_2U(SCH_1):PAGE98_I147@PURE_QUANTA.SCONN288_ADR50017P130CC(CHIPS)':
 'VSS105': CDS_PINID='VSS105';
NODE_NAME     J17 244
 '@S9S_MB_2U_LIB.S9S_MB_2U(SCH_1):PAGE98_I147@PURE_QUANTA.SCONN288_ADR50017P130CC(CHIPS)':
 'VSS106': CDS_PINID='VSS106';
NODE_NAME     J17 246
 '@S9S_MB_2U_LIB.S9S_MB_2U(SCH_1):PAGE98_I147@PURE_QUANTA.SCONN288_ADR50017P130CC(CHIPS)':
 'VSS107': CDS_PINID='VSS107';
NODE_NAME     J17 248
 '@S9S_MB_2U_LIB.S9S_MB_2U(SCH_1):PAGE98_I147@PURE_QUANTA.SCONN288_ADR50017P130CC(CHIPS)':
 'VSS108': CDS_PINID='VSS108';
NODE_NAME     J17 251
 '@S9S_MB_2U_LIB.S9S_MB_2U(SCH_1):PAGE98_I147@PURE_QUANTA.SCONN288_ADR50017P130CC(CHIPS)':
 'VSS109': CDS_PINID='VSS109';
NODE_NAME     J17 253
 '@S9S_MB_2U_LIB.S9S_MB_2U(SCH_1):PAGE98_I147@PURE_QUANTA.SCONN288_ADR50017P130CC(CHIPS)':
 'VSS110': CDS_PINID='VSS110';
NODE_NAME     J17 255
 '@S9S_MB_2U_LIB.S9S_MB_2U(SCH_1):PAGE98_I147@PURE_QUANTA.SCONN288_ADR50017P130CC(CHIPS)':
 'VSS111': CDS_PINID='VSS111';
NODE_NAME     J17 257
 '@S9S_MB_2U_LIB.S9S_MB_2U(SCH_1):PAGE98_I147@PURE_QUANTA.SCONN288_ADR50017P130CC(CHIPS)':
 'VSS112': CDS_PINID='VSS112';
NODE_NAME     J17 259
 '@S9S_MB_2U_LIB.S9S_MB_2U(SCH_1):PAGE98_I147@PURE_QUANTA.SCONN288_ADR50017P130CC(CHIPS)':
 'VSS113': CDS_PINID='VSS113';
NODE_NAME     J17 262
 '@S9S_MB_2U_LIB.S9S_MB_2U(SCH_1):PAGE98_I147@PURE_QUANTA.SCONN288_ADR50017P130CC(CHIPS)':
 'VSS114': CDS_PINID='VSS114';
NODE_NAME     J17 264
 '@S9S_MB_2U_LIB.S9S_MB_2U(SCH_1):PAGE98_I147@PURE_QUANTA.SCONN288_ADR50017P130CC(CHIPS)':
 'VSS115': CDS_PINID='VSS115';
NODE_NAME     J17 266
 '@S9S_MB_2U_LIB.S9S_MB_2U(SCH_1):PAGE98_I147@PURE_QUANTA.SCONN288_ADR50017P130CC(CHIPS)':
 'VSS116': CDS_PINID='VSS116';
NODE_NAME     J17 268
 '@S9S_MB_2U_LIB.S9S_MB_2U(SCH_1):PAGE98_I147@PURE_QUANTA.SCONN288_ADR50017P130CC(CHIPS)':
 'VSS117': CDS_PINID='VSS117';
NODE_NAME     J17 270
 '@S9S_MB_2U_LIB.S9S_MB_2U(SCH_1):PAGE98_I147@PURE_QUANTA.SCONN288_ADR50017P130CC(CHIPS)':
 'VSS118': CDS_PINID='VSS118';
NODE_NAME     J17 273
 '@S9S_MB_2U_LIB.S9S_MB_2U(SCH_1):PAGE98_I147@PURE_QUANTA.SCONN288_ADR50017P130CC(CHIPS)':
 'VSS119': CDS_PINID='VSS119';
NODE_NAME     J17 275
 '@S9S_MB_2U_LIB.S9S_MB_2U(SCH_1):PAGE98_I147@PURE_QUANTA.SCONN288_ADR50017P130CC(CHIPS)':
 'VSS120': CDS_PINID='VSS120';
NODE_NAME     J17 277
 '@S9S_MB_2U_LIB.S9S_MB_2U(SCH_1):PAGE98_I147@PURE_QUANTA.SCONN288_ADR50017P130CC(CHIPS)':
 'VSS121': CDS_PINID='VSS121';
NODE_NAME     J17 279
 '@S9S_MB_2U_LIB.S9S_MB_2U(SCH_1):PAGE98_I147@PURE_QUANTA.SCONN288_ADR50017P130CC(CHIPS)':
 'VSS122': CDS_PINID='VSS122';
NODE_NAME     J17 281
 '@S9S_MB_2U_LIB.S9S_MB_2U(SCH_1):PAGE98_I147@PURE_QUANTA.SCONN288_ADR50017P130CC(CHIPS)':
 'VSS123': CDS_PINID='VSS123';
NODE_NAME     J17 284
 '@S9S_MB_2U_LIB.S9S_MB_2U(SCH_1):PAGE98_I147@PURE_QUANTA.SCONN288_ADR50017P130CC(CHIPS)':
 'VSS124': CDS_PINID='VSS124';
NODE_NAME     J17 286
 '@S9S_MB_2U_LIB.S9S_MB_2U(SCH_1):PAGE98_I147@PURE_QUANTA.SCONN288_ADR50017P130CC(CHIPS)':
 'VSS125': CDS_PINID='VSS125';
NODE_NAME     J17 288
 '@S9S_MB_2U_LIB.S9S_MB_2U(SCH_1):PAGE98_I147@PURE_QUANTA.SCONN288_ADR50017P130CC(CHIPS)':
 'VSS126': CDS_PINID='VSS126';
NODE_NAME     R43 2
 '@S9S_MB_2U_LIB.S9S_MB_2U(SCH_1):PAGE99_I2@PURE_QUANTA.Q_RES(CHIPS)':
 'B': CDS_PINID='B';
NODE_NAME     C53 2
 '@S9S_MB_2U_LIB.S9S_MB_2U(SCH_1):PAGE99_I122@PURE_QUANTA.Q_CAP(CHIPS)':
 'B': CDS_PINID='B';
NODE_NAME     C54 2
 '@S9S_MB_2U_LIB.S9S_MB_2U(SCH_1):PAGE99_I126@PURE_QUANTA.Q_CAP(CHIPS)':
 'B': CDS_PINID='B';
NODE_NAME     C55 2
 '@S9S_MB_2U_LIB.S9S_MB_2U(SCH_1):PAGE99_I128@PURE_QUANTA.Q_CAP(CHIPS)':
 'B': CDS_PINID='B';
NODE_NAME     J18 G1
 '@S9S_MB_2U_LIB.S9S_MB_2U(SCH_1):PAGE99_I175@PURE_QUANTA.SCONN288_ADR50017P087CC(CHIPS)':
 'G1': CDS_PINID='G1';
NODE_NAME     J18 G2
 '@S9S_MB_2U_LIB.S9S_MB_2U(SCH_1):PAGE99_I175@PURE_QUANTA.SCONN288_ADR50017P087CC(CHIPS)':
 'G2': CDS_PINID='G2';
NODE_NAME     J18 G3
 '@S9S_MB_2U_LIB.S9S_MB_2U(SCH_1):PAGE99_I175@PURE_QUANTA.SCONN288_ADR50017P087CC(CHIPS)':
 'G3': CDS_PINID='G3';
NODE_NAME     J18 6
 '@S9S_MB_2U_LIB.S9S_MB_2U(SCH_1):PAGE99_I175@PURE_QUANTA.SCONN288_ADR50017P087CC(CHIPS)':
 'VSS0': CDS_PINID='VSS0';
NODE_NAME     J18 8
 '@S9S_MB_2U_LIB.S9S_MB_2U(SCH_1):PAGE99_I175@PURE_QUANTA.SCONN288_ADR50017P087CC(CHIPS)':
 'VSS1': CDS_PINID='VSS1';
NODE_NAME     J18 10
 '@S9S_MB_2U_LIB.S9S_MB_2U(SCH_1):PAGE99_I175@PURE_QUANTA.SCONN288_ADR50017P087CC(CHIPS)':
 'VSS2': CDS_PINID='VSS2';
NODE_NAME     J18 13
 '@S9S_MB_2U_LIB.S9S_MB_2U(SCH_1):PAGE99_I175@PURE_QUANTA.SCONN288_ADR50017P087CC(CHIPS)':
 'VSS3': CDS_PINID='VSS3';
NODE_NAME     J18 15
 '@S9S_MB_2U_LIB.S9S_MB_2U(SCH_1):PAGE99_I175@PURE_QUANTA.SCONN288_ADR50017P087CC(CHIPS)':
 'VSS4': CDS_PINID='VSS4';
NODE_NAME     J18 17
 '@S9S_MB_2U_LIB.S9S_MB_2U(SCH_1):PAGE99_I175@PURE_QUANTA.SCONN288_ADR50017P087CC(CHIPS)':
 'VSS5': CDS_PINID='VSS5';
NODE_NAME     J18 19
 '@S9S_MB_2U_LIB.S9S_MB_2U(SCH_1):PAGE99_I175@PURE_QUANTA.SCONN288_ADR50017P087CC(CHIPS)':
 'VSS6': CDS_PINID='VSS6';
NODE_NAME     J18 21
 '@S9S_MB_2U_LIB.S9S_MB_2U(SCH_1):PAGE99_I175@PURE_QUANTA.SCONN288_ADR50017P087CC(CHIPS)':
 'VSS7': CDS_PINID='VSS7';
NODE_NAME     J18 24
 '@S9S_MB_2U_LIB.S9S_MB_2U(SCH_1):PAGE99_I175@PURE_QUANTA.SCONN288_ADR50017P087CC(CHIPS)':
 'VSS8': CDS_PINID='VSS8';
NODE_NAME     J18 26
 '@S9S_MB_2U_LIB.S9S_MB_2U(SCH_1):PAGE99_I175@PURE_QUANTA.SCONN288_ADR50017P087CC(CHIPS)':
 'VSS9': CDS_PINID='VSS9';
NODE_NAME     J18 28
 '@S9S_MB_2U_LIB.S9S_MB_2U(SCH_1):PAGE99_I175@PURE_QUANTA.SCONN288_ADR50017P087CC(CHIPS)':
 'VSS10': CDS_PINID='VSS10';
NODE_NAME     J18 30
 '@S9S_MB_2U_LIB.S9S_MB_2U(SCH_1):PAGE99_I175@PURE_QUANTA.SCONN288_ADR50017P087CC(CHIPS)':
 'VSS11': CDS_PINID='VSS11';
NODE_NAME     J18 32
 '@S9S_MB_2U_LIB.S9S_MB_2U(SCH_1):PAGE99_I175@PURE_QUANTA.SCONN288_ADR50017P087CC(CHIPS)':
 'VSS12': CDS_PINID='VSS12';
NODE_NAME     J18 35
 '@S9S_MB_2U_LIB.S9S_MB_2U(SCH_1):PAGE99_I175@PURE_QUANTA.SCONN288_ADR50017P087CC(CHIPS)':
 'VSS13': CDS_PINID='VSS13';
NODE_NAME     J18 37
 '@S9S_MB_2U_LIB.S9S_MB_2U(SCH_1):PAGE99_I175@PURE_QUANTA.SCONN288_ADR50017P087CC(CHIPS)':
 'VSS14': CDS_PINID='VSS14';
NODE_NAME     J18 39
 '@S9S_MB_2U_LIB.S9S_MB_2U(SCH_1):PAGE99_I175@PURE_QUANTA.SCONN288_ADR50017P087CC(CHIPS)':
 'VSS15': CDS_PINID='VSS15';
NODE_NAME     J18 41
 '@S9S_MB_2U_LIB.S9S_MB_2U(SCH_1):PAGE99_I175@PURE_QUANTA.SCONN288_ADR50017P087CC(CHIPS)':
 'VSS16': CDS_PINID='VSS16';
NODE_NAME     J18 43
 '@S9S_MB_2U_LIB.S9S_MB_2U(SCH_1):PAGE99_I175@PURE_QUANTA.SCONN288_ADR50017P087CC(CHIPS)':
 'VSS17': CDS_PINID='VSS17';
NODE_NAME     J18 46
 '@S9S_MB_2U_LIB.S9S_MB_2U(SCH_1):PAGE99_I175@PURE_QUANTA.SCONN288_ADR50017P087CC(CHIPS)':
 'VSS18': CDS_PINID='VSS18';
NODE_NAME     J18 48
 '@S9S_MB_2U_LIB.S9S_MB_2U(SCH_1):PAGE99_I175@PURE_QUANTA.SCONN288_ADR50017P087CC(CHIPS)':
 'VSS19': CDS_PINID='VSS19';
NODE_NAME     J18 50
 '@S9S_MB_2U_LIB.S9S_MB_2U(SCH_1):PAGE99_I175@PURE_QUANTA.SCONN288_ADR50017P087CC(CHIPS)':
 'VSS20': CDS_PINID='VSS20';
NODE_NAME     J18 52
 '@S9S_MB_2U_LIB.S9S_MB_2U(SCH_1):PAGE99_I175@PURE_QUANTA.SCONN288_ADR50017P087CC(CHIPS)':
 'VSS21': CDS_PINID='VSS21';
NODE_NAME     J18 54
 '@S9S_MB_2U_LIB.S9S_MB_2U(SCH_1):PAGE99_I175@PURE_QUANTA.SCONN288_ADR50017P087CC(CHIPS)':
 'VSS22': CDS_PINID='VSS22';
NODE_NAME     J18 57
 '@S9S_MB_2U_LIB.S9S_MB_2U(SCH_1):PAGE99_I175@PURE_QUANTA.SCONN288_ADR50017P087CC(CHIPS)':
 'VSS23': CDS_PINID='VSS23';
NODE_NAME     J18 59
 '@S9S_MB_2U_LIB.S9S_MB_2U(SCH_1):PAGE99_I175@PURE_QUANTA.SCONN288_ADR50017P087CC(CHIPS)':
 'VSS24': CDS_PINID='VSS24';
NODE_NAME     J18 61
 '@S9S_MB_2U_LIB.S9S_MB_2U(SCH_1):PAGE99_I175@PURE_QUANTA.SCONN288_ADR50017P087CC(CHIPS)':
 'VSS25': CDS_PINID='VSS25';
NODE_NAME     J18 63
 '@S9S_MB_2U_LIB.S9S_MB_2U(SCH_1):PAGE99_I175@PURE_QUANTA.SCONN288_ADR50017P087CC(CHIPS)':
 'VSS26': CDS_PINID='VSS26';
NODE_NAME     J18 65
 '@S9S_MB_2U_LIB.S9S_MB_2U(SCH_1):PAGE99_I175@PURE_QUANTA.SCONN288_ADR50017P087CC(CHIPS)':
 'VSS27': CDS_PINID='VSS27';
NODE_NAME     J18 67
 '@S9S_MB_2U_LIB.S9S_MB_2U(SCH_1):PAGE99_I175@PURE_QUANTA.SCONN288_ADR50017P087CC(CHIPS)':
 'VSS28': CDS_PINID='VSS28';
NODE_NAME     J18 69
 '@S9S_MB_2U_LIB.S9S_MB_2U(SCH_1):PAGE99_I175@PURE_QUANTA.SCONN288_ADR50017P087CC(CHIPS)':
 'VSS29': CDS_PINID='VSS29';
NODE_NAME     J18 71
 '@S9S_MB_2U_LIB.S9S_MB_2U(SCH_1):PAGE99_I175@PURE_QUANTA.SCONN288_ADR50017P087CC(CHIPS)':
 'VSS30': CDS_PINID='VSS30';
NODE_NAME     J18 73
 '@S9S_MB_2U_LIB.S9S_MB_2U(SCH_1):PAGE99_I175@PURE_QUANTA.SCONN288_ADR50017P087CC(CHIPS)':
 'VSS31': CDS_PINID='VSS31';
NODE_NAME     J18 75
 '@S9S_MB_2U_LIB.S9S_MB_2U(SCH_1):PAGE99_I175@PURE_QUANTA.SCONN288_ADR50017P087CC(CHIPS)':
 'VSS32': CDS_PINID='VSS32';
NODE_NAME     J18 77
 '@S9S_MB_2U_LIB.S9S_MB_2U(SCH_1):PAGE99_I175@PURE_QUANTA.SCONN288_ADR50017P087CC(CHIPS)':
 'VSS33': CDS_PINID='VSS33';
NODE_NAME     J18 79
 '@S9S_MB_2U_LIB.S9S_MB_2U(SCH_1):PAGE99_I175@PURE_QUANTA.SCONN288_ADR50017P087CC(CHIPS)':
 'VSS34': CDS_PINID='VSS34';
NODE_NAME     J18 81
 '@S9S_MB_2U_LIB.S9S_MB_2U(SCH_1):PAGE99_I175@PURE_QUANTA.SCONN288_ADR50017P087CC(CHIPS)':
 'VSS35': CDS_PINID='VSS35';
NODE_NAME     J18 83
 '@S9S_MB_2U_LIB.S9S_MB_2U(SCH_1):PAGE99_I175@PURE_QUANTA.SCONN288_ADR50017P087CC(CHIPS)':
 'VSS36': CDS_PINID='VSS36';
NODE_NAME     J18 85
 '@S9S_MB_2U_LIB.S9S_MB_2U(SCH_1):PAGE99_I175@PURE_QUANTA.SCONN288_ADR50017P087CC(CHIPS)':
 'VSS37': CDS_PINID='VSS37';
NODE_NAME     J18 88
 '@S9S_MB_2U_LIB.S9S_MB_2U(SCH_1):PAGE99_I175@PURE_QUANTA.SCONN288_ADR50017P087CC(CHIPS)':
 'VSS38': CDS_PINID='VSS38';
NODE_NAME     J18 90
 '@S9S_MB_2U_LIB.S9S_MB_2U(SCH_1):PAGE99_I175@PURE_QUANTA.SCONN288_ADR50017P087CC(CHIPS)':
 'VSS39': CDS_PINID='VSS39';
NODE_NAME     J18 92
 '@S9S_MB_2U_LIB.S9S_MB_2U(SCH_1):PAGE99_I175@PURE_QUANTA.SCONN288_ADR50017P087CC(CHIPS)':
 'VSS40': CDS_PINID='VSS40';
NODE_NAME     J18 95
 '@S9S_MB_2U_LIB.S9S_MB_2U(SCH_1):PAGE99_I175@PURE_QUANTA.SCONN288_ADR50017P087CC(CHIPS)':
 'VSS41': CDS_PINID='VSS41';
NODE_NAME     J18 97
 '@S9S_MB_2U_LIB.S9S_MB_2U(SCH_1):PAGE99_I175@PURE_QUANTA.SCONN288_ADR50017P087CC(CHIPS)':
 'VSS42': CDS_PINID='VSS42';
NODE_NAME     J18 99
 '@S9S_MB_2U_LIB.S9S_MB_2U(SCH_1):PAGE99_I175@PURE_QUANTA.SCONN288_ADR50017P087CC(CHIPS)':
 'VSS43': CDS_PINID='VSS43';
NODE_NAME     J18 101
 '@S9S_MB_2U_LIB.S9S_MB_2U(SCH_1):PAGE99_I175@PURE_QUANTA.SCONN288_ADR50017P087CC(CHIPS)':
 'VSS44': CDS_PINID='VSS44';
NODE_NAME     J18 103
 '@S9S_MB_2U_LIB.S9S_MB_2U(SCH_1):PAGE99_I175@PURE_QUANTA.SCONN288_ADR50017P087CC(CHIPS)':
 'VSS45': CDS_PINID='VSS45';
NODE_NAME     J18 106
 '@S9S_MB_2U_LIB.S9S_MB_2U(SCH_1):PAGE99_I175@PURE_QUANTA.SCONN288_ADR50017P087CC(CHIPS)':
 'VSS46': CDS_PINID='VSS46';
NODE_NAME     J18 108
 '@S9S_MB_2U_LIB.S9S_MB_2U(SCH_1):PAGE99_I175@PURE_QUANTA.SCONN288_ADR50017P087CC(CHIPS)':
 'VSS47': CDS_PINID='VSS47';
NODE_NAME     J18 110
 '@S9S_MB_2U_LIB.S9S_MB_2U(SCH_1):PAGE99_I175@PURE_QUANTA.SCONN288_ADR50017P087CC(CHIPS)':
 'VSS48': CDS_PINID='VSS48';
NODE_NAME     J18 112
 '@S9S_MB_2U_LIB.S9S_MB_2U(SCH_1):PAGE99_I175@PURE_QUANTA.SCONN288_ADR50017P087CC(CHIPS)':
 'VSS49': CDS_PINID='VSS49';
NODE_NAME     J18 114
 '@S9S_MB_2U_LIB.S9S_MB_2U(SCH_1):PAGE99_I175@PURE_QUANTA.SCONN288_ADR50017P087CC(CHIPS)':
 'VSS50': CDS_PINID='VSS50';
NODE_NAME     J18 117
 '@S9S_MB_2U_LIB.S9S_MB_2U(SCH_1):PAGE99_I175@PURE_QUANTA.SCONN288_ADR50017P087CC(CHIPS)':
 'VSS51': CDS_PINID='VSS51';
NODE_NAME     J18 119
 '@S9S_MB_2U_LIB.S9S_MB_2U(SCH_1):PAGE99_I175@PURE_QUANTA.SCONN288_ADR50017P087CC(CHIPS)':
 'VSS52': CDS_PINID='VSS52';
NODE_NAME     J18 121
 '@S9S_MB_2U_LIB.S9S_MB_2U(SCH_1):PAGE99_I175@PURE_QUANTA.SCONN288_ADR50017P087CC(CHIPS)':
 'VSS53': CDS_PINID='VSS53';
NODE_NAME     J18 123
 '@S9S_MB_2U_LIB.S9S_MB_2U(SCH_1):PAGE99_I175@PURE_QUANTA.SCONN288_ADR50017P087CC(CHIPS)':
 'VSS54': CDS_PINID='VSS54';
NODE_NAME     J18 125
 '@S9S_MB_2U_LIB.S9S_MB_2U(SCH_1):PAGE99_I175@PURE_QUANTA.SCONN288_ADR50017P087CC(CHIPS)':
 'VSS55': CDS_PINID='VSS55';
NODE_NAME     J18 128
 '@S9S_MB_2U_LIB.S9S_MB_2U(SCH_1):PAGE99_I175@PURE_QUANTA.SCONN288_ADR50017P087CC(CHIPS)':
 'VSS56': CDS_PINID='VSS56';
NODE_NAME     J18 130
 '@S9S_MB_2U_LIB.S9S_MB_2U(SCH_1):PAGE99_I175@PURE_QUANTA.SCONN288_ADR50017P087CC(CHIPS)':
 'VSS57': CDS_PINID='VSS57';
NODE_NAME     J18 132
 '@S9S_MB_2U_LIB.S9S_MB_2U(SCH_1):PAGE99_I175@PURE_QUANTA.SCONN288_ADR50017P087CC(CHIPS)':
 'VSS58': CDS_PINID='VSS58';
NODE_NAME     J18 134
 '@S9S_MB_2U_LIB.S9S_MB_2U(SCH_1):PAGE99_I175@PURE_QUANTA.SCONN288_ADR50017P087CC(CHIPS)':
 'VSS59': CDS_PINID='VSS59';
NODE_NAME     J18 136
 '@S9S_MB_2U_LIB.S9S_MB_2U(SCH_1):PAGE99_I175@PURE_QUANTA.SCONN288_ADR50017P087CC(CHIPS)':
 'VSS60': CDS_PINID='VSS60';
NODE_NAME     J18 139
 '@S9S_MB_2U_LIB.S9S_MB_2U(SCH_1):PAGE99_I175@PURE_QUANTA.SCONN288_ADR50017P087CC(CHIPS)':
 'VSS61': CDS_PINID='VSS61';
NODE_NAME     J18 141
 '@S9S_MB_2U_LIB.S9S_MB_2U(SCH_1):PAGE99_I175@PURE_QUANTA.SCONN288_ADR50017P087CC(CHIPS)':
 'VSS62': CDS_PINID='VSS62';
NODE_NAME     J18 143
 '@S9S_MB_2U_LIB.S9S_MB_2U(SCH_1):PAGE99_I175@PURE_QUANTA.SCONN288_ADR50017P087CC(CHIPS)':
 'VSS63': CDS_PINID='VSS63';
NODE_NAME     J18 151
 '@S9S_MB_2U_LIB.S9S_MB_2U(SCH_1):PAGE99_I175@PURE_QUANTA.SCONN288_ADR50017P087CC(CHIPS)':
 'VSS64': CDS_PINID='VSS64';
NODE_NAME     J18 153
 '@S9S_MB_2U_LIB.S9S_MB_2U(SCH_1):PAGE99_I175@PURE_QUANTA.SCONN288_ADR50017P087CC(CHIPS)':
 'VSS65': CDS_PINID='VSS65';
NODE_NAME     J18 155
 '@S9S_MB_2U_LIB.S9S_MB_2U(SCH_1):PAGE99_I175@PURE_QUANTA.SCONN288_ADR50017P087CC(CHIPS)':
 'VSS66': CDS_PINID='VSS66';
NODE_NAME     J18 158
 '@S9S_MB_2U_LIB.S9S_MB_2U(SCH_1):PAGE99_I175@PURE_QUANTA.SCONN288_ADR50017P087CC(CHIPS)':
 'VSS67': CDS_PINID='VSS67';
NODE_NAME     J18 160
 '@S9S_MB_2U_LIB.S9S_MB_2U(SCH_1):PAGE99_I175@PURE_QUANTA.SCONN288_ADR50017P087CC(CHIPS)':
 'VSS68': CDS_PINID='VSS68';
NODE_NAME     J18 162
 '@S9S_MB_2U_LIB.S9S_MB_2U(SCH_1):PAGE99_I175@PURE_QUANTA.SCONN288_ADR50017P087CC(CHIPS)':
 'VSS69': CDS_PINID='VSS69';
NODE_NAME     J18 164
 '@S9S_MB_2U_LIB.S9S_MB_2U(SCH_1):PAGE99_I175@PURE_QUANTA.SCONN288_ADR50017P087CC(CHIPS)':
 'VSS70': CDS_PINID='VSS70';
NODE_NAME     J18 166
 '@S9S_MB_2U_LIB.S9S_MB_2U(SCH_1):PAGE99_I175@PURE_QUANTA.SCONN288_ADR50017P087CC(CHIPS)':
 'VSS71': CDS_PINID='VSS71';
NODE_NAME     J18 169
 '@S9S_MB_2U_LIB.S9S_MB_2U(SCH_1):PAGE99_I175@PURE_QUANTA.SCONN288_ADR50017P087CC(CHIPS)':
 'VSS72': CDS_PINID='VSS72';
NODE_NAME     J18 171
 '@S9S_MB_2U_LIB.S9S_MB_2U(SCH_1):PAGE99_I175@PURE_QUANTA.SCONN288_ADR50017P087CC(CHIPS)':
 'VSS73': CDS_PINID='VSS73';
NODE_NAME     J18 173
 '@S9S_MB_2U_LIB.S9S_MB_2U(SCH_1):PAGE99_I175@PURE_QUANTA.SCONN288_ADR50017P087CC(CHIPS)':
 'VSS74': CDS_PINID='VSS74';
NODE_NAME     J18 175
 '@S9S_MB_2U_LIB.S9S_MB_2U(SCH_1):PAGE99_I175@PURE_QUANTA.SCONN288_ADR50017P087CC(CHIPS)':
 'VSS75': CDS_PINID='VSS75';
NODE_NAME     J18 177
 '@S9S_MB_2U_LIB.S9S_MB_2U(SCH_1):PAGE99_I175@PURE_QUANTA.SCONN288_ADR50017P087CC(CHIPS)':
 'VSS76': CDS_PINID='VSS76';
NODE_NAME     J18 180
 '@S9S_MB_2U_LIB.S9S_MB_2U(SCH_1):PAGE99_I175@PURE_QUANTA.SCONN288_ADR50017P087CC(CHIPS)':
 'VSS77': CDS_PINID='VSS77';
NODE_NAME     J18 182
 '@S9S_MB_2U_LIB.S9S_MB_2U(SCH_1):PAGE99_I175@PURE_QUANTA.SCONN288_ADR50017P087CC(CHIPS)':
 'VSS78': CDS_PINID='VSS78';
NODE_NAME     J18 184
 '@S9S_MB_2U_LIB.S9S_MB_2U(SCH_1):PAGE99_I175@PURE_QUANTA.SCONN288_ADR50017P087CC(CHIPS)':
 'VSS79': CDS_PINID='VSS79';
NODE_NAME     J18 186
 '@S9S_MB_2U_LIB.S9S_MB_2U(SCH_1):PAGE99_I175@PURE_QUANTA.SCONN288_ADR50017P087CC(CHIPS)':
 'VSS80': CDS_PINID='VSS80';
NODE_NAME     J18 188
 '@S9S_MB_2U_LIB.S9S_MB_2U(SCH_1):PAGE99_I175@PURE_QUANTA.SCONN288_ADR50017P087CC(CHIPS)':
 'VSS81': CDS_PINID='VSS81';
NODE_NAME     J18 191
 '@S9S_MB_2U_LIB.S9S_MB_2U(SCH_1):PAGE99_I175@PURE_QUANTA.SCONN288_ADR50017P087CC(CHIPS)':
 'VSS82': CDS_PINID='VSS82';
NODE_NAME     J18 193
 '@S9S_MB_2U_LIB.S9S_MB_2U(SCH_1):PAGE99_I175@PURE_QUANTA.SCONN288_ADR50017P087CC(CHIPS)':
 'VSS83': CDS_PINID='VSS83';
NODE_NAME     J18 195
 '@S9S_MB_2U_LIB.S9S_MB_2U(SCH_1):PAGE99_I175@PURE_QUANTA.SCONN288_ADR50017P087CC(CHIPS)':
 'VSS84': CDS_PINID='VSS84';
NODE_NAME     J18 197
 '@S9S_MB_2U_LIB.S9S_MB_2U(SCH_1):PAGE99_I175@PURE_QUANTA.SCONN288_ADR50017P087CC(CHIPS)':
 'VSS85': CDS_PINID='VSS85';
NODE_NAME     J18 199
 '@S9S_MB_2U_LIB.S9S_MB_2U(SCH_1):PAGE99_I175@PURE_QUANTA.SCONN288_ADR50017P087CC(CHIPS)':
 'VSS86': CDS_PINID='VSS86';
NODE_NAME     J18 202
 '@S9S_MB_2U_LIB.S9S_MB_2U(SCH_1):PAGE99_I175@PURE_QUANTA.SCONN288_ADR50017P087CC(CHIPS)':
 'VSS87': CDS_PINID='VSS87';
NODE_NAME     J18 204
 '@S9S_MB_2U_LIB.S9S_MB_2U(SCH_1):PAGE99_I175@PURE_QUANTA.SCONN288_ADR50017P087CC(CHIPS)':
 'VSS88': CDS_PINID='VSS88';
NODE_NAME     J18 206
 '@S9S_MB_2U_LIB.S9S_MB_2U(SCH_1):PAGE99_I175@PURE_QUANTA.SCONN288_ADR50017P087CC(CHIPS)':
 'VSS89': CDS_PINID='VSS89';
NODE_NAME     J18 208
 '@S9S_MB_2U_LIB.S9S_MB_2U(SCH_1):PAGE99_I175@PURE_QUANTA.SCONN288_ADR50017P087CC(CHIPS)':
 'VSS90': CDS_PINID='VSS90';
NODE_NAME     J18 210
 '@S9S_MB_2U_LIB.S9S_MB_2U(SCH_1):PAGE99_I175@PURE_QUANTA.SCONN288_ADR50017P087CC(CHIPS)':
 'VSS91': CDS_PINID='VSS91';
NODE_NAME     J18 212
 '@S9S_MB_2U_LIB.S9S_MB_2U(SCH_1):PAGE99_I175@PURE_QUANTA.SCONN288_ADR50017P087CC(CHIPS)':
 'VSS92': CDS_PINID='VSS92';
NODE_NAME     J18 214
 '@S9S_MB_2U_LIB.S9S_MB_2U(SCH_1):PAGE99_I175@PURE_QUANTA.SCONN288_ADR50017P087CC(CHIPS)':
 'VSS93': CDS_PINID='VSS93';
NODE_NAME     J18 216
 '@S9S_MB_2U_LIB.S9S_MB_2U(SCH_1):PAGE99_I175@PURE_QUANTA.SCONN288_ADR50017P087CC(CHIPS)':
 'VSS94': CDS_PINID='VSS94';
NODE_NAME     J18 219
 '@S9S_MB_2U_LIB.S9S_MB_2U(SCH_1):PAGE99_I175@PURE_QUANTA.SCONN288_ADR50017P087CC(CHIPS)':
 'VSS95': CDS_PINID='VSS95';
NODE_NAME     J18 222
 '@S9S_MB_2U_LIB.S9S_MB_2U(SCH_1):PAGE99_I175@PURE_QUANTA.SCONN288_ADR50017P087CC(CHIPS)':
 'VSS96': CDS_PINID='VSS96';
NODE_NAME     J18 224
 '@S9S_MB_2U_LIB.S9S_MB_2U(SCH_1):PAGE99_I175@PURE_QUANTA.SCONN288_ADR50017P087CC(CHIPS)':
 'VSS97': CDS_PINID='VSS97';
NODE_NAME     J18 226
 '@S9S_MB_2U_LIB.S9S_MB_2U(SCH_1):PAGE99_I175@PURE_QUANTA.SCONN288_ADR50017P087CC(CHIPS)':
 'VSS98': CDS_PINID='VSS98';
NODE_NAME     J18 228
 '@S9S_MB_2U_LIB.S9S_MB_2U(SCH_1):PAGE99_I175@PURE_QUANTA.SCONN288_ADR50017P087CC(CHIPS)':
 'VSS99': CDS_PINID='VSS99';
NODE_NAME     J18 230
 '@S9S_MB_2U_LIB.S9S_MB_2U(SCH_1):PAGE99_I175@PURE_QUANTA.SCONN288_ADR50017P087CC(CHIPS)':
 'VSS100': CDS_PINID='VSS100';
NODE_NAME     J18 233
 '@S9S_MB_2U_LIB.S9S_MB_2U(SCH_1):PAGE99_I175@PURE_QUANTA.SCONN288_ADR50017P087CC(CHIPS)':
 'VSS101': CDS_PINID='VSS101';
NODE_NAME     J18 235
 '@S9S_MB_2U_LIB.S9S_MB_2U(SCH_1):PAGE99_I175@PURE_QUANTA.SCONN288_ADR50017P087CC(CHIPS)':
 'VSS102': CDS_PINID='VSS102';
NODE_NAME     J18 237
 '@S9S_MB_2U_LIB.S9S_MB_2U(SCH_1):PAGE99_I175@PURE_QUANTA.SCONN288_ADR50017P087CC(CHIPS)':
 'VSS103': CDS_PINID='VSS103';
NODE_NAME     J18 240
 '@S9S_MB_2U_LIB.S9S_MB_2U(SCH_1):PAGE99_I175@PURE_QUANTA.SCONN288_ADR50017P087CC(CHIPS)':
 'VSS104': CDS_PINID='VSS104';
NODE_NAME     J18 242
 '@S9S_MB_2U_LIB.S9S_MB_2U(SCH_1):PAGE99_I175@PURE_QUANTA.SCONN288_ADR50017P087CC(CHIPS)':
 'VSS105': CDS_PINID='VSS105';
NODE_NAME     J18 244
 '@S9S_MB_2U_LIB.S9S_MB_2U(SCH_1):PAGE99_I175@PURE_QUANTA.SCONN288_ADR50017P087CC(CHIPS)':
 'VSS106': CDS_PINID='VSS106';
NODE_NAME     J18 246
 '@S9S_MB_2U_LIB.S9S_MB_2U(SCH_1):PAGE99_I175@PURE_QUANTA.SCONN288_ADR50017P087CC(CHIPS)':
 'VSS107': CDS_PINID='VSS107';
NODE_NAME     J18 248
 '@S9S_MB_2U_LIB.S9S_MB_2U(SCH_1):PAGE99_I175@PURE_QUANTA.SCONN288_ADR50017P087CC(CHIPS)':
 'VSS108': CDS_PINID='VSS108';
NODE_NAME     J18 251
 '@S9S_MB_2U_LIB.S9S_MB_2U(SCH_1):PAGE99_I175@PURE_QUANTA.SCONN288_ADR50017P087CC(CHIPS)':
 'VSS109': CDS_PINID='VSS109';
NODE_NAME     J18 253
 '@S9S_MB_2U_LIB.S9S_MB_2U(SCH_1):PAGE99_I175@PURE_QUANTA.SCONN288_ADR50017P087CC(CHIPS)':
 'VSS110': CDS_PINID='VSS110';
NODE_NAME     J18 255
 '@S9S_MB_2U_LIB.S9S_MB_2U(SCH_1):PAGE99_I175@PURE_QUANTA.SCONN288_ADR50017P087CC(CHIPS)':
 'VSS111': CDS_PINID='VSS111';
NODE_NAME     J18 257
 '@S9S_MB_2U_LIB.S9S_MB_2U(SCH_1):PAGE99_I175@PURE_QUANTA.SCONN288_ADR50017P087CC(CHIPS)':
 'VSS112': CDS_PINID='VSS112';
NODE_NAME     J18 259
 '@S9S_MB_2U_LIB.S9S_MB_2U(SCH_1):PAGE99_I175@PURE_QUANTA.SCONN288_ADR50017P087CC(CHIPS)':
 'VSS113': CDS_PINID='VSS113';
NODE_NAME     J18 262
 '@S9S_MB_2U_LIB.S9S_MB_2U(SCH_1):PAGE99_I175@PURE_QUANTA.SCONN288_ADR50017P087CC(CHIPS)':
 'VSS114': CDS_PINID='VSS114';
NODE_NAME     J18 264
 '@S9S_MB_2U_LIB.S9S_MB_2U(SCH_1):PAGE99_I175@PURE_QUANTA.SCONN288_ADR50017P087CC(CHIPS)':
 'VSS115': CDS_PINID='VSS115';
NODE_NAME     J18 266
 '@S9S_MB_2U_LIB.S9S_MB_2U(SCH_1):PAGE99_I175@PURE_QUANTA.SCONN288_ADR50017P087CC(CHIPS)':
 'VSS116': CDS_PINID='VSS116';
NODE_NAME     J18 268
 '@S9S_MB_2U_LIB.S9S_MB_2U(SCH_1):PAGE99_I175@PURE_QUANTA.SCONN288_ADR50017P087CC(CHIPS)':
 'VSS117': CDS_PINID='VSS117';
NODE_NAME     J18 270
 '@S9S_MB_2U_LIB.S9S_MB_2U(SCH_1):PAGE99_I175@PURE_QUANTA.SCONN288_ADR50017P087CC(CHIPS)':
 'VSS118': CDS_PINID='VSS118';
NODE_NAME     J18 273
 '@S9S_MB_2U_LIB.S9S_MB_2U(SCH_1):PAGE99_I175@PURE_QUANTA.SCONN288_ADR50017P087CC(CHIPS)':
 'VSS119': CDS_PINID='VSS119';
NODE_NAME     J18 275
 '@S9S_MB_2U_LIB.S9S_MB_2U(SCH_1):PAGE99_I175@PURE_QUANTA.SCONN288_ADR50017P087CC(CHIPS)':
 'VSS120': CDS_PINID='VSS120';
NODE_NAME     J18 277
 '@S9S_MB_2U_LIB.S9S_MB_2U(SCH_1):PAGE99_I175@PURE_QUANTA.SCONN288_ADR50017P087CC(CHIPS)':
 'VSS121': CDS_PINID='VSS121';
NODE_NAME     J18 279
 '@S9S_MB_2U_LIB.S9S_MB_2U(SCH_1):PAGE99_I175@PURE_QUANTA.SCONN288_ADR50017P087CC(CHIPS)':
 'VSS122': CDS_PINID='VSS122';
NODE_NAME     J18 281
 '@S9S_MB_2U_LIB.S9S_MB_2U(SCH_1):PAGE99_I175@PURE_QUANTA.SCONN288_ADR50017P087CC(CHIPS)':
 'VSS123': CDS_PINID='VSS123';
NODE_NAME     J18 284
 '@S9S_MB_2U_LIB.S9S_MB_2U(SCH_1):PAGE99_I175@PURE_QUANTA.SCONN288_ADR50017P087CC(CHIPS)':
 'VSS124': CDS_PINID='VSS124';
NODE_NAME     J18 286
 '@S9S_MB_2U_LIB.S9S_MB_2U(SCH_1):PAGE99_I175@PURE_QUANTA.SCONN288_ADR50017P087CC(CHIPS)':
 'VSS125': CDS_PINID='VSS125';
NODE_NAME     J18 288
 '@S9S_MB_2U_LIB.S9S_MB_2U(SCH_1):PAGE99_I175@PURE_QUANTA.SCONN288_ADR50017P087CC(CHIPS)':
 'VSS126': CDS_PINID='VSS126';
NODE_NAME     R44 2
 '@S9S_MB_2U_LIB.S9S_MB_2U(SCH_1):PAGE100_I3@PURE_QUANTA.Q_RES(CHIPS)':
 'B': CDS_PINID='B';
NODE_NAME     C56 2
 '@S9S_MB_2U_LIB.S9S_MB_2U(SCH_1):PAGE100_I121@PURE_QUANTA.Q_CAP(CHIPS)':
 'B': CDS_PINID='B';
NODE_NAME     C57 2
 '@S9S_MB_2U_LIB.S9S_MB_2U(SCH_1):PAGE100_I122@PURE_QUANTA.Q_CAP(CHIPS)':
 'B': CDS_PINID='B';
NODE_NAME     C58 2
 '@S9S_MB_2U_LIB.S9S_MB_2U(SCH_1):PAGE100_I124@PURE_QUANTA.Q_CAP(CHIPS)':
 'B': CDS_PINID='B';
NODE_NAME     J19 G1
 '@S9S_MB_2U_LIB.S9S_MB_2U(SCH_1):PAGE100_I175@PURE_QUANTA.SCONN288_ADR50017P130CC(CHIPS)':
 'G1': CDS_PINID='G1';
NODE_NAME     J19 G2
 '@S9S_MB_2U_LIB.S9S_MB_2U(SCH_1):PAGE100_I175@PURE_QUANTA.SCONN288_ADR50017P130CC(CHIPS)':
 'G2': CDS_PINID='G2';
NODE_NAME     J19 G3
 '@S9S_MB_2U_LIB.S9S_MB_2U(SCH_1):PAGE100_I175@PURE_QUANTA.SCONN288_ADR50017P130CC(CHIPS)':
 'G3': CDS_PINID='G3';
NODE_NAME     J19 6
 '@S9S_MB_2U_LIB.S9S_MB_2U(SCH_1):PAGE100_I175@PURE_QUANTA.SCONN288_ADR50017P130CC(CHIPS)':
 'VSS0': CDS_PINID='VSS0';
NODE_NAME     J19 8
 '@S9S_MB_2U_LIB.S9S_MB_2U(SCH_1):PAGE100_I175@PURE_QUANTA.SCONN288_ADR50017P130CC(CHIPS)':
 'VSS1': CDS_PINID='VSS1';
NODE_NAME     J19 10
 '@S9S_MB_2U_LIB.S9S_MB_2U(SCH_1):PAGE100_I175@PURE_QUANTA.SCONN288_ADR50017P130CC(CHIPS)':
 'VSS2': CDS_PINID='VSS2';
NODE_NAME     J19 13
 '@S9S_MB_2U_LIB.S9S_MB_2U(SCH_1):PAGE100_I175@PURE_QUANTA.SCONN288_ADR50017P130CC(CHIPS)':
 'VSS3': CDS_PINID='VSS3';
NODE_NAME     J19 15
 '@S9S_MB_2U_LIB.S9S_MB_2U(SCH_1):PAGE100_I175@PURE_QUANTA.SCONN288_ADR50017P130CC(CHIPS)':
 'VSS4': CDS_PINID='VSS4';
NODE_NAME     J19 17
 '@S9S_MB_2U_LIB.S9S_MB_2U(SCH_1):PAGE100_I175@PURE_QUANTA.SCONN288_ADR50017P130CC(CHIPS)':
 'VSS5': CDS_PINID='VSS5';
NODE_NAME     J19 19
 '@S9S_MB_2U_LIB.S9S_MB_2U(SCH_1):PAGE100_I175@PURE_QUANTA.SCONN288_ADR50017P130CC(CHIPS)':
 'VSS6': CDS_PINID='VSS6';
NODE_NAME     J19 21
 '@S9S_MB_2U_LIB.S9S_MB_2U(SCH_1):PAGE100_I175@PURE_QUANTA.SCONN288_ADR50017P130CC(CHIPS)':
 'VSS7': CDS_PINID='VSS7';
NODE_NAME     J19 24
 '@S9S_MB_2U_LIB.S9S_MB_2U(SCH_1):PAGE100_I175@PURE_QUANTA.SCONN288_ADR50017P130CC(CHIPS)':
 'VSS8': CDS_PINID='VSS8';
NODE_NAME     J19 26
 '@S9S_MB_2U_LIB.S9S_MB_2U(SCH_1):PAGE100_I175@PURE_QUANTA.SCONN288_ADR50017P130CC(CHIPS)':
 'VSS9': CDS_PINID='VSS9';
NODE_NAME     J19 28
 '@S9S_MB_2U_LIB.S9S_MB_2U(SCH_1):PAGE100_I175@PURE_QUANTA.SCONN288_ADR50017P130CC(CHIPS)':
 'VSS10': CDS_PINID='VSS10';
NODE_NAME     J19 30
 '@S9S_MB_2U_LIB.S9S_MB_2U(SCH_1):PAGE100_I175@PURE_QUANTA.SCONN288_ADR50017P130CC(CHIPS)':
 'VSS11': CDS_PINID='VSS11';
NODE_NAME     J19 32
 '@S9S_MB_2U_LIB.S9S_MB_2U(SCH_1):PAGE100_I175@PURE_QUANTA.SCONN288_ADR50017P130CC(CHIPS)':
 'VSS12': CDS_PINID='VSS12';
NODE_NAME     J19 35
 '@S9S_MB_2U_LIB.S9S_MB_2U(SCH_1):PAGE100_I175@PURE_QUANTA.SCONN288_ADR50017P130CC(CHIPS)':
 'VSS13': CDS_PINID='VSS13';
NODE_NAME     J19 37
 '@S9S_MB_2U_LIB.S9S_MB_2U(SCH_1):PAGE100_I175@PURE_QUANTA.SCONN288_ADR50017P130CC(CHIPS)':
 'VSS14': CDS_PINID='VSS14';
NODE_NAME     J19 39
 '@S9S_MB_2U_LIB.S9S_MB_2U(SCH_1):PAGE100_I175@PURE_QUANTA.SCONN288_ADR50017P130CC(CHIPS)':
 'VSS15': CDS_PINID='VSS15';
NODE_NAME     J19 41
 '@S9S_MB_2U_LIB.S9S_MB_2U(SCH_1):PAGE100_I175@PURE_QUANTA.SCONN288_ADR50017P130CC(CHIPS)':
 'VSS16': CDS_PINID='VSS16';
NODE_NAME     J19 43
 '@S9S_MB_2U_LIB.S9S_MB_2U(SCH_1):PAGE100_I175@PURE_QUANTA.SCONN288_ADR50017P130CC(CHIPS)':
 'VSS17': CDS_PINID='VSS17';
NODE_NAME     J19 46
 '@S9S_MB_2U_LIB.S9S_MB_2U(SCH_1):PAGE100_I175@PURE_QUANTA.SCONN288_ADR50017P130CC(CHIPS)':
 'VSS18': CDS_PINID='VSS18';
NODE_NAME     J19 48
 '@S9S_MB_2U_LIB.S9S_MB_2U(SCH_1):PAGE100_I175@PURE_QUANTA.SCONN288_ADR50017P130CC(CHIPS)':
 'VSS19': CDS_PINID='VSS19';
NODE_NAME     J19 50
 '@S9S_MB_2U_LIB.S9S_MB_2U(SCH_1):PAGE100_I175@PURE_QUANTA.SCONN288_ADR50017P130CC(CHIPS)':
 'VSS20': CDS_PINID='VSS20';
NODE_NAME     J19 52
 '@S9S_MB_2U_LIB.S9S_MB_2U(SCH_1):PAGE100_I175@PURE_QUANTA.SCONN288_ADR50017P130CC(CHIPS)':
 'VSS21': CDS_PINID='VSS21';
NODE_NAME     J19 54
 '@S9S_MB_2U_LIB.S9S_MB_2U(SCH_1):PAGE100_I175@PURE_QUANTA.SCONN288_ADR50017P130CC(CHIPS)':
 'VSS22': CDS_PINID='VSS22';
NODE_NAME     J19 57
 '@S9S_MB_2U_LIB.S9S_MB_2U(SCH_1):PAGE100_I175@PURE_QUANTA.SCONN288_ADR50017P130CC(CHIPS)':
 'VSS23': CDS_PINID='VSS23';
NODE_NAME     J19 59
 '@S9S_MB_2U_LIB.S9S_MB_2U(SCH_1):PAGE100_I175@PURE_QUANTA.SCONN288_ADR50017P130CC(CHIPS)':
 'VSS24': CDS_PINID='VSS24';
NODE_NAME     J19 61
 '@S9S_MB_2U_LIB.S9S_MB_2U(SCH_1):PAGE100_I175@PURE_QUANTA.SCONN288_ADR50017P130CC(CHIPS)':
 'VSS25': CDS_PINID='VSS25';
NODE_NAME     J19 63
 '@S9S_MB_2U_LIB.S9S_MB_2U(SCH_1):PAGE100_I175@PURE_QUANTA.SCONN288_ADR50017P130CC(CHIPS)':
 'VSS26': CDS_PINID='VSS26';
NODE_NAME     J19 65
 '@S9S_MB_2U_LIB.S9S_MB_2U(SCH_1):PAGE100_I175@PURE_QUANTA.SCONN288_ADR50017P130CC(CHIPS)':
 'VSS27': CDS_PINID='VSS27';
NODE_NAME     J19 67
 '@S9S_MB_2U_LIB.S9S_MB_2U(SCH_1):PAGE100_I175@PURE_QUANTA.SCONN288_ADR50017P130CC(CHIPS)':
 'VSS28': CDS_PINID='VSS28';
NODE_NAME     J19 69
 '@S9S_MB_2U_LIB.S9S_MB_2U(SCH_1):PAGE100_I175@PURE_QUANTA.SCONN288_ADR50017P130CC(CHIPS)':
 'VSS29': CDS_PINID='VSS29';
NODE_NAME     J19 71
 '@S9S_MB_2U_LIB.S9S_MB_2U(SCH_1):PAGE100_I175@PURE_QUANTA.SCONN288_ADR50017P130CC(CHIPS)':
 'VSS30': CDS_PINID='VSS30';
NODE_NAME     J19 73
 '@S9S_MB_2U_LIB.S9S_MB_2U(SCH_1):PAGE100_I175@PURE_QUANTA.SCONN288_ADR50017P130CC(CHIPS)':
 'VSS31': CDS_PINID='VSS31';
NODE_NAME     J19 75
 '@S9S_MB_2U_LIB.S9S_MB_2U(SCH_1):PAGE100_I175@PURE_QUANTA.SCONN288_ADR50017P130CC(CHIPS)':
 'VSS32': CDS_PINID='VSS32';
NODE_NAME     J19 77
 '@S9S_MB_2U_LIB.S9S_MB_2U(SCH_1):PAGE100_I175@PURE_QUANTA.SCONN288_ADR50017P130CC(CHIPS)':
 'VSS33': CDS_PINID='VSS33';
NODE_NAME     J19 79
 '@S9S_MB_2U_LIB.S9S_MB_2U(SCH_1):PAGE100_I175@PURE_QUANTA.SCONN288_ADR50017P130CC(CHIPS)':
 'VSS34': CDS_PINID='VSS34';
NODE_NAME     J19 81
 '@S9S_MB_2U_LIB.S9S_MB_2U(SCH_1):PAGE100_I175@PURE_QUANTA.SCONN288_ADR50017P130CC(CHIPS)':
 'VSS35': CDS_PINID='VSS35';
NODE_NAME     J19 83
 '@S9S_MB_2U_LIB.S9S_MB_2U(SCH_1):PAGE100_I175@PURE_QUANTA.SCONN288_ADR50017P130CC(CHIPS)':
 'VSS36': CDS_PINID='VSS36';
NODE_NAME     J19 85
 '@S9S_MB_2U_LIB.S9S_MB_2U(SCH_1):PAGE100_I175@PURE_QUANTA.SCONN288_ADR50017P130CC(CHIPS)':
 'VSS37': CDS_PINID='VSS37';
NODE_NAME     J19 88
 '@S9S_MB_2U_LIB.S9S_MB_2U(SCH_1):PAGE100_I175@PURE_QUANTA.SCONN288_ADR50017P130CC(CHIPS)':
 'VSS38': CDS_PINID='VSS38';
NODE_NAME     J19 90
 '@S9S_MB_2U_LIB.S9S_MB_2U(SCH_1):PAGE100_I175@PURE_QUANTA.SCONN288_ADR50017P130CC(CHIPS)':
 'VSS39': CDS_PINID='VSS39';
NODE_NAME     J19 92
 '@S9S_MB_2U_LIB.S9S_MB_2U(SCH_1):PAGE100_I175@PURE_QUANTA.SCONN288_ADR50017P130CC(CHIPS)':
 'VSS40': CDS_PINID='VSS40';
NODE_NAME     J19 95
 '@S9S_MB_2U_LIB.S9S_MB_2U(SCH_1):PAGE100_I175@PURE_QUANTA.SCONN288_ADR50017P130CC(CHIPS)':
 'VSS41': CDS_PINID='VSS41';
NODE_NAME     J19 97
 '@S9S_MB_2U_LIB.S9S_MB_2U(SCH_1):PAGE100_I175@PURE_QUANTA.SCONN288_ADR50017P130CC(CHIPS)':
 'VSS42': CDS_PINID='VSS42';
NODE_NAME     J19 99
 '@S9S_MB_2U_LIB.S9S_MB_2U(SCH_1):PAGE100_I175@PURE_QUANTA.SCONN288_ADR50017P130CC(CHIPS)':
 'VSS43': CDS_PINID='VSS43';
NODE_NAME     J19 101
 '@S9S_MB_2U_LIB.S9S_MB_2U(SCH_1):PAGE100_I175@PURE_QUANTA.SCONN288_ADR50017P130CC(CHIPS)':
 'VSS44': CDS_PINID='VSS44';
NODE_NAME     J19 103
 '@S9S_MB_2U_LIB.S9S_MB_2U(SCH_1):PAGE100_I175@PURE_QUANTA.SCONN288_ADR50017P130CC(CHIPS)':
 'VSS45': CDS_PINID='VSS45';
NODE_NAME     J19 106
 '@S9S_MB_2U_LIB.S9S_MB_2U(SCH_1):PAGE100_I175@PURE_QUANTA.SCONN288_ADR50017P130CC(CHIPS)':
 'VSS46': CDS_PINID='VSS46';
NODE_NAME     J19 108
 '@S9S_MB_2U_LIB.S9S_MB_2U(SCH_1):PAGE100_I175@PURE_QUANTA.SCONN288_ADR50017P130CC(CHIPS)':
 'VSS47': CDS_PINID='VSS47';
NODE_NAME     J19 110
 '@S9S_MB_2U_LIB.S9S_MB_2U(SCH_1):PAGE100_I175@PURE_QUANTA.SCONN288_ADR50017P130CC(CHIPS)':
 'VSS48': CDS_PINID='VSS48';
NODE_NAME     J19 112
 '@S9S_MB_2U_LIB.S9S_MB_2U(SCH_1):PAGE100_I175@PURE_QUANTA.SCONN288_ADR50017P130CC(CHIPS)':
 'VSS49': CDS_PINID='VSS49';
NODE_NAME     J19 114
 '@S9S_MB_2U_LIB.S9S_MB_2U(SCH_1):PAGE100_I175@PURE_QUANTA.SCONN288_ADR50017P130CC(CHIPS)':
 'VSS50': CDS_PINID='VSS50';
NODE_NAME     J19 117
 '@S9S_MB_2U_LIB.S9S_MB_2U(SCH_1):PAGE100_I175@PURE_QUANTA.SCONN288_ADR50017P130CC(CHIPS)':
 'VSS51': CDS_PINID='VSS51';
NODE_NAME     J19 119
 '@S9S_MB_2U_LIB.S9S_MB_2U(SCH_1):PAGE100_I175@PURE_QUANTA.SCONN288_ADR50017P130CC(CHIPS)':
 'VSS52': CDS_PINID='VSS52';
NODE_NAME     J19 121
 '@S9S_MB_2U_LIB.S9S_MB_2U(SCH_1):PAGE100_I175@PURE_QUANTA.SCONN288_ADR50017P130CC(CHIPS)':
 'VSS53': CDS_PINID='VSS53';
NODE_NAME     J19 123
 '@S9S_MB_2U_LIB.S9S_MB_2U(SCH_1):PAGE100_I175@PURE_QUANTA.SCONN288_ADR50017P130CC(CHIPS)':
 'VSS54': CDS_PINID='VSS54';
NODE_NAME     J19 125
 '@S9S_MB_2U_LIB.S9S_MB_2U(SCH_1):PAGE100_I175@PURE_QUANTA.SCONN288_ADR50017P130CC(CHIPS)':
 'VSS55': CDS_PINID='VSS55';
NODE_NAME     J19 128
 '@S9S_MB_2U_LIB.S9S_MB_2U(SCH_1):PAGE100_I175@PURE_QUANTA.SCONN288_ADR50017P130CC(CHIPS)':
 'VSS56': CDS_PINID='VSS56';
NODE_NAME     J19 130
 '@S9S_MB_2U_LIB.S9S_MB_2U(SCH_1):PAGE100_I175@PURE_QUANTA.SCONN288_ADR50017P130CC(CHIPS)':
 'VSS57': CDS_PINID='VSS57';
NODE_NAME     J19 132
 '@S9S_MB_2U_LIB.S9S_MB_2U(SCH_1):PAGE100_I175@PURE_QUANTA.SCONN288_ADR50017P130CC(CHIPS)':
 'VSS58': CDS_PINID='VSS58';
NODE_NAME     J19 134
 '@S9S_MB_2U_LIB.S9S_MB_2U(SCH_1):PAGE100_I175@PURE_QUANTA.SCONN288_ADR50017P130CC(CHIPS)':
 'VSS59': CDS_PINID='VSS59';
NODE_NAME     J19 136
 '@S9S_MB_2U_LIB.S9S_MB_2U(SCH_1):PAGE100_I175@PURE_QUANTA.SCONN288_ADR50017P130CC(CHIPS)':
 'VSS60': CDS_PINID='VSS60';
NODE_NAME     J19 139
 '@S9S_MB_2U_LIB.S9S_MB_2U(SCH_1):PAGE100_I175@PURE_QUANTA.SCONN288_ADR50017P130CC(CHIPS)':
 'VSS61': CDS_PINID='VSS61';
NODE_NAME     J19 141
 '@S9S_MB_2U_LIB.S9S_MB_2U(SCH_1):PAGE100_I175@PURE_QUANTA.SCONN288_ADR50017P130CC(CHIPS)':
 'VSS62': CDS_PINID='VSS62';
NODE_NAME     J19 143
 '@S9S_MB_2U_LIB.S9S_MB_2U(SCH_1):PAGE100_I175@PURE_QUANTA.SCONN288_ADR50017P130CC(CHIPS)':
 'VSS63': CDS_PINID='VSS63';
NODE_NAME     J19 151
 '@S9S_MB_2U_LIB.S9S_MB_2U(SCH_1):PAGE100_I175@PURE_QUANTA.SCONN288_ADR50017P130CC(CHIPS)':
 'VSS64': CDS_PINID='VSS64';
NODE_NAME     J19 153
 '@S9S_MB_2U_LIB.S9S_MB_2U(SCH_1):PAGE100_I175@PURE_QUANTA.SCONN288_ADR50017P130CC(CHIPS)':
 'VSS65': CDS_PINID='VSS65';
NODE_NAME     J19 155
 '@S9S_MB_2U_LIB.S9S_MB_2U(SCH_1):PAGE100_I175@PURE_QUANTA.SCONN288_ADR50017P130CC(CHIPS)':
 'VSS66': CDS_PINID='VSS66';
NODE_NAME     J19 158
 '@S9S_MB_2U_LIB.S9S_MB_2U(SCH_1):PAGE100_I175@PURE_QUANTA.SCONN288_ADR50017P130CC(CHIPS)':
 'VSS67': CDS_PINID='VSS67';
NODE_NAME     J19 160
 '@S9S_MB_2U_LIB.S9S_MB_2U(SCH_1):PAGE100_I175@PURE_QUANTA.SCONN288_ADR50017P130CC(CHIPS)':
 'VSS68': CDS_PINID='VSS68';
NODE_NAME     J19 162
 '@S9S_MB_2U_LIB.S9S_MB_2U(SCH_1):PAGE100_I175@PURE_QUANTA.SCONN288_ADR50017P130CC(CHIPS)':
 'VSS69': CDS_PINID='VSS69';
NODE_NAME     J19 164
 '@S9S_MB_2U_LIB.S9S_MB_2U(SCH_1):PAGE100_I175@PURE_QUANTA.SCONN288_ADR50017P130CC(CHIPS)':
 'VSS70': CDS_PINID='VSS70';
NODE_NAME     J19 166
 '@S9S_MB_2U_LIB.S9S_MB_2U(SCH_1):PAGE100_I175@PURE_QUANTA.SCONN288_ADR50017P130CC(CHIPS)':
 'VSS71': CDS_PINID='VSS71';
NODE_NAME     J19 169
 '@S9S_MB_2U_LIB.S9S_MB_2U(SCH_1):PAGE100_I175@PURE_QUANTA.SCONN288_ADR50017P130CC(CHIPS)':
 'VSS72': CDS_PINID='VSS72';
NODE_NAME     J19 171
 '@S9S_MB_2U_LIB.S9S_MB_2U(SCH_1):PAGE100_I175@PURE_QUANTA.SCONN288_ADR50017P130CC(CHIPS)':
 'VSS73': CDS_PINID='VSS73';
NODE_NAME     J19 173
 '@S9S_MB_2U_LIB.S9S_MB_2U(SCH_1):PAGE100_I175@PURE_QUANTA.SCONN288_ADR50017P130CC(CHIPS)':
 'VSS74': CDS_PINID='VSS74';
NODE_NAME     J19 175
 '@S9S_MB_2U_LIB.S9S_MB_2U(SCH_1):PAGE100_I175@PURE_QUANTA.SCONN288_ADR50017P130CC(CHIPS)':
 'VSS75': CDS_PINID='VSS75';
NODE_NAME     J19 177
 '@S9S_MB_2U_LIB.S9S_MB_2U(SCH_1):PAGE100_I175@PURE_QUANTA.SCONN288_ADR50017P130CC(CHIPS)':
 'VSS76': CDS_PINID='VSS76';
NODE_NAME     J19 180
 '@S9S_MB_2U_LIB.S9S_MB_2U(SCH_1):PAGE100_I175@PURE_QUANTA.SCONN288_ADR50017P130CC(CHIPS)':
 'VSS77': CDS_PINID='VSS77';
NODE_NAME     J19 182
 '@S9S_MB_2U_LIB.S9S_MB_2U(SCH_1):PAGE100_I175@PURE_QUANTA.SCONN288_ADR50017P130CC(CHIPS)':
 'VSS78': CDS_PINID='VSS78';
NODE_NAME     J19 184
 '@S9S_MB_2U_LIB.S9S_MB_2U(SCH_1):PAGE100_I175@PURE_QUANTA.SCONN288_ADR50017P130CC(CHIPS)':
 'VSS79': CDS_PINID='VSS79';
NODE_NAME     J19 186
 '@S9S_MB_2U_LIB.S9S_MB_2U(SCH_1):PAGE100_I175@PURE_QUANTA.SCONN288_ADR50017P130CC(CHIPS)':
 'VSS80': CDS_PINID='VSS80';
NODE_NAME     J19 188
 '@S9S_MB_2U_LIB.S9S_MB_2U(SCH_1):PAGE100_I175@PURE_QUANTA.SCONN288_ADR50017P130CC(CHIPS)':
 'VSS81': CDS_PINID='VSS81';
NODE_NAME     J19 191
 '@S9S_MB_2U_LIB.S9S_MB_2U(SCH_1):PAGE100_I175@PURE_QUANTA.SCONN288_ADR50017P130CC(CHIPS)':
 'VSS82': CDS_PINID='VSS82';
NODE_NAME     J19 193
 '@S9S_MB_2U_LIB.S9S_MB_2U(SCH_1):PAGE100_I175@PURE_QUANTA.SCONN288_ADR50017P130CC(CHIPS)':
 'VSS83': CDS_PINID='VSS83';
NODE_NAME     J19 195
 '@S9S_MB_2U_LIB.S9S_MB_2U(SCH_1):PAGE100_I175@PURE_QUANTA.SCONN288_ADR50017P130CC(CHIPS)':
 'VSS84': CDS_PINID='VSS84';
NODE_NAME     J19 197
 '@S9S_MB_2U_LIB.S9S_MB_2U(SCH_1):PAGE100_I175@PURE_QUANTA.SCONN288_ADR50017P130CC(CHIPS)':
 'VSS85': CDS_PINID='VSS85';
NODE_NAME     J19 199
 '@S9S_MB_2U_LIB.S9S_MB_2U(SCH_1):PAGE100_I175@PURE_QUANTA.SCONN288_ADR50017P130CC(CHIPS)':
 'VSS86': CDS_PINID='VSS86';
NODE_NAME     J19 202
 '@S9S_MB_2U_LIB.S9S_MB_2U(SCH_1):PAGE100_I175@PURE_QUANTA.SCONN288_ADR50017P130CC(CHIPS)':
 'VSS87': CDS_PINID='VSS87';
NODE_NAME     J19 204
 '@S9S_MB_2U_LIB.S9S_MB_2U(SCH_1):PAGE100_I175@PURE_QUANTA.SCONN288_ADR50017P130CC(CHIPS)':
 'VSS88': CDS_PINID='VSS88';
NODE_NAME     J19 206
 '@S9S_MB_2U_LIB.S9S_MB_2U(SCH_1):PAGE100_I175@PURE_QUANTA.SCONN288_ADR50017P130CC(CHIPS)':
 'VSS89': CDS_PINID='VSS89';
NODE_NAME     J19 208
 '@S9S_MB_2U_LIB.S9S_MB_2U(SCH_1):PAGE100_I175@PURE_QUANTA.SCONN288_ADR50017P130CC(CHIPS)':
 'VSS90': CDS_PINID='VSS90';
NODE_NAME     J19 210
 '@S9S_MB_2U_LIB.S9S_MB_2U(SCH_1):PAGE100_I175@PURE_QUANTA.SCONN288_ADR50017P130CC(CHIPS)':
 'VSS91': CDS_PINID='VSS91';
NODE_NAME     J19 212
 '@S9S_MB_2U_LIB.S9S_MB_2U(SCH_1):PAGE100_I175@PURE_QUANTA.SCONN288_ADR50017P130CC(CHIPS)':
 'VSS92': CDS_PINID='VSS92';
NODE_NAME     J19 214
 '@S9S_MB_2U_LIB.S9S_MB_2U(SCH_1):PAGE100_I175@PURE_QUANTA.SCONN288_ADR50017P130CC(CHIPS)':
 'VSS93': CDS_PINID='VSS93';
NODE_NAME     J19 216
 '@S9S_MB_2U_LIB.S9S_MB_2U(SCH_1):PAGE100_I175@PURE_QUANTA.SCONN288_ADR50017P130CC(CHIPS)':
 'VSS94': CDS_PINID='VSS94';
NODE_NAME     J19 219
 '@S9S_MB_2U_LIB.S9S_MB_2U(SCH_1):PAGE100_I175@PURE_QUANTA.SCONN288_ADR50017P130CC(CHIPS)':
 'VSS95': CDS_PINID='VSS95';
NODE_NAME     J19 222
 '@S9S_MB_2U_LIB.S9S_MB_2U(SCH_1):PAGE100_I175@PURE_QUANTA.SCONN288_ADR50017P130CC(CHIPS)':
 'VSS96': CDS_PINID='VSS96';
NODE_NAME     J19 224
 '@S9S_MB_2U_LIB.S9S_MB_2U(SCH_1):PAGE100_I175@PURE_QUANTA.SCONN288_ADR50017P130CC(CHIPS)':
 'VSS97': CDS_PINID='VSS97';
NODE_NAME     J19 226
 '@S9S_MB_2U_LIB.S9S_MB_2U(SCH_1):PAGE100_I175@PURE_QUANTA.SCONN288_ADR50017P130CC(CHIPS)':
 'VSS98': CDS_PINID='VSS98';
NODE_NAME     J19 228
 '@S9S_MB_2U_LIB.S9S_MB_2U(SCH_1):PAGE100_I175@PURE_QUANTA.SCONN288_ADR50017P130CC(CHIPS)':
 'VSS99': CDS_PINID='VSS99';
NODE_NAME     J19 230
 '@S9S_MB_2U_LIB.S9S_MB_2U(SCH_1):PAGE100_I175@PURE_QUANTA.SCONN288_ADR50017P130CC(CHIPS)':
 'VSS100': CDS_PINID='VSS100';
NODE_NAME     J19 233
 '@S9S_MB_2U_LIB.S9S_MB_2U(SCH_1):PAGE100_I175@PURE_QUANTA.SCONN288_ADR50017P130CC(CHIPS)':
 'VSS101': CDS_PINID='VSS101';
NODE_NAME     J19 235
 '@S9S_MB_2U_LIB.S9S_MB_2U(SCH_1):PAGE100_I175@PURE_QUANTA.SCONN288_ADR50017P130CC(CHIPS)':
 'VSS102': CDS_PINID='VSS102';
NODE_NAME     J19 237
 '@S9S_MB_2U_LIB.S9S_MB_2U(SCH_1):PAGE100_I175@PURE_QUANTA.SCONN288_ADR50017P130CC(CHIPS)':
 'VSS103': CDS_PINID='VSS103';
NODE_NAME     J19 240
 '@S9S_MB_2U_LIB.S9S_MB_2U(SCH_1):PAGE100_I175@PURE_QUANTA.SCONN288_ADR50017P130CC(CHIPS)':
 'VSS104': CDS_PINID='VSS104';
NODE_NAME     J19 242
 '@S9S_MB_2U_LIB.S9S_MB_2U(SCH_1):PAGE100_I175@PURE_QUANTA.SCONN288_ADR50017P130CC(CHIPS)':
 'VSS105': CDS_PINID='VSS105';
NODE_NAME     J19 244
 '@S9S_MB_2U_LIB.S9S_MB_2U(SCH_1):PAGE100_I175@PURE_QUANTA.SCONN288_ADR50017P130CC(CHIPS)':
 'VSS106': CDS_PINID='VSS106';
NODE_NAME     J19 246
 '@S9S_MB_2U_LIB.S9S_MB_2U(SCH_1):PAGE100_I175@PURE_QUANTA.SCONN288_ADR50017P130CC(CHIPS)':
 'VSS107': CDS_PINID='VSS107';
NODE_NAME     J19 248
 '@S9S_MB_2U_LIB.S9S_MB_2U(SCH_1):PAGE100_I175@PURE_QUANTA.SCONN288_ADR50017P130CC(CHIPS)':
 'VSS108': CDS_PINID='VSS108';
NODE_NAME     J19 251
 '@S9S_MB_2U_LIB.S9S_MB_2U(SCH_1):PAGE100_I175@PURE_QUANTA.SCONN288_ADR50017P130CC(CHIPS)':
 'VSS109': CDS_PINID='VSS109';
NODE_NAME     J19 253
 '@S9S_MB_2U_LIB.S9S_MB_2U(SCH_1):PAGE100_I175@PURE_QUANTA.SCONN288_ADR50017P130CC(CHIPS)':
 'VSS110': CDS_PINID='VSS110';
NODE_NAME     J19 255
 '@S9S_MB_2U_LIB.S9S_MB_2U(SCH_1):PAGE100_I175@PURE_QUANTA.SCONN288_ADR50017P130CC(CHIPS)':
 'VSS111': CDS_PINID='VSS111';
NODE_NAME     J19 257
 '@S9S_MB_2U_LIB.S9S_MB_2U(SCH_1):PAGE100_I175@PURE_QUANTA.SCONN288_ADR50017P130CC(CHIPS)':
 'VSS112': CDS_PINID='VSS112';
NODE_NAME     J19 259
 '@S9S_MB_2U_LIB.S9S_MB_2U(SCH_1):PAGE100_I175@PURE_QUANTA.SCONN288_ADR50017P130CC(CHIPS)':
 'VSS113': CDS_PINID='VSS113';
NODE_NAME     J19 262
 '@S9S_MB_2U_LIB.S9S_MB_2U(SCH_1):PAGE100_I175@PURE_QUANTA.SCONN288_ADR50017P130CC(CHIPS)':
 'VSS114': CDS_PINID='VSS114';
NODE_NAME     J19 264
 '@S9S_MB_2U_LIB.S9S_MB_2U(SCH_1):PAGE100_I175@PURE_QUANTA.SCONN288_ADR50017P130CC(CHIPS)':
 'VSS115': CDS_PINID='VSS115';
NODE_NAME     J19 266
 '@S9S_MB_2U_LIB.S9S_MB_2U(SCH_1):PAGE100_I175@PURE_QUANTA.SCONN288_ADR50017P130CC(CHIPS)':
 'VSS116': CDS_PINID='VSS116';
NODE_NAME     J19 268
 '@S9S_MB_2U_LIB.S9S_MB_2U(SCH_1):PAGE100_I175@PURE_QUANTA.SCONN288_ADR50017P130CC(CHIPS)':
 'VSS117': CDS_PINID='VSS117';
NODE_NAME     J19 270
 '@S9S_MB_2U_LIB.S9S_MB_2U(SCH_1):PAGE100_I175@PURE_QUANTA.SCONN288_ADR50017P130CC(CHIPS)':
 'VSS118': CDS_PINID='VSS118';
NODE_NAME     J19 273
 '@S9S_MB_2U_LIB.S9S_MB_2U(SCH_1):PAGE100_I175@PURE_QUANTA.SCONN288_ADR50017P130CC(CHIPS)':
 'VSS119': CDS_PINID='VSS119';
NODE_NAME     J19 275
 '@S9S_MB_2U_LIB.S9S_MB_2U(SCH_1):PAGE100_I175@PURE_QUANTA.SCONN288_ADR50017P130CC(CHIPS)':
 'VSS120': CDS_PINID='VSS120';
NODE_NAME     J19 277
 '@S9S_MB_2U_LIB.S9S_MB_2U(SCH_1):PAGE100_I175@PURE_QUANTA.SCONN288_ADR50017P130CC(CHIPS)':
 'VSS121': CDS_PINID='VSS121';
NODE_NAME     J19 279
 '@S9S_MB_2U_LIB.S9S_MB_2U(SCH_1):PAGE100_I175@PURE_QUANTA.SCONN288_ADR50017P130CC(CHIPS)':
 'VSS122': CDS_PINID='VSS122';
NODE_NAME     J19 281
 '@S9S_MB_2U_LIB.S9S_MB_2U(SCH_1):PAGE100_I175@PURE_QUANTA.SCONN288_ADR50017P130CC(CHIPS)':
 'VSS123': CDS_PINID='VSS123';
NODE_NAME     J19 284
 '@S9S_MB_2U_LIB.S9S_MB_2U(SCH_1):PAGE100_I175@PURE_QUANTA.SCONN288_ADR50017P130CC(CHIPS)':
 'VSS124': CDS_PINID='VSS124';
NODE_NAME     J19 286
 '@S9S_MB_2U_LIB.S9S_MB_2U(SCH_1):PAGE100_I175@PURE_QUANTA.SCONN288_ADR50017P130CC(CHIPS)':
 'VSS125': CDS_PINID='VSS125';
NODE_NAME     J19 288
 '@S9S_MB_2U_LIB.S9S_MB_2U(SCH_1):PAGE100_I175@PURE_QUANTA.SCONN288_ADR50017P130CC(CHIPS)':
 'VSS126': CDS_PINID='VSS126';
NODE_NAME     R45 2
 '@S9S_MB_2U_LIB.S9S_MB_2U(SCH_1):PAGE101_I46@PURE_QUANTA.Q_RES(CHIPS)':
 'B': CDS_PINID='B';
NODE_NAME     C59 2
 '@S9S_MB_2U_LIB.S9S_MB_2U(SCH_1):PAGE101_I121@PURE_QUANTA.Q_CAP(CHIPS)':
 'B': CDS_PINID='B';
NODE_NAME     C60 2
 '@S9S_MB_2U_LIB.S9S_MB_2U(SCH_1):PAGE101_I125@PURE_QUANTA.Q_CAP(CHIPS)':
 'B': CDS_PINID='B';
NODE_NAME     C61 2
 '@S9S_MB_2U_LIB.S9S_MB_2U(SCH_1):PAGE101_I127@PURE_QUANTA.Q_CAP(CHIPS)':
 'B': CDS_PINID='B';
NODE_NAME     J20 G1
 '@S9S_MB_2U_LIB.S9S_MB_2U(SCH_1):PAGE101_I176@PURE_QUANTA.SCONN288_ADR50017P087CC(CHIPS)':
 'G1': CDS_PINID='G1';
NODE_NAME     J20 G2
 '@S9S_MB_2U_LIB.S9S_MB_2U(SCH_1):PAGE101_I176@PURE_QUANTA.SCONN288_ADR50017P087CC(CHIPS)':
 'G2': CDS_PINID='G2';
NODE_NAME     J20 G3
 '@S9S_MB_2U_LIB.S9S_MB_2U(SCH_1):PAGE101_I176@PURE_QUANTA.SCONN288_ADR50017P087CC(CHIPS)':
 'G3': CDS_PINID='G3';
NODE_NAME     J20 6
 '@S9S_MB_2U_LIB.S9S_MB_2U(SCH_1):PAGE101_I176@PURE_QUANTA.SCONN288_ADR50017P087CC(CHIPS)':
 'VSS0': CDS_PINID='VSS0';
NODE_NAME     J20 8
 '@S9S_MB_2U_LIB.S9S_MB_2U(SCH_1):PAGE101_I176@PURE_QUANTA.SCONN288_ADR50017P087CC(CHIPS)':
 'VSS1': CDS_PINID='VSS1';
NODE_NAME     J20 10
 '@S9S_MB_2U_LIB.S9S_MB_2U(SCH_1):PAGE101_I176@PURE_QUANTA.SCONN288_ADR50017P087CC(CHIPS)':
 'VSS2': CDS_PINID='VSS2';
NODE_NAME     J20 13
 '@S9S_MB_2U_LIB.S9S_MB_2U(SCH_1):PAGE101_I176@PURE_QUANTA.SCONN288_ADR50017P087CC(CHIPS)':
 'VSS3': CDS_PINID='VSS3';
NODE_NAME     J20 15
 '@S9S_MB_2U_LIB.S9S_MB_2U(SCH_1):PAGE101_I176@PURE_QUANTA.SCONN288_ADR50017P087CC(CHIPS)':
 'VSS4': CDS_PINID='VSS4';
NODE_NAME     J20 17
 '@S9S_MB_2U_LIB.S9S_MB_2U(SCH_1):PAGE101_I176@PURE_QUANTA.SCONN288_ADR50017P087CC(CHIPS)':
 'VSS5': CDS_PINID='VSS5';
NODE_NAME     J20 19
 '@S9S_MB_2U_LIB.S9S_MB_2U(SCH_1):PAGE101_I176@PURE_QUANTA.SCONN288_ADR50017P087CC(CHIPS)':
 'VSS6': CDS_PINID='VSS6';
NODE_NAME     J20 21
 '@S9S_MB_2U_LIB.S9S_MB_2U(SCH_1):PAGE101_I176@PURE_QUANTA.SCONN288_ADR50017P087CC(CHIPS)':
 'VSS7': CDS_PINID='VSS7';
NODE_NAME     J20 24
 '@S9S_MB_2U_LIB.S9S_MB_2U(SCH_1):PAGE101_I176@PURE_QUANTA.SCONN288_ADR50017P087CC(CHIPS)':
 'VSS8': CDS_PINID='VSS8';
NODE_NAME     J20 26
 '@S9S_MB_2U_LIB.S9S_MB_2U(SCH_1):PAGE101_I176@PURE_QUANTA.SCONN288_ADR50017P087CC(CHIPS)':
 'VSS9': CDS_PINID='VSS9';
NODE_NAME     J20 28
 '@S9S_MB_2U_LIB.S9S_MB_2U(SCH_1):PAGE101_I176@PURE_QUANTA.SCONN288_ADR50017P087CC(CHIPS)':
 'VSS10': CDS_PINID='VSS10';
NODE_NAME     J20 30
 '@S9S_MB_2U_LIB.S9S_MB_2U(SCH_1):PAGE101_I176@PURE_QUANTA.SCONN288_ADR50017P087CC(CHIPS)':
 'VSS11': CDS_PINID='VSS11';
NODE_NAME     J20 32
 '@S9S_MB_2U_LIB.S9S_MB_2U(SCH_1):PAGE101_I176@PURE_QUANTA.SCONN288_ADR50017P087CC(CHIPS)':
 'VSS12': CDS_PINID='VSS12';
NODE_NAME     J20 35
 '@S9S_MB_2U_LIB.S9S_MB_2U(SCH_1):PAGE101_I176@PURE_QUANTA.SCONN288_ADR50017P087CC(CHIPS)':
 'VSS13': CDS_PINID='VSS13';
NODE_NAME     J20 37
 '@S9S_MB_2U_LIB.S9S_MB_2U(SCH_1):PAGE101_I176@PURE_QUANTA.SCONN288_ADR50017P087CC(CHIPS)':
 'VSS14': CDS_PINID='VSS14';
NODE_NAME     J20 39
 '@S9S_MB_2U_LIB.S9S_MB_2U(SCH_1):PAGE101_I176@PURE_QUANTA.SCONN288_ADR50017P087CC(CHIPS)':
 'VSS15': CDS_PINID='VSS15';
NODE_NAME     J20 41
 '@S9S_MB_2U_LIB.S9S_MB_2U(SCH_1):PAGE101_I176@PURE_QUANTA.SCONN288_ADR50017P087CC(CHIPS)':
 'VSS16': CDS_PINID='VSS16';
NODE_NAME     J20 43
 '@S9S_MB_2U_LIB.S9S_MB_2U(SCH_1):PAGE101_I176@PURE_QUANTA.SCONN288_ADR50017P087CC(CHIPS)':
 'VSS17': CDS_PINID='VSS17';
NODE_NAME     J20 46
 '@S9S_MB_2U_LIB.S9S_MB_2U(SCH_1):PAGE101_I176@PURE_QUANTA.SCONN288_ADR50017P087CC(CHIPS)':
 'VSS18': CDS_PINID='VSS18';
NODE_NAME     J20 48
 '@S9S_MB_2U_LIB.S9S_MB_2U(SCH_1):PAGE101_I176@PURE_QUANTA.SCONN288_ADR50017P087CC(CHIPS)':
 'VSS19': CDS_PINID='VSS19';
NODE_NAME     J20 50
 '@S9S_MB_2U_LIB.S9S_MB_2U(SCH_1):PAGE101_I176@PURE_QUANTA.SCONN288_ADR50017P087CC(CHIPS)':
 'VSS20': CDS_PINID='VSS20';
NODE_NAME     J20 52
 '@S9S_MB_2U_LIB.S9S_MB_2U(SCH_1):PAGE101_I176@PURE_QUANTA.SCONN288_ADR50017P087CC(CHIPS)':
 'VSS21': CDS_PINID='VSS21';
NODE_NAME     J20 54
 '@S9S_MB_2U_LIB.S9S_MB_2U(SCH_1):PAGE101_I176@PURE_QUANTA.SCONN288_ADR50017P087CC(CHIPS)':
 'VSS22': CDS_PINID='VSS22';
NODE_NAME     J20 57
 '@S9S_MB_2U_LIB.S9S_MB_2U(SCH_1):PAGE101_I176@PURE_QUANTA.SCONN288_ADR50017P087CC(CHIPS)':
 'VSS23': CDS_PINID='VSS23';
NODE_NAME     J20 59
 '@S9S_MB_2U_LIB.S9S_MB_2U(SCH_1):PAGE101_I176@PURE_QUANTA.SCONN288_ADR50017P087CC(CHIPS)':
 'VSS24': CDS_PINID='VSS24';
NODE_NAME     J20 61
 '@S9S_MB_2U_LIB.S9S_MB_2U(SCH_1):PAGE101_I176@PURE_QUANTA.SCONN288_ADR50017P087CC(CHIPS)':
 'VSS25': CDS_PINID='VSS25';
NODE_NAME     J20 63
 '@S9S_MB_2U_LIB.S9S_MB_2U(SCH_1):PAGE101_I176@PURE_QUANTA.SCONN288_ADR50017P087CC(CHIPS)':
 'VSS26': CDS_PINID='VSS26';
NODE_NAME     J20 65
 '@S9S_MB_2U_LIB.S9S_MB_2U(SCH_1):PAGE101_I176@PURE_QUANTA.SCONN288_ADR50017P087CC(CHIPS)':
 'VSS27': CDS_PINID='VSS27';
NODE_NAME     J20 67
 '@S9S_MB_2U_LIB.S9S_MB_2U(SCH_1):PAGE101_I176@PURE_QUANTA.SCONN288_ADR50017P087CC(CHIPS)':
 'VSS28': CDS_PINID='VSS28';
NODE_NAME     J20 69
 '@S9S_MB_2U_LIB.S9S_MB_2U(SCH_1):PAGE101_I176@PURE_QUANTA.SCONN288_ADR50017P087CC(CHIPS)':
 'VSS29': CDS_PINID='VSS29';
NODE_NAME     J20 71
 '@S9S_MB_2U_LIB.S9S_MB_2U(SCH_1):PAGE101_I176@PURE_QUANTA.SCONN288_ADR50017P087CC(CHIPS)':
 'VSS30': CDS_PINID='VSS30';
NODE_NAME     J20 73
 '@S9S_MB_2U_LIB.S9S_MB_2U(SCH_1):PAGE101_I176@PURE_QUANTA.SCONN288_ADR50017P087CC(CHIPS)':
 'VSS31': CDS_PINID='VSS31';
NODE_NAME     J20 75
 '@S9S_MB_2U_LIB.S9S_MB_2U(SCH_1):PAGE101_I176@PURE_QUANTA.SCONN288_ADR50017P087CC(CHIPS)':
 'VSS32': CDS_PINID='VSS32';
NODE_NAME     J20 77
 '@S9S_MB_2U_LIB.S9S_MB_2U(SCH_1):PAGE101_I176@PURE_QUANTA.SCONN288_ADR50017P087CC(CHIPS)':
 'VSS33': CDS_PINID='VSS33';
NODE_NAME     J20 79
 '@S9S_MB_2U_LIB.S9S_MB_2U(SCH_1):PAGE101_I176@PURE_QUANTA.SCONN288_ADR50017P087CC(CHIPS)':
 'VSS34': CDS_PINID='VSS34';
NODE_NAME     J20 81
 '@S9S_MB_2U_LIB.S9S_MB_2U(SCH_1):PAGE101_I176@PURE_QUANTA.SCONN288_ADR50017P087CC(CHIPS)':
 'VSS35': CDS_PINID='VSS35';
NODE_NAME     J20 83
 '@S9S_MB_2U_LIB.S9S_MB_2U(SCH_1):PAGE101_I176@PURE_QUANTA.SCONN288_ADR50017P087CC(CHIPS)':
 'VSS36': CDS_PINID='VSS36';
NODE_NAME     J20 85
 '@S9S_MB_2U_LIB.S9S_MB_2U(SCH_1):PAGE101_I176@PURE_QUANTA.SCONN288_ADR50017P087CC(CHIPS)':
 'VSS37': CDS_PINID='VSS37';
NODE_NAME     J20 88
 '@S9S_MB_2U_LIB.S9S_MB_2U(SCH_1):PAGE101_I176@PURE_QUANTA.SCONN288_ADR50017P087CC(CHIPS)':
 'VSS38': CDS_PINID='VSS38';
NODE_NAME     J20 90
 '@S9S_MB_2U_LIB.S9S_MB_2U(SCH_1):PAGE101_I176@PURE_QUANTA.SCONN288_ADR50017P087CC(CHIPS)':
 'VSS39': CDS_PINID='VSS39';
NODE_NAME     J20 92
 '@S9S_MB_2U_LIB.S9S_MB_2U(SCH_1):PAGE101_I176@PURE_QUANTA.SCONN288_ADR50017P087CC(CHIPS)':
 'VSS40': CDS_PINID='VSS40';
NODE_NAME     J20 95
 '@S9S_MB_2U_LIB.S9S_MB_2U(SCH_1):PAGE101_I176@PURE_QUANTA.SCONN288_ADR50017P087CC(CHIPS)':
 'VSS41': CDS_PINID='VSS41';
NODE_NAME     J20 97
 '@S9S_MB_2U_LIB.S9S_MB_2U(SCH_1):PAGE101_I176@PURE_QUANTA.SCONN288_ADR50017P087CC(CHIPS)':
 'VSS42': CDS_PINID='VSS42';
NODE_NAME     J20 99
 '@S9S_MB_2U_LIB.S9S_MB_2U(SCH_1):PAGE101_I176@PURE_QUANTA.SCONN288_ADR50017P087CC(CHIPS)':
 'VSS43': CDS_PINID='VSS43';
NODE_NAME     J20 101
 '@S9S_MB_2U_LIB.S9S_MB_2U(SCH_1):PAGE101_I176@PURE_QUANTA.SCONN288_ADR50017P087CC(CHIPS)':
 'VSS44': CDS_PINID='VSS44';
NODE_NAME     J20 103
 '@S9S_MB_2U_LIB.S9S_MB_2U(SCH_1):PAGE101_I176@PURE_QUANTA.SCONN288_ADR50017P087CC(CHIPS)':
 'VSS45': CDS_PINID='VSS45';
NODE_NAME     J20 106
 '@S9S_MB_2U_LIB.S9S_MB_2U(SCH_1):PAGE101_I176@PURE_QUANTA.SCONN288_ADR50017P087CC(CHIPS)':
 'VSS46': CDS_PINID='VSS46';
NODE_NAME     J20 108
 '@S9S_MB_2U_LIB.S9S_MB_2U(SCH_1):PAGE101_I176@PURE_QUANTA.SCONN288_ADR50017P087CC(CHIPS)':
 'VSS47': CDS_PINID='VSS47';
NODE_NAME     J20 110
 '@S9S_MB_2U_LIB.S9S_MB_2U(SCH_1):PAGE101_I176@PURE_QUANTA.SCONN288_ADR50017P087CC(CHIPS)':
 'VSS48': CDS_PINID='VSS48';
NODE_NAME     J20 112
 '@S9S_MB_2U_LIB.S9S_MB_2U(SCH_1):PAGE101_I176@PURE_QUANTA.SCONN288_ADR50017P087CC(CHIPS)':
 'VSS49': CDS_PINID='VSS49';
NODE_NAME     J20 114
 '@S9S_MB_2U_LIB.S9S_MB_2U(SCH_1):PAGE101_I176@PURE_QUANTA.SCONN288_ADR50017P087CC(CHIPS)':
 'VSS50': CDS_PINID='VSS50';
NODE_NAME     J20 117
 '@S9S_MB_2U_LIB.S9S_MB_2U(SCH_1):PAGE101_I176@PURE_QUANTA.SCONN288_ADR50017P087CC(CHIPS)':
 'VSS51': CDS_PINID='VSS51';
NODE_NAME     J20 119
 '@S9S_MB_2U_LIB.S9S_MB_2U(SCH_1):PAGE101_I176@PURE_QUANTA.SCONN288_ADR50017P087CC(CHIPS)':
 'VSS52': CDS_PINID='VSS52';
NODE_NAME     J20 121
 '@S9S_MB_2U_LIB.S9S_MB_2U(SCH_1):PAGE101_I176@PURE_QUANTA.SCONN288_ADR50017P087CC(CHIPS)':
 'VSS53': CDS_PINID='VSS53';
NODE_NAME     J20 123
 '@S9S_MB_2U_LIB.S9S_MB_2U(SCH_1):PAGE101_I176@PURE_QUANTA.SCONN288_ADR50017P087CC(CHIPS)':
 'VSS54': CDS_PINID='VSS54';
NODE_NAME     J20 125
 '@S9S_MB_2U_LIB.S9S_MB_2U(SCH_1):PAGE101_I176@PURE_QUANTA.SCONN288_ADR50017P087CC(CHIPS)':
 'VSS55': CDS_PINID='VSS55';
NODE_NAME     J20 128
 '@S9S_MB_2U_LIB.S9S_MB_2U(SCH_1):PAGE101_I176@PURE_QUANTA.SCONN288_ADR50017P087CC(CHIPS)':
 'VSS56': CDS_PINID='VSS56';
NODE_NAME     J20 130
 '@S9S_MB_2U_LIB.S9S_MB_2U(SCH_1):PAGE101_I176@PURE_QUANTA.SCONN288_ADR50017P087CC(CHIPS)':
 'VSS57': CDS_PINID='VSS57';
NODE_NAME     J20 132
 '@S9S_MB_2U_LIB.S9S_MB_2U(SCH_1):PAGE101_I176@PURE_QUANTA.SCONN288_ADR50017P087CC(CHIPS)':
 'VSS58': CDS_PINID='VSS58';
NODE_NAME     J20 134
 '@S9S_MB_2U_LIB.S9S_MB_2U(SCH_1):PAGE101_I176@PURE_QUANTA.SCONN288_ADR50017P087CC(CHIPS)':
 'VSS59': CDS_PINID='VSS59';
NODE_NAME     J20 136
 '@S9S_MB_2U_LIB.S9S_MB_2U(SCH_1):PAGE101_I176@PURE_QUANTA.SCONN288_ADR50017P087CC(CHIPS)':
 'VSS60': CDS_PINID='VSS60';
NODE_NAME     J20 139
 '@S9S_MB_2U_LIB.S9S_MB_2U(SCH_1):PAGE101_I176@PURE_QUANTA.SCONN288_ADR50017P087CC(CHIPS)':
 'VSS61': CDS_PINID='VSS61';
NODE_NAME     J20 141
 '@S9S_MB_2U_LIB.S9S_MB_2U(SCH_1):PAGE101_I176@PURE_QUANTA.SCONN288_ADR50017P087CC(CHIPS)':
 'VSS62': CDS_PINID='VSS62';
NODE_NAME     J20 143
 '@S9S_MB_2U_LIB.S9S_MB_2U(SCH_1):PAGE101_I176@PURE_QUANTA.SCONN288_ADR50017P087CC(CHIPS)':
 'VSS63': CDS_PINID='VSS63';
NODE_NAME     J20 151
 '@S9S_MB_2U_LIB.S9S_MB_2U(SCH_1):PAGE101_I176@PURE_QUANTA.SCONN288_ADR50017P087CC(CHIPS)':
 'VSS64': CDS_PINID='VSS64';
NODE_NAME     J20 153
 '@S9S_MB_2U_LIB.S9S_MB_2U(SCH_1):PAGE101_I176@PURE_QUANTA.SCONN288_ADR50017P087CC(CHIPS)':
 'VSS65': CDS_PINID='VSS65';
NODE_NAME     J20 155
 '@S9S_MB_2U_LIB.S9S_MB_2U(SCH_1):PAGE101_I176@PURE_QUANTA.SCONN288_ADR50017P087CC(CHIPS)':
 'VSS66': CDS_PINID='VSS66';
NODE_NAME     J20 158
 '@S9S_MB_2U_LIB.S9S_MB_2U(SCH_1):PAGE101_I176@PURE_QUANTA.SCONN288_ADR50017P087CC(CHIPS)':
 'VSS67': CDS_PINID='VSS67';
NODE_NAME     J20 160
 '@S9S_MB_2U_LIB.S9S_MB_2U(SCH_1):PAGE101_I176@PURE_QUANTA.SCONN288_ADR50017P087CC(CHIPS)':
 'VSS68': CDS_PINID='VSS68';
NODE_NAME     J20 162
 '@S9S_MB_2U_LIB.S9S_MB_2U(SCH_1):PAGE101_I176@PURE_QUANTA.SCONN288_ADR50017P087CC(CHIPS)':
 'VSS69': CDS_PINID='VSS69';
NODE_NAME     J20 164
 '@S9S_MB_2U_LIB.S9S_MB_2U(SCH_1):PAGE101_I176@PURE_QUANTA.SCONN288_ADR50017P087CC(CHIPS)':
 'VSS70': CDS_PINID='VSS70';
NODE_NAME     J20 166
 '@S9S_MB_2U_LIB.S9S_MB_2U(SCH_1):PAGE101_I176@PURE_QUANTA.SCONN288_ADR50017P087CC(CHIPS)':
 'VSS71': CDS_PINID='VSS71';
NODE_NAME     J20 169
 '@S9S_MB_2U_LIB.S9S_MB_2U(SCH_1):PAGE101_I176@PURE_QUANTA.SCONN288_ADR50017P087CC(CHIPS)':
 'VSS72': CDS_PINID='VSS72';
NODE_NAME     J20 171
 '@S9S_MB_2U_LIB.S9S_MB_2U(SCH_1):PAGE101_I176@PURE_QUANTA.SCONN288_ADR50017P087CC(CHIPS)':
 'VSS73': CDS_PINID='VSS73';
NODE_NAME     J20 173
 '@S9S_MB_2U_LIB.S9S_MB_2U(SCH_1):PAGE101_I176@PURE_QUANTA.SCONN288_ADR50017P087CC(CHIPS)':
 'VSS74': CDS_PINID='VSS74';
NODE_NAME     J20 175
 '@S9S_MB_2U_LIB.S9S_MB_2U(SCH_1):PAGE101_I176@PURE_QUANTA.SCONN288_ADR50017P087CC(CHIPS)':
 'VSS75': CDS_PINID='VSS75';
NODE_NAME     J20 177
 '@S9S_MB_2U_LIB.S9S_MB_2U(SCH_1):PAGE101_I176@PURE_QUANTA.SCONN288_ADR50017P087CC(CHIPS)':
 'VSS76': CDS_PINID='VSS76';
NODE_NAME     J20 180
 '@S9S_MB_2U_LIB.S9S_MB_2U(SCH_1):PAGE101_I176@PURE_QUANTA.SCONN288_ADR50017P087CC(CHIPS)':
 'VSS77': CDS_PINID='VSS77';
NODE_NAME     J20 182
 '@S9S_MB_2U_LIB.S9S_MB_2U(SCH_1):PAGE101_I176@PURE_QUANTA.SCONN288_ADR50017P087CC(CHIPS)':
 'VSS78': CDS_PINID='VSS78';
NODE_NAME     J20 184
 '@S9S_MB_2U_LIB.S9S_MB_2U(SCH_1):PAGE101_I176@PURE_QUANTA.SCONN288_ADR50017P087CC(CHIPS)':
 'VSS79': CDS_PINID='VSS79';
NODE_NAME     J20 186
 '@S9S_MB_2U_LIB.S9S_MB_2U(SCH_1):PAGE101_I176@PURE_QUANTA.SCONN288_ADR50017P087CC(CHIPS)':
 'VSS80': CDS_PINID='VSS80';
NODE_NAME     J20 188
 '@S9S_MB_2U_LIB.S9S_MB_2U(SCH_1):PAGE101_I176@PURE_QUANTA.SCONN288_ADR50017P087CC(CHIPS)':
 'VSS81': CDS_PINID='VSS81';
NODE_NAME     J20 191
 '@S9S_MB_2U_LIB.S9S_MB_2U(SCH_1):PAGE101_I176@PURE_QUANTA.SCONN288_ADR50017P087CC(CHIPS)':
 'VSS82': CDS_PINID='VSS82';
NODE_NAME     J20 193
 '@S9S_MB_2U_LIB.S9S_MB_2U(SCH_1):PAGE101_I176@PURE_QUANTA.SCONN288_ADR50017P087CC(CHIPS)':
 'VSS83': CDS_PINID='VSS83';
NODE_NAME     J20 195
 '@S9S_MB_2U_LIB.S9S_MB_2U(SCH_1):PAGE101_I176@PURE_QUANTA.SCONN288_ADR50017P087CC(CHIPS)':
 'VSS84': CDS_PINID='VSS84';
NODE_NAME     J20 197
 '@S9S_MB_2U_LIB.S9S_MB_2U(SCH_1):PAGE101_I176@PURE_QUANTA.SCONN288_ADR50017P087CC(CHIPS)':
 'VSS85': CDS_PINID='VSS85';
NODE_NAME     J20 199
 '@S9S_MB_2U_LIB.S9S_MB_2U(SCH_1):PAGE101_I176@PURE_QUANTA.SCONN288_ADR50017P087CC(CHIPS)':
 'VSS86': CDS_PINID='VSS86';
NODE_NAME     J20 202
 '@S9S_MB_2U_LIB.S9S_MB_2U(SCH_1):PAGE101_I176@PURE_QUANTA.SCONN288_ADR50017P087CC(CHIPS)':
 'VSS87': CDS_PINID='VSS87';
NODE_NAME     J20 204
 '@S9S_MB_2U_LIB.S9S_MB_2U(SCH_1):PAGE101_I176@PURE_QUANTA.SCONN288_ADR50017P087CC(CHIPS)':
 'VSS88': CDS_PINID='VSS88';
NODE_NAME     J20 206
 '@S9S_MB_2U_LIB.S9S_MB_2U(SCH_1):PAGE101_I176@PURE_QUANTA.SCONN288_ADR50017P087CC(CHIPS)':
 'VSS89': CDS_PINID='VSS89';
NODE_NAME     J20 208
 '@S9S_MB_2U_LIB.S9S_MB_2U(SCH_1):PAGE101_I176@PURE_QUANTA.SCONN288_ADR50017P087CC(CHIPS)':
 'VSS90': CDS_PINID='VSS90';
NODE_NAME     J20 210
 '@S9S_MB_2U_LIB.S9S_MB_2U(SCH_1):PAGE101_I176@PURE_QUANTA.SCONN288_ADR50017P087CC(CHIPS)':
 'VSS91': CDS_PINID='VSS91';
NODE_NAME     J20 212
 '@S9S_MB_2U_LIB.S9S_MB_2U(SCH_1):PAGE101_I176@PURE_QUANTA.SCONN288_ADR50017P087CC(CHIPS)':
 'VSS92': CDS_PINID='VSS92';
NODE_NAME     J20 214
 '@S9S_MB_2U_LIB.S9S_MB_2U(SCH_1):PAGE101_I176@PURE_QUANTA.SCONN288_ADR50017P087CC(CHIPS)':
 'VSS93': CDS_PINID='VSS93';
NODE_NAME     J20 216
 '@S9S_MB_2U_LIB.S9S_MB_2U(SCH_1):PAGE101_I176@PURE_QUANTA.SCONN288_ADR50017P087CC(CHIPS)':
 'VSS94': CDS_PINID='VSS94';
NODE_NAME     J20 219
 '@S9S_MB_2U_LIB.S9S_MB_2U(SCH_1):PAGE101_I176@PURE_QUANTA.SCONN288_ADR50017P087CC(CHIPS)':
 'VSS95': CDS_PINID='VSS95';
NODE_NAME     J20 222
 '@S9S_MB_2U_LIB.S9S_MB_2U(SCH_1):PAGE101_I176@PURE_QUANTA.SCONN288_ADR50017P087CC(CHIPS)':
 'VSS96': CDS_PINID='VSS96';
NODE_NAME     J20 224
 '@S9S_MB_2U_LIB.S9S_MB_2U(SCH_1):PAGE101_I176@PURE_QUANTA.SCONN288_ADR50017P087CC(CHIPS)':
 'VSS97': CDS_PINID='VSS97';
NODE_NAME     J20 226
 '@S9S_MB_2U_LIB.S9S_MB_2U(SCH_1):PAGE101_I176@PURE_QUANTA.SCONN288_ADR50017P087CC(CHIPS)':
 'VSS98': CDS_PINID='VSS98';
NODE_NAME     J20 228
 '@S9S_MB_2U_LIB.S9S_MB_2U(SCH_1):PAGE101_I176@PURE_QUANTA.SCONN288_ADR50017P087CC(CHIPS)':
 'VSS99': CDS_PINID='VSS99';
NODE_NAME     J20 230
 '@S9S_MB_2U_LIB.S9S_MB_2U(SCH_1):PAGE101_I176@PURE_QUANTA.SCONN288_ADR50017P087CC(CHIPS)':
 'VSS100': CDS_PINID='VSS100';
NODE_NAME     J20 233
 '@S9S_MB_2U_LIB.S9S_MB_2U(SCH_1):PAGE101_I176@PURE_QUANTA.SCONN288_ADR50017P087CC(CHIPS)':
 'VSS101': CDS_PINID='VSS101';
NODE_NAME     J20 235
 '@S9S_MB_2U_LIB.S9S_MB_2U(SCH_1):PAGE101_I176@PURE_QUANTA.SCONN288_ADR50017P087CC(CHIPS)':
 'VSS102': CDS_PINID='VSS102';
NODE_NAME     J20 237
 '@S9S_MB_2U_LIB.S9S_MB_2U(SCH_1):PAGE101_I176@PURE_QUANTA.SCONN288_ADR50017P087CC(CHIPS)':
 'VSS103': CDS_PINID='VSS103';
NODE_NAME     J20 240
 '@S9S_MB_2U_LIB.S9S_MB_2U(SCH_1):PAGE101_I176@PURE_QUANTA.SCONN288_ADR50017P087CC(CHIPS)':
 'VSS104': CDS_PINID='VSS104';
NODE_NAME     J20 242
 '@S9S_MB_2U_LIB.S9S_MB_2U(SCH_1):PAGE101_I176@PURE_QUANTA.SCONN288_ADR50017P087CC(CHIPS)':
 'VSS105': CDS_PINID='VSS105';
NODE_NAME     J20 244
 '@S9S_MB_2U_LIB.S9S_MB_2U(SCH_1):PAGE101_I176@PURE_QUANTA.SCONN288_ADR50017P087CC(CHIPS)':
 'VSS106': CDS_PINID='VSS106';
NODE_NAME     J20 246
 '@S9S_MB_2U_LIB.S9S_MB_2U(SCH_1):PAGE101_I176@PURE_QUANTA.SCONN288_ADR50017P087CC(CHIPS)':
 'VSS107': CDS_PINID='VSS107';
NODE_NAME     J20 248
 '@S9S_MB_2U_LIB.S9S_MB_2U(SCH_1):PAGE101_I176@PURE_QUANTA.SCONN288_ADR50017P087CC(CHIPS)':
 'VSS108': CDS_PINID='VSS108';
NODE_NAME     J20 251
 '@S9S_MB_2U_LIB.S9S_MB_2U(SCH_1):PAGE101_I176@PURE_QUANTA.SCONN288_ADR50017P087CC(CHIPS)':
 'VSS109': CDS_PINID='VSS109';
NODE_NAME     J20 253
 '@S9S_MB_2U_LIB.S9S_MB_2U(SCH_1):PAGE101_I176@PURE_QUANTA.SCONN288_ADR50017P087CC(CHIPS)':
 'VSS110': CDS_PINID='VSS110';
NODE_NAME     J20 255
 '@S9S_MB_2U_LIB.S9S_MB_2U(SCH_1):PAGE101_I176@PURE_QUANTA.SCONN288_ADR50017P087CC(CHIPS)':
 'VSS111': CDS_PINID='VSS111';
NODE_NAME     J20 257
 '@S9S_MB_2U_LIB.S9S_MB_2U(SCH_1):PAGE101_I176@PURE_QUANTA.SCONN288_ADR50017P087CC(CHIPS)':
 'VSS112': CDS_PINID='VSS112';
NODE_NAME     J20 259
 '@S9S_MB_2U_LIB.S9S_MB_2U(SCH_1):PAGE101_I176@PURE_QUANTA.SCONN288_ADR50017P087CC(CHIPS)':
 'VSS113': CDS_PINID='VSS113';
NODE_NAME     J20 262
 '@S9S_MB_2U_LIB.S9S_MB_2U(SCH_1):PAGE101_I176@PURE_QUANTA.SCONN288_ADR50017P087CC(CHIPS)':
 'VSS114': CDS_PINID='VSS114';
NODE_NAME     J20 264
 '@S9S_MB_2U_LIB.S9S_MB_2U(SCH_1):PAGE101_I176@PURE_QUANTA.SCONN288_ADR50017P087CC(CHIPS)':
 'VSS115': CDS_PINID='VSS115';
NODE_NAME     J20 266
 '@S9S_MB_2U_LIB.S9S_MB_2U(SCH_1):PAGE101_I176@PURE_QUANTA.SCONN288_ADR50017P087CC(CHIPS)':
 'VSS116': CDS_PINID='VSS116';
NODE_NAME     J20 268
 '@S9S_MB_2U_LIB.S9S_MB_2U(SCH_1):PAGE101_I176@PURE_QUANTA.SCONN288_ADR50017P087CC(CHIPS)':
 'VSS117': CDS_PINID='VSS117';
NODE_NAME     J20 270
 '@S9S_MB_2U_LIB.S9S_MB_2U(SCH_1):PAGE101_I176@PURE_QUANTA.SCONN288_ADR50017P087CC(CHIPS)':
 'VSS118': CDS_PINID='VSS118';
NODE_NAME     J20 273
 '@S9S_MB_2U_LIB.S9S_MB_2U(SCH_1):PAGE101_I176@PURE_QUANTA.SCONN288_ADR50017P087CC(CHIPS)':
 'VSS119': CDS_PINID='VSS119';
NODE_NAME     J20 275
 '@S9S_MB_2U_LIB.S9S_MB_2U(SCH_1):PAGE101_I176@PURE_QUANTA.SCONN288_ADR50017P087CC(CHIPS)':
 'VSS120': CDS_PINID='VSS120';
NODE_NAME     J20 277
 '@S9S_MB_2U_LIB.S9S_MB_2U(SCH_1):PAGE101_I176@PURE_QUANTA.SCONN288_ADR50017P087CC(CHIPS)':
 'VSS121': CDS_PINID='VSS121';
NODE_NAME     J20 279
 '@S9S_MB_2U_LIB.S9S_MB_2U(SCH_1):PAGE101_I176@PURE_QUANTA.SCONN288_ADR50017P087CC(CHIPS)':
 'VSS122': CDS_PINID='VSS122';
NODE_NAME     J20 281
 '@S9S_MB_2U_LIB.S9S_MB_2U(SCH_1):PAGE101_I176@PURE_QUANTA.SCONN288_ADR50017P087CC(CHIPS)':
 'VSS123': CDS_PINID='VSS123';
NODE_NAME     J20 284
 '@S9S_MB_2U_LIB.S9S_MB_2U(SCH_1):PAGE101_I176@PURE_QUANTA.SCONN288_ADR50017P087CC(CHIPS)':
 'VSS124': CDS_PINID='VSS124';
NODE_NAME     J20 286
 '@S9S_MB_2U_LIB.S9S_MB_2U(SCH_1):PAGE101_I176@PURE_QUANTA.SCONN288_ADR50017P087CC(CHIPS)':
 'VSS125': CDS_PINID='VSS125';
NODE_NAME     J20 288
 '@S9S_MB_2U_LIB.S9S_MB_2U(SCH_1):PAGE101_I176@PURE_QUANTA.SCONN288_ADR50017P087CC(CHIPS)':
 'VSS126': CDS_PINID='VSS126';
NODE_NAME     R46 2
 '@S9S_MB_2U_LIB.S9S_MB_2U(SCH_1):PAGE102_I2@PURE_QUANTA.Q_RES(CHIPS)':
 'B': CDS_PINID='B';
NODE_NAME     C62 2
 '@S9S_MB_2U_LIB.S9S_MB_2U(SCH_1):PAGE102_I124@PURE_QUANTA.Q_CAP(CHIPS)':
 'B': CDS_PINID='B';
NODE_NAME     C63 2
 '@S9S_MB_2U_LIB.S9S_MB_2U(SCH_1):PAGE102_I127@PURE_QUANTA.Q_CAP(CHIPS)':
 'B': CDS_PINID='B';
NODE_NAME     C64 2
 '@S9S_MB_2U_LIB.S9S_MB_2U(SCH_1):PAGE102_I167@PURE_QUANTA.Q_CAP(CHIPS)':
 'B': CDS_PINID='B';
NODE_NAME     J21 G1
 '@S9S_MB_2U_LIB.S9S_MB_2U(SCH_1):PAGE102_I169@PURE_QUANTA.SCONN288_ADR50017P130CC(CHIPS)':
 'G1': CDS_PINID='G1';
NODE_NAME     J21 G2
 '@S9S_MB_2U_LIB.S9S_MB_2U(SCH_1):PAGE102_I169@PURE_QUANTA.SCONN288_ADR50017P130CC(CHIPS)':
 'G2': CDS_PINID='G2';
NODE_NAME     J21 G3
 '@S9S_MB_2U_LIB.S9S_MB_2U(SCH_1):PAGE102_I169@PURE_QUANTA.SCONN288_ADR50017P130CC(CHIPS)':
 'G3': CDS_PINID='G3';
NODE_NAME     J21 6
 '@S9S_MB_2U_LIB.S9S_MB_2U(SCH_1):PAGE102_I169@PURE_QUANTA.SCONN288_ADR50017P130CC(CHIPS)':
 'VSS0': CDS_PINID='VSS0';
NODE_NAME     J21 8
 '@S9S_MB_2U_LIB.S9S_MB_2U(SCH_1):PAGE102_I169@PURE_QUANTA.SCONN288_ADR50017P130CC(CHIPS)':
 'VSS1': CDS_PINID='VSS1';
NODE_NAME     J21 10
 '@S9S_MB_2U_LIB.S9S_MB_2U(SCH_1):PAGE102_I169@PURE_QUANTA.SCONN288_ADR50017P130CC(CHIPS)':
 'VSS2': CDS_PINID='VSS2';
NODE_NAME     J21 13
 '@S9S_MB_2U_LIB.S9S_MB_2U(SCH_1):PAGE102_I169@PURE_QUANTA.SCONN288_ADR50017P130CC(CHIPS)':
 'VSS3': CDS_PINID='VSS3';
NODE_NAME     J21 15
 '@S9S_MB_2U_LIB.S9S_MB_2U(SCH_1):PAGE102_I169@PURE_QUANTA.SCONN288_ADR50017P130CC(CHIPS)':
 'VSS4': CDS_PINID='VSS4';
NODE_NAME     J21 17
 '@S9S_MB_2U_LIB.S9S_MB_2U(SCH_1):PAGE102_I169@PURE_QUANTA.SCONN288_ADR50017P130CC(CHIPS)':
 'VSS5': CDS_PINID='VSS5';
NODE_NAME     J21 19
 '@S9S_MB_2U_LIB.S9S_MB_2U(SCH_1):PAGE102_I169@PURE_QUANTA.SCONN288_ADR50017P130CC(CHIPS)':
 'VSS6': CDS_PINID='VSS6';
NODE_NAME     J21 21
 '@S9S_MB_2U_LIB.S9S_MB_2U(SCH_1):PAGE102_I169@PURE_QUANTA.SCONN288_ADR50017P130CC(CHIPS)':
 'VSS7': CDS_PINID='VSS7';
NODE_NAME     J21 24
 '@S9S_MB_2U_LIB.S9S_MB_2U(SCH_1):PAGE102_I169@PURE_QUANTA.SCONN288_ADR50017P130CC(CHIPS)':
 'VSS8': CDS_PINID='VSS8';
NODE_NAME     J21 26
 '@S9S_MB_2U_LIB.S9S_MB_2U(SCH_1):PAGE102_I169@PURE_QUANTA.SCONN288_ADR50017P130CC(CHIPS)':
 'VSS9': CDS_PINID='VSS9';
NODE_NAME     J21 28
 '@S9S_MB_2U_LIB.S9S_MB_2U(SCH_1):PAGE102_I169@PURE_QUANTA.SCONN288_ADR50017P130CC(CHIPS)':
 'VSS10': CDS_PINID='VSS10';
NODE_NAME     J21 30
 '@S9S_MB_2U_LIB.S9S_MB_2U(SCH_1):PAGE102_I169@PURE_QUANTA.SCONN288_ADR50017P130CC(CHIPS)':
 'VSS11': CDS_PINID='VSS11';
NODE_NAME     J21 32
 '@S9S_MB_2U_LIB.S9S_MB_2U(SCH_1):PAGE102_I169@PURE_QUANTA.SCONN288_ADR50017P130CC(CHIPS)':
 'VSS12': CDS_PINID='VSS12';
NODE_NAME     J21 35
 '@S9S_MB_2U_LIB.S9S_MB_2U(SCH_1):PAGE102_I169@PURE_QUANTA.SCONN288_ADR50017P130CC(CHIPS)':
 'VSS13': CDS_PINID='VSS13';
NODE_NAME     J21 37
 '@S9S_MB_2U_LIB.S9S_MB_2U(SCH_1):PAGE102_I169@PURE_QUANTA.SCONN288_ADR50017P130CC(CHIPS)':
 'VSS14': CDS_PINID='VSS14';
NODE_NAME     J21 39
 '@S9S_MB_2U_LIB.S9S_MB_2U(SCH_1):PAGE102_I169@PURE_QUANTA.SCONN288_ADR50017P130CC(CHIPS)':
 'VSS15': CDS_PINID='VSS15';
NODE_NAME     J21 41
 '@S9S_MB_2U_LIB.S9S_MB_2U(SCH_1):PAGE102_I169@PURE_QUANTA.SCONN288_ADR50017P130CC(CHIPS)':
 'VSS16': CDS_PINID='VSS16';
NODE_NAME     J21 43
 '@S9S_MB_2U_LIB.S9S_MB_2U(SCH_1):PAGE102_I169@PURE_QUANTA.SCONN288_ADR50017P130CC(CHIPS)':
 'VSS17': CDS_PINID='VSS17';
NODE_NAME     J21 46
 '@S9S_MB_2U_LIB.S9S_MB_2U(SCH_1):PAGE102_I169@PURE_QUANTA.SCONN288_ADR50017P130CC(CHIPS)':
 'VSS18': CDS_PINID='VSS18';
NODE_NAME     J21 48
 '@S9S_MB_2U_LIB.S9S_MB_2U(SCH_1):PAGE102_I169@PURE_QUANTA.SCONN288_ADR50017P130CC(CHIPS)':
 'VSS19': CDS_PINID='VSS19';
NODE_NAME     J21 50
 '@S9S_MB_2U_LIB.S9S_MB_2U(SCH_1):PAGE102_I169@PURE_QUANTA.SCONN288_ADR50017P130CC(CHIPS)':
 'VSS20': CDS_PINID='VSS20';
NODE_NAME     J21 52
 '@S9S_MB_2U_LIB.S9S_MB_2U(SCH_1):PAGE102_I169@PURE_QUANTA.SCONN288_ADR50017P130CC(CHIPS)':
 'VSS21': CDS_PINID='VSS21';
NODE_NAME     J21 54
 '@S9S_MB_2U_LIB.S9S_MB_2U(SCH_1):PAGE102_I169@PURE_QUANTA.SCONN288_ADR50017P130CC(CHIPS)':
 'VSS22': CDS_PINID='VSS22';
NODE_NAME     J21 57
 '@S9S_MB_2U_LIB.S9S_MB_2U(SCH_1):PAGE102_I169@PURE_QUANTA.SCONN288_ADR50017P130CC(CHIPS)':
 'VSS23': CDS_PINID='VSS23';
NODE_NAME     J21 59
 '@S9S_MB_2U_LIB.S9S_MB_2U(SCH_1):PAGE102_I169@PURE_QUANTA.SCONN288_ADR50017P130CC(CHIPS)':
 'VSS24': CDS_PINID='VSS24';
NODE_NAME     J21 61
 '@S9S_MB_2U_LIB.S9S_MB_2U(SCH_1):PAGE102_I169@PURE_QUANTA.SCONN288_ADR50017P130CC(CHIPS)':
 'VSS25': CDS_PINID='VSS25';
NODE_NAME     J21 63
 '@S9S_MB_2U_LIB.S9S_MB_2U(SCH_1):PAGE102_I169@PURE_QUANTA.SCONN288_ADR50017P130CC(CHIPS)':
 'VSS26': CDS_PINID='VSS26';
NODE_NAME     J21 65
 '@S9S_MB_2U_LIB.S9S_MB_2U(SCH_1):PAGE102_I169@PURE_QUANTA.SCONN288_ADR50017P130CC(CHIPS)':
 'VSS27': CDS_PINID='VSS27';
NODE_NAME     J21 67
 '@S9S_MB_2U_LIB.S9S_MB_2U(SCH_1):PAGE102_I169@PURE_QUANTA.SCONN288_ADR50017P130CC(CHIPS)':
 'VSS28': CDS_PINID='VSS28';
NODE_NAME     J21 69
 '@S9S_MB_2U_LIB.S9S_MB_2U(SCH_1):PAGE102_I169@PURE_QUANTA.SCONN288_ADR50017P130CC(CHIPS)':
 'VSS29': CDS_PINID='VSS29';
NODE_NAME     J21 71
 '@S9S_MB_2U_LIB.S9S_MB_2U(SCH_1):PAGE102_I169@PURE_QUANTA.SCONN288_ADR50017P130CC(CHIPS)':
 'VSS30': CDS_PINID='VSS30';
NODE_NAME     J21 73
 '@S9S_MB_2U_LIB.S9S_MB_2U(SCH_1):PAGE102_I169@PURE_QUANTA.SCONN288_ADR50017P130CC(CHIPS)':
 'VSS31': CDS_PINID='VSS31';
NODE_NAME     J21 75
 '@S9S_MB_2U_LIB.S9S_MB_2U(SCH_1):PAGE102_I169@PURE_QUANTA.SCONN288_ADR50017P130CC(CHIPS)':
 'VSS32': CDS_PINID='VSS32';
NODE_NAME     J21 77
 '@S9S_MB_2U_LIB.S9S_MB_2U(SCH_1):PAGE102_I169@PURE_QUANTA.SCONN288_ADR50017P130CC(CHIPS)':
 'VSS33': CDS_PINID='VSS33';
NODE_NAME     J21 79
 '@S9S_MB_2U_LIB.S9S_MB_2U(SCH_1):PAGE102_I169@PURE_QUANTA.SCONN288_ADR50017P130CC(CHIPS)':
 'VSS34': CDS_PINID='VSS34';
NODE_NAME     J21 81
 '@S9S_MB_2U_LIB.S9S_MB_2U(SCH_1):PAGE102_I169@PURE_QUANTA.SCONN288_ADR50017P130CC(CHIPS)':
 'VSS35': CDS_PINID='VSS35';
NODE_NAME     J21 83
 '@S9S_MB_2U_LIB.S9S_MB_2U(SCH_1):PAGE102_I169@PURE_QUANTA.SCONN288_ADR50017P130CC(CHIPS)':
 'VSS36': CDS_PINID='VSS36';
NODE_NAME     J21 85
 '@S9S_MB_2U_LIB.S9S_MB_2U(SCH_1):PAGE102_I169@PURE_QUANTA.SCONN288_ADR50017P130CC(CHIPS)':
 'VSS37': CDS_PINID='VSS37';
NODE_NAME     J21 88
 '@S9S_MB_2U_LIB.S9S_MB_2U(SCH_1):PAGE102_I169@PURE_QUANTA.SCONN288_ADR50017P130CC(CHIPS)':
 'VSS38': CDS_PINID='VSS38';
NODE_NAME     J21 90
 '@S9S_MB_2U_LIB.S9S_MB_2U(SCH_1):PAGE102_I169@PURE_QUANTA.SCONN288_ADR50017P130CC(CHIPS)':
 'VSS39': CDS_PINID='VSS39';
NODE_NAME     J21 92
 '@S9S_MB_2U_LIB.S9S_MB_2U(SCH_1):PAGE102_I169@PURE_QUANTA.SCONN288_ADR50017P130CC(CHIPS)':
 'VSS40': CDS_PINID='VSS40';
NODE_NAME     J21 95
 '@S9S_MB_2U_LIB.S9S_MB_2U(SCH_1):PAGE102_I169@PURE_QUANTA.SCONN288_ADR50017P130CC(CHIPS)':
 'VSS41': CDS_PINID='VSS41';
NODE_NAME     J21 97
 '@S9S_MB_2U_LIB.S9S_MB_2U(SCH_1):PAGE102_I169@PURE_QUANTA.SCONN288_ADR50017P130CC(CHIPS)':
 'VSS42': CDS_PINID='VSS42';
NODE_NAME     J21 99
 '@S9S_MB_2U_LIB.S9S_MB_2U(SCH_1):PAGE102_I169@PURE_QUANTA.SCONN288_ADR50017P130CC(CHIPS)':
 'VSS43': CDS_PINID='VSS43';
NODE_NAME     J21 101
 '@S9S_MB_2U_LIB.S9S_MB_2U(SCH_1):PAGE102_I169@PURE_QUANTA.SCONN288_ADR50017P130CC(CHIPS)':
 'VSS44': CDS_PINID='VSS44';
NODE_NAME     J21 103
 '@S9S_MB_2U_LIB.S9S_MB_2U(SCH_1):PAGE102_I169@PURE_QUANTA.SCONN288_ADR50017P130CC(CHIPS)':
 'VSS45': CDS_PINID='VSS45';
NODE_NAME     J21 106
 '@S9S_MB_2U_LIB.S9S_MB_2U(SCH_1):PAGE102_I169@PURE_QUANTA.SCONN288_ADR50017P130CC(CHIPS)':
 'VSS46': CDS_PINID='VSS46';
NODE_NAME     J21 108
 '@S9S_MB_2U_LIB.S9S_MB_2U(SCH_1):PAGE102_I169@PURE_QUANTA.SCONN288_ADR50017P130CC(CHIPS)':
 'VSS47': CDS_PINID='VSS47';
NODE_NAME     J21 110
 '@S9S_MB_2U_LIB.S9S_MB_2U(SCH_1):PAGE102_I169@PURE_QUANTA.SCONN288_ADR50017P130CC(CHIPS)':
 'VSS48': CDS_PINID='VSS48';
NODE_NAME     J21 112
 '@S9S_MB_2U_LIB.S9S_MB_2U(SCH_1):PAGE102_I169@PURE_QUANTA.SCONN288_ADR50017P130CC(CHIPS)':
 'VSS49': CDS_PINID='VSS49';
NODE_NAME     J21 114
 '@S9S_MB_2U_LIB.S9S_MB_2U(SCH_1):PAGE102_I169@PURE_QUANTA.SCONN288_ADR50017P130CC(CHIPS)':
 'VSS50': CDS_PINID='VSS50';
NODE_NAME     J21 117
 '@S9S_MB_2U_LIB.S9S_MB_2U(SCH_1):PAGE102_I169@PURE_QUANTA.SCONN288_ADR50017P130CC(CHIPS)':
 'VSS51': CDS_PINID='VSS51';
NODE_NAME     J21 119
 '@S9S_MB_2U_LIB.S9S_MB_2U(SCH_1):PAGE102_I169@PURE_QUANTA.SCONN288_ADR50017P130CC(CHIPS)':
 'VSS52': CDS_PINID='VSS52';
NODE_NAME     J21 121
 '@S9S_MB_2U_LIB.S9S_MB_2U(SCH_1):PAGE102_I169@PURE_QUANTA.SCONN288_ADR50017P130CC(CHIPS)':
 'VSS53': CDS_PINID='VSS53';
NODE_NAME     J21 123
 '@S9S_MB_2U_LIB.S9S_MB_2U(SCH_1):PAGE102_I169@PURE_QUANTA.SCONN288_ADR50017P130CC(CHIPS)':
 'VSS54': CDS_PINID='VSS54';
NODE_NAME     J21 125
 '@S9S_MB_2U_LIB.S9S_MB_2U(SCH_1):PAGE102_I169@PURE_QUANTA.SCONN288_ADR50017P130CC(CHIPS)':
 'VSS55': CDS_PINID='VSS55';
NODE_NAME     J21 128
 '@S9S_MB_2U_LIB.S9S_MB_2U(SCH_1):PAGE102_I169@PURE_QUANTA.SCONN288_ADR50017P130CC(CHIPS)':
 'VSS56': CDS_PINID='VSS56';
NODE_NAME     J21 130
 '@S9S_MB_2U_LIB.S9S_MB_2U(SCH_1):PAGE102_I169@PURE_QUANTA.SCONN288_ADR50017P130CC(CHIPS)':
 'VSS57': CDS_PINID='VSS57';
NODE_NAME     J21 132
 '@S9S_MB_2U_LIB.S9S_MB_2U(SCH_1):PAGE102_I169@PURE_QUANTA.SCONN288_ADR50017P130CC(CHIPS)':
 'VSS58': CDS_PINID='VSS58';
NODE_NAME     J21 134
 '@S9S_MB_2U_LIB.S9S_MB_2U(SCH_1):PAGE102_I169@PURE_QUANTA.SCONN288_ADR50017P130CC(CHIPS)':
 'VSS59': CDS_PINID='VSS59';
NODE_NAME     J21 136
 '@S9S_MB_2U_LIB.S9S_MB_2U(SCH_1):PAGE102_I169@PURE_QUANTA.SCONN288_ADR50017P130CC(CHIPS)':
 'VSS60': CDS_PINID='VSS60';
NODE_NAME     J21 139
 '@S9S_MB_2U_LIB.S9S_MB_2U(SCH_1):PAGE102_I169@PURE_QUANTA.SCONN288_ADR50017P130CC(CHIPS)':
 'VSS61': CDS_PINID='VSS61';
NODE_NAME     J21 141
 '@S9S_MB_2U_LIB.S9S_MB_2U(SCH_1):PAGE102_I169@PURE_QUANTA.SCONN288_ADR50017P130CC(CHIPS)':
 'VSS62': CDS_PINID='VSS62';
NODE_NAME     J21 143
 '@S9S_MB_2U_LIB.S9S_MB_2U(SCH_1):PAGE102_I169@PURE_QUANTA.SCONN288_ADR50017P130CC(CHIPS)':
 'VSS63': CDS_PINID='VSS63';
NODE_NAME     J21 151
 '@S9S_MB_2U_LIB.S9S_MB_2U(SCH_1):PAGE102_I169@PURE_QUANTA.SCONN288_ADR50017P130CC(CHIPS)':
 'VSS64': CDS_PINID='VSS64';
NODE_NAME     J21 153
 '@S9S_MB_2U_LIB.S9S_MB_2U(SCH_1):PAGE102_I169@PURE_QUANTA.SCONN288_ADR50017P130CC(CHIPS)':
 'VSS65': CDS_PINID='VSS65';
NODE_NAME     J21 155
 '@S9S_MB_2U_LIB.S9S_MB_2U(SCH_1):PAGE102_I169@PURE_QUANTA.SCONN288_ADR50017P130CC(CHIPS)':
 'VSS66': CDS_PINID='VSS66';
NODE_NAME     J21 158
 '@S9S_MB_2U_LIB.S9S_MB_2U(SCH_1):PAGE102_I169@PURE_QUANTA.SCONN288_ADR50017P130CC(CHIPS)':
 'VSS67': CDS_PINID='VSS67';
NODE_NAME     J21 160
 '@S9S_MB_2U_LIB.S9S_MB_2U(SCH_1):PAGE102_I169@PURE_QUANTA.SCONN288_ADR50017P130CC(CHIPS)':
 'VSS68': CDS_PINID='VSS68';
NODE_NAME     J21 162
 '@S9S_MB_2U_LIB.S9S_MB_2U(SCH_1):PAGE102_I169@PURE_QUANTA.SCONN288_ADR50017P130CC(CHIPS)':
 'VSS69': CDS_PINID='VSS69';
NODE_NAME     J21 164
 '@S9S_MB_2U_LIB.S9S_MB_2U(SCH_1):PAGE102_I169@PURE_QUANTA.SCONN288_ADR50017P130CC(CHIPS)':
 'VSS70': CDS_PINID='VSS70';
NODE_NAME     J21 166
 '@S9S_MB_2U_LIB.S9S_MB_2U(SCH_1):PAGE102_I169@PURE_QUANTA.SCONN288_ADR50017P130CC(CHIPS)':
 'VSS71': CDS_PINID='VSS71';
NODE_NAME     J21 169
 '@S9S_MB_2U_LIB.S9S_MB_2U(SCH_1):PAGE102_I169@PURE_QUANTA.SCONN288_ADR50017P130CC(CHIPS)':
 'VSS72': CDS_PINID='VSS72';
NODE_NAME     J21 171
 '@S9S_MB_2U_LIB.S9S_MB_2U(SCH_1):PAGE102_I169@PURE_QUANTA.SCONN288_ADR50017P130CC(CHIPS)':
 'VSS73': CDS_PINID='VSS73';
NODE_NAME     J21 173
 '@S9S_MB_2U_LIB.S9S_MB_2U(SCH_1):PAGE102_I169@PURE_QUANTA.SCONN288_ADR50017P130CC(CHIPS)':
 'VSS74': CDS_PINID='VSS74';
NODE_NAME     J21 175
 '@S9S_MB_2U_LIB.S9S_MB_2U(SCH_1):PAGE102_I169@PURE_QUANTA.SCONN288_ADR50017P130CC(CHIPS)':
 'VSS75': CDS_PINID='VSS75';
NODE_NAME     J21 177
 '@S9S_MB_2U_LIB.S9S_MB_2U(SCH_1):PAGE102_I169@PURE_QUANTA.SCONN288_ADR50017P130CC(CHIPS)':
 'VSS76': CDS_PINID='VSS76';
NODE_NAME     J21 180
 '@S9S_MB_2U_LIB.S9S_MB_2U(SCH_1):PAGE102_I169@PURE_QUANTA.SCONN288_ADR50017P130CC(CHIPS)':
 'VSS77': CDS_PINID='VSS77';
NODE_NAME     J21 182
 '@S9S_MB_2U_LIB.S9S_MB_2U(SCH_1):PAGE102_I169@PURE_QUANTA.SCONN288_ADR50017P130CC(CHIPS)':
 'VSS78': CDS_PINID='VSS78';
NODE_NAME     J21 184
 '@S9S_MB_2U_LIB.S9S_MB_2U(SCH_1):PAGE102_I169@PURE_QUANTA.SCONN288_ADR50017P130CC(CHIPS)':
 'VSS79': CDS_PINID='VSS79';
NODE_NAME     J21 186
 '@S9S_MB_2U_LIB.S9S_MB_2U(SCH_1):PAGE102_I169@PURE_QUANTA.SCONN288_ADR50017P130CC(CHIPS)':
 'VSS80': CDS_PINID='VSS80';
NODE_NAME     J21 188
 '@S9S_MB_2U_LIB.S9S_MB_2U(SCH_1):PAGE102_I169@PURE_QUANTA.SCONN288_ADR50017P130CC(CHIPS)':
 'VSS81': CDS_PINID='VSS81';
NODE_NAME     J21 191
 '@S9S_MB_2U_LIB.S9S_MB_2U(SCH_1):PAGE102_I169@PURE_QUANTA.SCONN288_ADR50017P130CC(CHIPS)':
 'VSS82': CDS_PINID='VSS82';
NODE_NAME     J21 193
 '@S9S_MB_2U_LIB.S9S_MB_2U(SCH_1):PAGE102_I169@PURE_QUANTA.SCONN288_ADR50017P130CC(CHIPS)':
 'VSS83': CDS_PINID='VSS83';
NODE_NAME     J21 195
 '@S9S_MB_2U_LIB.S9S_MB_2U(SCH_1):PAGE102_I169@PURE_QUANTA.SCONN288_ADR50017P130CC(CHIPS)':
 'VSS84': CDS_PINID='VSS84';
NODE_NAME     J21 197
 '@S9S_MB_2U_LIB.S9S_MB_2U(SCH_1):PAGE102_I169@PURE_QUANTA.SCONN288_ADR50017P130CC(CHIPS)':
 'VSS85': CDS_PINID='VSS85';
NODE_NAME     J21 199
 '@S9S_MB_2U_LIB.S9S_MB_2U(SCH_1):PAGE102_I169@PURE_QUANTA.SCONN288_ADR50017P130CC(CHIPS)':
 'VSS86': CDS_PINID='VSS86';
NODE_NAME     J21 202
 '@S9S_MB_2U_LIB.S9S_MB_2U(SCH_1):PAGE102_I169@PURE_QUANTA.SCONN288_ADR50017P130CC(CHIPS)':
 'VSS87': CDS_PINID='VSS87';
NODE_NAME     J21 204
 '@S9S_MB_2U_LIB.S9S_MB_2U(SCH_1):PAGE102_I169@PURE_QUANTA.SCONN288_ADR50017P130CC(CHIPS)':
 'VSS88': CDS_PINID='VSS88';
NODE_NAME     J21 206
 '@S9S_MB_2U_LIB.S9S_MB_2U(SCH_1):PAGE102_I169@PURE_QUANTA.SCONN288_ADR50017P130CC(CHIPS)':
 'VSS89': CDS_PINID='VSS89';
NODE_NAME     J21 208
 '@S9S_MB_2U_LIB.S9S_MB_2U(SCH_1):PAGE102_I169@PURE_QUANTA.SCONN288_ADR50017P130CC(CHIPS)':
 'VSS90': CDS_PINID='VSS90';
NODE_NAME     J21 210
 '@S9S_MB_2U_LIB.S9S_MB_2U(SCH_1):PAGE102_I169@PURE_QUANTA.SCONN288_ADR50017P130CC(CHIPS)':
 'VSS91': CDS_PINID='VSS91';
NODE_NAME     J21 212
 '@S9S_MB_2U_LIB.S9S_MB_2U(SCH_1):PAGE102_I169@PURE_QUANTA.SCONN288_ADR50017P130CC(CHIPS)':
 'VSS92': CDS_PINID='VSS92';
NODE_NAME     J21 214
 '@S9S_MB_2U_LIB.S9S_MB_2U(SCH_1):PAGE102_I169@PURE_QUANTA.SCONN288_ADR50017P130CC(CHIPS)':
 'VSS93': CDS_PINID='VSS93';
NODE_NAME     J21 216
 '@S9S_MB_2U_LIB.S9S_MB_2U(SCH_1):PAGE102_I169@PURE_QUANTA.SCONN288_ADR50017P130CC(CHIPS)':
 'VSS94': CDS_PINID='VSS94';
NODE_NAME     J21 219
 '@S9S_MB_2U_LIB.S9S_MB_2U(SCH_1):PAGE102_I169@PURE_QUANTA.SCONN288_ADR50017P130CC(CHIPS)':
 'VSS95': CDS_PINID='VSS95';
NODE_NAME     J21 222
 '@S9S_MB_2U_LIB.S9S_MB_2U(SCH_1):PAGE102_I169@PURE_QUANTA.SCONN288_ADR50017P130CC(CHIPS)':
 'VSS96': CDS_PINID='VSS96';
NODE_NAME     J21 224
 '@S9S_MB_2U_LIB.S9S_MB_2U(SCH_1):PAGE102_I169@PURE_QUANTA.SCONN288_ADR50017P130CC(CHIPS)':
 'VSS97': CDS_PINID='VSS97';
NODE_NAME     J21 226
 '@S9S_MB_2U_LIB.S9S_MB_2U(SCH_1):PAGE102_I169@PURE_QUANTA.SCONN288_ADR50017P130CC(CHIPS)':
 'VSS98': CDS_PINID='VSS98';
NODE_NAME     J21 228
 '@S9S_MB_2U_LIB.S9S_MB_2U(SCH_1):PAGE102_I169@PURE_QUANTA.SCONN288_ADR50017P130CC(CHIPS)':
 'VSS99': CDS_PINID='VSS99';
NODE_NAME     J21 230
 '@S9S_MB_2U_LIB.S9S_MB_2U(SCH_1):PAGE102_I169@PURE_QUANTA.SCONN288_ADR50017P130CC(CHIPS)':
 'VSS100': CDS_PINID='VSS100';
NODE_NAME     J21 233
 '@S9S_MB_2U_LIB.S9S_MB_2U(SCH_1):PAGE102_I169@PURE_QUANTA.SCONN288_ADR50017P130CC(CHIPS)':
 'VSS101': CDS_PINID='VSS101';
NODE_NAME     J21 235
 '@S9S_MB_2U_LIB.S9S_MB_2U(SCH_1):PAGE102_I169@PURE_QUANTA.SCONN288_ADR50017P130CC(CHIPS)':
 'VSS102': CDS_PINID='VSS102';
NODE_NAME     J21 237
 '@S9S_MB_2U_LIB.S9S_MB_2U(SCH_1):PAGE102_I169@PURE_QUANTA.SCONN288_ADR50017P130CC(CHIPS)':
 'VSS103': CDS_PINID='VSS103';
NODE_NAME     J21 240
 '@S9S_MB_2U_LIB.S9S_MB_2U(SCH_1):PAGE102_I169@PURE_QUANTA.SCONN288_ADR50017P130CC(CHIPS)':
 'VSS104': CDS_PINID='VSS104';
NODE_NAME     J21 242
 '@S9S_MB_2U_LIB.S9S_MB_2U(SCH_1):PAGE102_I169@PURE_QUANTA.SCONN288_ADR50017P130CC(CHIPS)':
 'VSS105': CDS_PINID='VSS105';
NODE_NAME     J21 244
 '@S9S_MB_2U_LIB.S9S_MB_2U(SCH_1):PAGE102_I169@PURE_QUANTA.SCONN288_ADR50017P130CC(CHIPS)':
 'VSS106': CDS_PINID='VSS106';
NODE_NAME     J21 246
 '@S9S_MB_2U_LIB.S9S_MB_2U(SCH_1):PAGE102_I169@PURE_QUANTA.SCONN288_ADR50017P130CC(CHIPS)':
 'VSS107': CDS_PINID='VSS107';
NODE_NAME     J21 248
 '@S9S_MB_2U_LIB.S9S_MB_2U(SCH_1):PAGE102_I169@PURE_QUANTA.SCONN288_ADR50017P130CC(CHIPS)':
 'VSS108': CDS_PINID='VSS108';
NODE_NAME     J21 251
 '@S9S_MB_2U_LIB.S9S_MB_2U(SCH_1):PAGE102_I169@PURE_QUANTA.SCONN288_ADR50017P130CC(CHIPS)':
 'VSS109': CDS_PINID='VSS109';
NODE_NAME     J21 253
 '@S9S_MB_2U_LIB.S9S_MB_2U(SCH_1):PAGE102_I169@PURE_QUANTA.SCONN288_ADR50017P130CC(CHIPS)':
 'VSS110': CDS_PINID='VSS110';
NODE_NAME     J21 255
 '@S9S_MB_2U_LIB.S9S_MB_2U(SCH_1):PAGE102_I169@PURE_QUANTA.SCONN288_ADR50017P130CC(CHIPS)':
 'VSS111': CDS_PINID='VSS111';
NODE_NAME     J21 257
 '@S9S_MB_2U_LIB.S9S_MB_2U(SCH_1):PAGE102_I169@PURE_QUANTA.SCONN288_ADR50017P130CC(CHIPS)':
 'VSS112': CDS_PINID='VSS112';
NODE_NAME     J21 259
 '@S9S_MB_2U_LIB.S9S_MB_2U(SCH_1):PAGE102_I169@PURE_QUANTA.SCONN288_ADR50017P130CC(CHIPS)':
 'VSS113': CDS_PINID='VSS113';
NODE_NAME     J21 262
 '@S9S_MB_2U_LIB.S9S_MB_2U(SCH_1):PAGE102_I169@PURE_QUANTA.SCONN288_ADR50017P130CC(CHIPS)':
 'VSS114': CDS_PINID='VSS114';
NODE_NAME     J21 264
 '@S9S_MB_2U_LIB.S9S_MB_2U(SCH_1):PAGE102_I169@PURE_QUANTA.SCONN288_ADR50017P130CC(CHIPS)':
 'VSS115': CDS_PINID='VSS115';
NODE_NAME     J21 266
 '@S9S_MB_2U_LIB.S9S_MB_2U(SCH_1):PAGE102_I169@PURE_QUANTA.SCONN288_ADR50017P130CC(CHIPS)':
 'VSS116': CDS_PINID='VSS116';
NODE_NAME     J21 268
 '@S9S_MB_2U_LIB.S9S_MB_2U(SCH_1):PAGE102_I169@PURE_QUANTA.SCONN288_ADR50017P130CC(CHIPS)':
 'VSS117': CDS_PINID='VSS117';
NODE_NAME     J21 270
 '@S9S_MB_2U_LIB.S9S_MB_2U(SCH_1):PAGE102_I169@PURE_QUANTA.SCONN288_ADR50017P130CC(CHIPS)':
 'VSS118': CDS_PINID='VSS118';
NODE_NAME     J21 273
 '@S9S_MB_2U_LIB.S9S_MB_2U(SCH_1):PAGE102_I169@PURE_QUANTA.SCONN288_ADR50017P130CC(CHIPS)':
 'VSS119': CDS_PINID='VSS119';
NODE_NAME     J21 275
 '@S9S_MB_2U_LIB.S9S_MB_2U(SCH_1):PAGE102_I169@PURE_QUANTA.SCONN288_ADR50017P130CC(CHIPS)':
 'VSS120': CDS_PINID='VSS120';
NODE_NAME     J21 277
 '@S9S_MB_2U_LIB.S9S_MB_2U(SCH_1):PAGE102_I169@PURE_QUANTA.SCONN288_ADR50017P130CC(CHIPS)':
 'VSS121': CDS_PINID='VSS121';
NODE_NAME     J21 279
 '@S9S_MB_2U_LIB.S9S_MB_2U(SCH_1):PAGE102_I169@PURE_QUANTA.SCONN288_ADR50017P130CC(CHIPS)':
 'VSS122': CDS_PINID='VSS122';
NODE_NAME     J21 281
 '@S9S_MB_2U_LIB.S9S_MB_2U(SCH_1):PAGE102_I169@PURE_QUANTA.SCONN288_ADR50017P130CC(CHIPS)':
 'VSS123': CDS_PINID='VSS123';
NODE_NAME     J21 284
 '@S9S_MB_2U_LIB.S9S_MB_2U(SCH_1):PAGE102_I169@PURE_QUANTA.SCONN288_ADR50017P130CC(CHIPS)':
 'VSS124': CDS_PINID='VSS124';
NODE_NAME     J21 286
 '@S9S_MB_2U_LIB.S9S_MB_2U(SCH_1):PAGE102_I169@PURE_QUANTA.SCONN288_ADR50017P130CC(CHIPS)':
 'VSS125': CDS_PINID='VSS125';
NODE_NAME     J21 288
 '@S9S_MB_2U_LIB.S9S_MB_2U(SCH_1):PAGE102_I169@PURE_QUANTA.SCONN288_ADR50017P130CC(CHIPS)':
 'VSS126': CDS_PINID='VSS126';
NODE_NAME     R47 2
 '@S9S_MB_2U_LIB.S9S_MB_2U(SCH_1):PAGE103_I2@PURE_QUANTA.Q_RES(CHIPS)':
 'B': CDS_PINID='B';
NODE_NAME     C65 2
 '@S9S_MB_2U_LIB.S9S_MB_2U(SCH_1):PAGE103_I122@PURE_QUANTA.Q_CAP(CHIPS)':
 'B': CDS_PINID='B';
NODE_NAME     C66 2
 '@S9S_MB_2U_LIB.S9S_MB_2U(SCH_1):PAGE103_I126@PURE_QUANTA.Q_CAP(CHIPS)':
 'B': CDS_PINID='B';
NODE_NAME     C67 2
 '@S9S_MB_2U_LIB.S9S_MB_2U(SCH_1):PAGE103_I128@PURE_QUANTA.Q_CAP(CHIPS)':
 'B': CDS_PINID='B';
NODE_NAME     J22 G1
 '@S9S_MB_2U_LIB.S9S_MB_2U(SCH_1):PAGE103_I176@PURE_QUANTA.SCONN288_ADR50017P087CC(CHIPS)':
 'G1': CDS_PINID='G1';
NODE_NAME     J22 G2
 '@S9S_MB_2U_LIB.S9S_MB_2U(SCH_1):PAGE103_I176@PURE_QUANTA.SCONN288_ADR50017P087CC(CHIPS)':
 'G2': CDS_PINID='G2';
NODE_NAME     J22 G3
 '@S9S_MB_2U_LIB.S9S_MB_2U(SCH_1):PAGE103_I176@PURE_QUANTA.SCONN288_ADR50017P087CC(CHIPS)':
 'G3': CDS_PINID='G3';
NODE_NAME     J22 6
 '@S9S_MB_2U_LIB.S9S_MB_2U(SCH_1):PAGE103_I176@PURE_QUANTA.SCONN288_ADR50017P087CC(CHIPS)':
 'VSS0': CDS_PINID='VSS0';
NODE_NAME     J22 8
 '@S9S_MB_2U_LIB.S9S_MB_2U(SCH_1):PAGE103_I176@PURE_QUANTA.SCONN288_ADR50017P087CC(CHIPS)':
 'VSS1': CDS_PINID='VSS1';
NODE_NAME     J22 10
 '@S9S_MB_2U_LIB.S9S_MB_2U(SCH_1):PAGE103_I176@PURE_QUANTA.SCONN288_ADR50017P087CC(CHIPS)':
 'VSS2': CDS_PINID='VSS2';
NODE_NAME     J22 13
 '@S9S_MB_2U_LIB.S9S_MB_2U(SCH_1):PAGE103_I176@PURE_QUANTA.SCONN288_ADR50017P087CC(CHIPS)':
 'VSS3': CDS_PINID='VSS3';
NODE_NAME     J22 15
 '@S9S_MB_2U_LIB.S9S_MB_2U(SCH_1):PAGE103_I176@PURE_QUANTA.SCONN288_ADR50017P087CC(CHIPS)':
 'VSS4': CDS_PINID='VSS4';
NODE_NAME     J22 17
 '@S9S_MB_2U_LIB.S9S_MB_2U(SCH_1):PAGE103_I176@PURE_QUANTA.SCONN288_ADR50017P087CC(CHIPS)':
 'VSS5': CDS_PINID='VSS5';
NODE_NAME     J22 19
 '@S9S_MB_2U_LIB.S9S_MB_2U(SCH_1):PAGE103_I176@PURE_QUANTA.SCONN288_ADR50017P087CC(CHIPS)':
 'VSS6': CDS_PINID='VSS6';
NODE_NAME     J22 21
 '@S9S_MB_2U_LIB.S9S_MB_2U(SCH_1):PAGE103_I176@PURE_QUANTA.SCONN288_ADR50017P087CC(CHIPS)':
 'VSS7': CDS_PINID='VSS7';
NODE_NAME     J22 24
 '@S9S_MB_2U_LIB.S9S_MB_2U(SCH_1):PAGE103_I176@PURE_QUANTA.SCONN288_ADR50017P087CC(CHIPS)':
 'VSS8': CDS_PINID='VSS8';
NODE_NAME     J22 26
 '@S9S_MB_2U_LIB.S9S_MB_2U(SCH_1):PAGE103_I176@PURE_QUANTA.SCONN288_ADR50017P087CC(CHIPS)':
 'VSS9': CDS_PINID='VSS9';
NODE_NAME     J22 28
 '@S9S_MB_2U_LIB.S9S_MB_2U(SCH_1):PAGE103_I176@PURE_QUANTA.SCONN288_ADR50017P087CC(CHIPS)':
 'VSS10': CDS_PINID='VSS10';
NODE_NAME     J22 30
 '@S9S_MB_2U_LIB.S9S_MB_2U(SCH_1):PAGE103_I176@PURE_QUANTA.SCONN288_ADR50017P087CC(CHIPS)':
 'VSS11': CDS_PINID='VSS11';
NODE_NAME     J22 32
 '@S9S_MB_2U_LIB.S9S_MB_2U(SCH_1):PAGE103_I176@PURE_QUANTA.SCONN288_ADR50017P087CC(CHIPS)':
 'VSS12': CDS_PINID='VSS12';
NODE_NAME     J22 35
 '@S9S_MB_2U_LIB.S9S_MB_2U(SCH_1):PAGE103_I176@PURE_QUANTA.SCONN288_ADR50017P087CC(CHIPS)':
 'VSS13': CDS_PINID='VSS13';
NODE_NAME     J22 37
 '@S9S_MB_2U_LIB.S9S_MB_2U(SCH_1):PAGE103_I176@PURE_QUANTA.SCONN288_ADR50017P087CC(CHIPS)':
 'VSS14': CDS_PINID='VSS14';
NODE_NAME     J22 39
 '@S9S_MB_2U_LIB.S9S_MB_2U(SCH_1):PAGE103_I176@PURE_QUANTA.SCONN288_ADR50017P087CC(CHIPS)':
 'VSS15': CDS_PINID='VSS15';
NODE_NAME     J22 41
 '@S9S_MB_2U_LIB.S9S_MB_2U(SCH_1):PAGE103_I176@PURE_QUANTA.SCONN288_ADR50017P087CC(CHIPS)':
 'VSS16': CDS_PINID='VSS16';
NODE_NAME     J22 43
 '@S9S_MB_2U_LIB.S9S_MB_2U(SCH_1):PAGE103_I176@PURE_QUANTA.SCONN288_ADR50017P087CC(CHIPS)':
 'VSS17': CDS_PINID='VSS17';
NODE_NAME     J22 46
 '@S9S_MB_2U_LIB.S9S_MB_2U(SCH_1):PAGE103_I176@PURE_QUANTA.SCONN288_ADR50017P087CC(CHIPS)':
 'VSS18': CDS_PINID='VSS18';
NODE_NAME     J22 48
 '@S9S_MB_2U_LIB.S9S_MB_2U(SCH_1):PAGE103_I176@PURE_QUANTA.SCONN288_ADR50017P087CC(CHIPS)':
 'VSS19': CDS_PINID='VSS19';
NODE_NAME     J22 50
 '@S9S_MB_2U_LIB.S9S_MB_2U(SCH_1):PAGE103_I176@PURE_QUANTA.SCONN288_ADR50017P087CC(CHIPS)':
 'VSS20': CDS_PINID='VSS20';
NODE_NAME     J22 52
 '@S9S_MB_2U_LIB.S9S_MB_2U(SCH_1):PAGE103_I176@PURE_QUANTA.SCONN288_ADR50017P087CC(CHIPS)':
 'VSS21': CDS_PINID='VSS21';
NODE_NAME     J22 54
 '@S9S_MB_2U_LIB.S9S_MB_2U(SCH_1):PAGE103_I176@PURE_QUANTA.SCONN288_ADR50017P087CC(CHIPS)':
 'VSS22': CDS_PINID='VSS22';
NODE_NAME     J22 57
 '@S9S_MB_2U_LIB.S9S_MB_2U(SCH_1):PAGE103_I176@PURE_QUANTA.SCONN288_ADR50017P087CC(CHIPS)':
 'VSS23': CDS_PINID='VSS23';
NODE_NAME     J22 59
 '@S9S_MB_2U_LIB.S9S_MB_2U(SCH_1):PAGE103_I176@PURE_QUANTA.SCONN288_ADR50017P087CC(CHIPS)':
 'VSS24': CDS_PINID='VSS24';
NODE_NAME     J22 61
 '@S9S_MB_2U_LIB.S9S_MB_2U(SCH_1):PAGE103_I176@PURE_QUANTA.SCONN288_ADR50017P087CC(CHIPS)':
 'VSS25': CDS_PINID='VSS25';
NODE_NAME     J22 63
 '@S9S_MB_2U_LIB.S9S_MB_2U(SCH_1):PAGE103_I176@PURE_QUANTA.SCONN288_ADR50017P087CC(CHIPS)':
 'VSS26': CDS_PINID='VSS26';
NODE_NAME     J22 65
 '@S9S_MB_2U_LIB.S9S_MB_2U(SCH_1):PAGE103_I176@PURE_QUANTA.SCONN288_ADR50017P087CC(CHIPS)':
 'VSS27': CDS_PINID='VSS27';
NODE_NAME     J22 67
 '@S9S_MB_2U_LIB.S9S_MB_2U(SCH_1):PAGE103_I176@PURE_QUANTA.SCONN288_ADR50017P087CC(CHIPS)':
 'VSS28': CDS_PINID='VSS28';
NODE_NAME     J22 69
 '@S9S_MB_2U_LIB.S9S_MB_2U(SCH_1):PAGE103_I176@PURE_QUANTA.SCONN288_ADR50017P087CC(CHIPS)':
 'VSS29': CDS_PINID='VSS29';
NODE_NAME     J22 71
 '@S9S_MB_2U_LIB.S9S_MB_2U(SCH_1):PAGE103_I176@PURE_QUANTA.SCONN288_ADR50017P087CC(CHIPS)':
 'VSS30': CDS_PINID='VSS30';
NODE_NAME     J22 73
 '@S9S_MB_2U_LIB.S9S_MB_2U(SCH_1):PAGE103_I176@PURE_QUANTA.SCONN288_ADR50017P087CC(CHIPS)':
 'VSS31': CDS_PINID='VSS31';
NODE_NAME     J22 75
 '@S9S_MB_2U_LIB.S9S_MB_2U(SCH_1):PAGE103_I176@PURE_QUANTA.SCONN288_ADR50017P087CC(CHIPS)':
 'VSS32': CDS_PINID='VSS32';
NODE_NAME     J22 77
 '@S9S_MB_2U_LIB.S9S_MB_2U(SCH_1):PAGE103_I176@PURE_QUANTA.SCONN288_ADR50017P087CC(CHIPS)':
 'VSS33': CDS_PINID='VSS33';
NODE_NAME     J22 79
 '@S9S_MB_2U_LIB.S9S_MB_2U(SCH_1):PAGE103_I176@PURE_QUANTA.SCONN288_ADR50017P087CC(CHIPS)':
 'VSS34': CDS_PINID='VSS34';
NODE_NAME     J22 81
 '@S9S_MB_2U_LIB.S9S_MB_2U(SCH_1):PAGE103_I176@PURE_QUANTA.SCONN288_ADR50017P087CC(CHIPS)':
 'VSS35': CDS_PINID='VSS35';
NODE_NAME     J22 83
 '@S9S_MB_2U_LIB.S9S_MB_2U(SCH_1):PAGE103_I176@PURE_QUANTA.SCONN288_ADR50017P087CC(CHIPS)':
 'VSS36': CDS_PINID='VSS36';
NODE_NAME     J22 85
 '@S9S_MB_2U_LIB.S9S_MB_2U(SCH_1):PAGE103_I176@PURE_QUANTA.SCONN288_ADR50017P087CC(CHIPS)':
 'VSS37': CDS_PINID='VSS37';
NODE_NAME     J22 88
 '@S9S_MB_2U_LIB.S9S_MB_2U(SCH_1):PAGE103_I176@PURE_QUANTA.SCONN288_ADR50017P087CC(CHIPS)':
 'VSS38': CDS_PINID='VSS38';
NODE_NAME     J22 90
 '@S9S_MB_2U_LIB.S9S_MB_2U(SCH_1):PAGE103_I176@PURE_QUANTA.SCONN288_ADR50017P087CC(CHIPS)':
 'VSS39': CDS_PINID='VSS39';
NODE_NAME     J22 92
 '@S9S_MB_2U_LIB.S9S_MB_2U(SCH_1):PAGE103_I176@PURE_QUANTA.SCONN288_ADR50017P087CC(CHIPS)':
 'VSS40': CDS_PINID='VSS40';
NODE_NAME     J22 95
 '@S9S_MB_2U_LIB.S9S_MB_2U(SCH_1):PAGE103_I176@PURE_QUANTA.SCONN288_ADR50017P087CC(CHIPS)':
 'VSS41': CDS_PINID='VSS41';
NODE_NAME     J22 97
 '@S9S_MB_2U_LIB.S9S_MB_2U(SCH_1):PAGE103_I176@PURE_QUANTA.SCONN288_ADR50017P087CC(CHIPS)':
 'VSS42': CDS_PINID='VSS42';
NODE_NAME     J22 99
 '@S9S_MB_2U_LIB.S9S_MB_2U(SCH_1):PAGE103_I176@PURE_QUANTA.SCONN288_ADR50017P087CC(CHIPS)':
 'VSS43': CDS_PINID='VSS43';
NODE_NAME     J22 101
 '@S9S_MB_2U_LIB.S9S_MB_2U(SCH_1):PAGE103_I176@PURE_QUANTA.SCONN288_ADR50017P087CC(CHIPS)':
 'VSS44': CDS_PINID='VSS44';
NODE_NAME     J22 103
 '@S9S_MB_2U_LIB.S9S_MB_2U(SCH_1):PAGE103_I176@PURE_QUANTA.SCONN288_ADR50017P087CC(CHIPS)':
 'VSS45': CDS_PINID='VSS45';
NODE_NAME     J22 106
 '@S9S_MB_2U_LIB.S9S_MB_2U(SCH_1):PAGE103_I176@PURE_QUANTA.SCONN288_ADR50017P087CC(CHIPS)':
 'VSS46': CDS_PINID='VSS46';
NODE_NAME     J22 108
 '@S9S_MB_2U_LIB.S9S_MB_2U(SCH_1):PAGE103_I176@PURE_QUANTA.SCONN288_ADR50017P087CC(CHIPS)':
 'VSS47': CDS_PINID='VSS47';
NODE_NAME     J22 110
 '@S9S_MB_2U_LIB.S9S_MB_2U(SCH_1):PAGE103_I176@PURE_QUANTA.SCONN288_ADR50017P087CC(CHIPS)':
 'VSS48': CDS_PINID='VSS48';
NODE_NAME     J22 112
 '@S9S_MB_2U_LIB.S9S_MB_2U(SCH_1):PAGE103_I176@PURE_QUANTA.SCONN288_ADR50017P087CC(CHIPS)':
 'VSS49': CDS_PINID='VSS49';
NODE_NAME     J22 114
 '@S9S_MB_2U_LIB.S9S_MB_2U(SCH_1):PAGE103_I176@PURE_QUANTA.SCONN288_ADR50017P087CC(CHIPS)':
 'VSS50': CDS_PINID='VSS50';
NODE_NAME     J22 117
 '@S9S_MB_2U_LIB.S9S_MB_2U(SCH_1):PAGE103_I176@PURE_QUANTA.SCONN288_ADR50017P087CC(CHIPS)':
 'VSS51': CDS_PINID='VSS51';
NODE_NAME     J22 119
 '@S9S_MB_2U_LIB.S9S_MB_2U(SCH_1):PAGE103_I176@PURE_QUANTA.SCONN288_ADR50017P087CC(CHIPS)':
 'VSS52': CDS_PINID='VSS52';
NODE_NAME     J22 121
 '@S9S_MB_2U_LIB.S9S_MB_2U(SCH_1):PAGE103_I176@PURE_QUANTA.SCONN288_ADR50017P087CC(CHIPS)':
 'VSS53': CDS_PINID='VSS53';
NODE_NAME     J22 123
 '@S9S_MB_2U_LIB.S9S_MB_2U(SCH_1):PAGE103_I176@PURE_QUANTA.SCONN288_ADR50017P087CC(CHIPS)':
 'VSS54': CDS_PINID='VSS54';
NODE_NAME     J22 125
 '@S9S_MB_2U_LIB.S9S_MB_2U(SCH_1):PAGE103_I176@PURE_QUANTA.SCONN288_ADR50017P087CC(CHIPS)':
 'VSS55': CDS_PINID='VSS55';
NODE_NAME     J22 128
 '@S9S_MB_2U_LIB.S9S_MB_2U(SCH_1):PAGE103_I176@PURE_QUANTA.SCONN288_ADR50017P087CC(CHIPS)':
 'VSS56': CDS_PINID='VSS56';
NODE_NAME     J22 130
 '@S9S_MB_2U_LIB.S9S_MB_2U(SCH_1):PAGE103_I176@PURE_QUANTA.SCONN288_ADR50017P087CC(CHIPS)':
 'VSS57': CDS_PINID='VSS57';
NODE_NAME     J22 132
 '@S9S_MB_2U_LIB.S9S_MB_2U(SCH_1):PAGE103_I176@PURE_QUANTA.SCONN288_ADR50017P087CC(CHIPS)':
 'VSS58': CDS_PINID='VSS58';
NODE_NAME     J22 134
 '@S9S_MB_2U_LIB.S9S_MB_2U(SCH_1):PAGE103_I176@PURE_QUANTA.SCONN288_ADR50017P087CC(CHIPS)':
 'VSS59': CDS_PINID='VSS59';
NODE_NAME     J22 136
 '@S9S_MB_2U_LIB.S9S_MB_2U(SCH_1):PAGE103_I176@PURE_QUANTA.SCONN288_ADR50017P087CC(CHIPS)':
 'VSS60': CDS_PINID='VSS60';
NODE_NAME     J22 139
 '@S9S_MB_2U_LIB.S9S_MB_2U(SCH_1):PAGE103_I176@PURE_QUANTA.SCONN288_ADR50017P087CC(CHIPS)':
 'VSS61': CDS_PINID='VSS61';
NODE_NAME     J22 141
 '@S9S_MB_2U_LIB.S9S_MB_2U(SCH_1):PAGE103_I176@PURE_QUANTA.SCONN288_ADR50017P087CC(CHIPS)':
 'VSS62': CDS_PINID='VSS62';
NODE_NAME     J22 143
 '@S9S_MB_2U_LIB.S9S_MB_2U(SCH_1):PAGE103_I176@PURE_QUANTA.SCONN288_ADR50017P087CC(CHIPS)':
 'VSS63': CDS_PINID='VSS63';
NODE_NAME     J22 151
 '@S9S_MB_2U_LIB.S9S_MB_2U(SCH_1):PAGE103_I176@PURE_QUANTA.SCONN288_ADR50017P087CC(CHIPS)':
 'VSS64': CDS_PINID='VSS64';
NODE_NAME     J22 153
 '@S9S_MB_2U_LIB.S9S_MB_2U(SCH_1):PAGE103_I176@PURE_QUANTA.SCONN288_ADR50017P087CC(CHIPS)':
 'VSS65': CDS_PINID='VSS65';
NODE_NAME     J22 155
 '@S9S_MB_2U_LIB.S9S_MB_2U(SCH_1):PAGE103_I176@PURE_QUANTA.SCONN288_ADR50017P087CC(CHIPS)':
 'VSS66': CDS_PINID='VSS66';
NODE_NAME     J22 158
 '@S9S_MB_2U_LIB.S9S_MB_2U(SCH_1):PAGE103_I176@PURE_QUANTA.SCONN288_ADR50017P087CC(CHIPS)':
 'VSS67': CDS_PINID='VSS67';
NODE_NAME     J22 160
 '@S9S_MB_2U_LIB.S9S_MB_2U(SCH_1):PAGE103_I176@PURE_QUANTA.SCONN288_ADR50017P087CC(CHIPS)':
 'VSS68': CDS_PINID='VSS68';
NODE_NAME     J22 162
 '@S9S_MB_2U_LIB.S9S_MB_2U(SCH_1):PAGE103_I176@PURE_QUANTA.SCONN288_ADR50017P087CC(CHIPS)':
 'VSS69': CDS_PINID='VSS69';
NODE_NAME     J22 164
 '@S9S_MB_2U_LIB.S9S_MB_2U(SCH_1):PAGE103_I176@PURE_QUANTA.SCONN288_ADR50017P087CC(CHIPS)':
 'VSS70': CDS_PINID='VSS70';
NODE_NAME     J22 166
 '@S9S_MB_2U_LIB.S9S_MB_2U(SCH_1):PAGE103_I176@PURE_QUANTA.SCONN288_ADR50017P087CC(CHIPS)':
 'VSS71': CDS_PINID='VSS71';
NODE_NAME     J22 169
 '@S9S_MB_2U_LIB.S9S_MB_2U(SCH_1):PAGE103_I176@PURE_QUANTA.SCONN288_ADR50017P087CC(CHIPS)':
 'VSS72': CDS_PINID='VSS72';
NODE_NAME     J22 171
 '@S9S_MB_2U_LIB.S9S_MB_2U(SCH_1):PAGE103_I176@PURE_QUANTA.SCONN288_ADR50017P087CC(CHIPS)':
 'VSS73': CDS_PINID='VSS73';
NODE_NAME     J22 173
 '@S9S_MB_2U_LIB.S9S_MB_2U(SCH_1):PAGE103_I176@PURE_QUANTA.SCONN288_ADR50017P087CC(CHIPS)':
 'VSS74': CDS_PINID='VSS74';
NODE_NAME     J22 175
 '@S9S_MB_2U_LIB.S9S_MB_2U(SCH_1):PAGE103_I176@PURE_QUANTA.SCONN288_ADR50017P087CC(CHIPS)':
 'VSS75': CDS_PINID='VSS75';
NODE_NAME     J22 177
 '@S9S_MB_2U_LIB.S9S_MB_2U(SCH_1):PAGE103_I176@PURE_QUANTA.SCONN288_ADR50017P087CC(CHIPS)':
 'VSS76': CDS_PINID='VSS76';
NODE_NAME     J22 180
 '@S9S_MB_2U_LIB.S9S_MB_2U(SCH_1):PAGE103_I176@PURE_QUANTA.SCONN288_ADR50017P087CC(CHIPS)':
 'VSS77': CDS_PINID='VSS77';
NODE_NAME     J22 182
 '@S9S_MB_2U_LIB.S9S_MB_2U(SCH_1):PAGE103_I176@PURE_QUANTA.SCONN288_ADR50017P087CC(CHIPS)':
 'VSS78': CDS_PINID='VSS78';
NODE_NAME     J22 184
 '@S9S_MB_2U_LIB.S9S_MB_2U(SCH_1):PAGE103_I176@PURE_QUANTA.SCONN288_ADR50017P087CC(CHIPS)':
 'VSS79': CDS_PINID='VSS79';
NODE_NAME     J22 186
 '@S9S_MB_2U_LIB.S9S_MB_2U(SCH_1):PAGE103_I176@PURE_QUANTA.SCONN288_ADR50017P087CC(CHIPS)':
 'VSS80': CDS_PINID='VSS80';
NODE_NAME     J22 188
 '@S9S_MB_2U_LIB.S9S_MB_2U(SCH_1):PAGE103_I176@PURE_QUANTA.SCONN288_ADR50017P087CC(CHIPS)':
 'VSS81': CDS_PINID='VSS81';
NODE_NAME     J22 191
 '@S9S_MB_2U_LIB.S9S_MB_2U(SCH_1):PAGE103_I176@PURE_QUANTA.SCONN288_ADR50017P087CC(CHIPS)':
 'VSS82': CDS_PINID='VSS82';
NODE_NAME     J22 193
 '@S9S_MB_2U_LIB.S9S_MB_2U(SCH_1):PAGE103_I176@PURE_QUANTA.SCONN288_ADR50017P087CC(CHIPS)':
 'VSS83': CDS_PINID='VSS83';
NODE_NAME     J22 195
 '@S9S_MB_2U_LIB.S9S_MB_2U(SCH_1):PAGE103_I176@PURE_QUANTA.SCONN288_ADR50017P087CC(CHIPS)':
 'VSS84': CDS_PINID='VSS84';
NODE_NAME     J22 197
 '@S9S_MB_2U_LIB.S9S_MB_2U(SCH_1):PAGE103_I176@PURE_QUANTA.SCONN288_ADR50017P087CC(CHIPS)':
 'VSS85': CDS_PINID='VSS85';
NODE_NAME     J22 199
 '@S9S_MB_2U_LIB.S9S_MB_2U(SCH_1):PAGE103_I176@PURE_QUANTA.SCONN288_ADR50017P087CC(CHIPS)':
 'VSS86': CDS_PINID='VSS86';
NODE_NAME     J22 202
 '@S9S_MB_2U_LIB.S9S_MB_2U(SCH_1):PAGE103_I176@PURE_QUANTA.SCONN288_ADR50017P087CC(CHIPS)':
 'VSS87': CDS_PINID='VSS87';
NODE_NAME     J22 204
 '@S9S_MB_2U_LIB.S9S_MB_2U(SCH_1):PAGE103_I176@PURE_QUANTA.SCONN288_ADR50017P087CC(CHIPS)':
 'VSS88': CDS_PINID='VSS88';
NODE_NAME     J22 206
 '@S9S_MB_2U_LIB.S9S_MB_2U(SCH_1):PAGE103_I176@PURE_QUANTA.SCONN288_ADR50017P087CC(CHIPS)':
 'VSS89': CDS_PINID='VSS89';
NODE_NAME     J22 208
 '@S9S_MB_2U_LIB.S9S_MB_2U(SCH_1):PAGE103_I176@PURE_QUANTA.SCONN288_ADR50017P087CC(CHIPS)':
 'VSS90': CDS_PINID='VSS90';
NODE_NAME     J22 210
 '@S9S_MB_2U_LIB.S9S_MB_2U(SCH_1):PAGE103_I176@PURE_QUANTA.SCONN288_ADR50017P087CC(CHIPS)':
 'VSS91': CDS_PINID='VSS91';
NODE_NAME     J22 212
 '@S9S_MB_2U_LIB.S9S_MB_2U(SCH_1):PAGE103_I176@PURE_QUANTA.SCONN288_ADR50017P087CC(CHIPS)':
 'VSS92': CDS_PINID='VSS92';
NODE_NAME     J22 214
 '@S9S_MB_2U_LIB.S9S_MB_2U(SCH_1):PAGE103_I176@PURE_QUANTA.SCONN288_ADR50017P087CC(CHIPS)':
 'VSS93': CDS_PINID='VSS93';
NODE_NAME     J22 216
 '@S9S_MB_2U_LIB.S9S_MB_2U(SCH_1):PAGE103_I176@PURE_QUANTA.SCONN288_ADR50017P087CC(CHIPS)':
 'VSS94': CDS_PINID='VSS94';
NODE_NAME     J22 219
 '@S9S_MB_2U_LIB.S9S_MB_2U(SCH_1):PAGE103_I176@PURE_QUANTA.SCONN288_ADR50017P087CC(CHIPS)':
 'VSS95': CDS_PINID='VSS95';
NODE_NAME     J22 222
 '@S9S_MB_2U_LIB.S9S_MB_2U(SCH_1):PAGE103_I176@PURE_QUANTA.SCONN288_ADR50017P087CC(CHIPS)':
 'VSS96': CDS_PINID='VSS96';
NODE_NAME     J22 224
 '@S9S_MB_2U_LIB.S9S_MB_2U(SCH_1):PAGE103_I176@PURE_QUANTA.SCONN288_ADR50017P087CC(CHIPS)':
 'VSS97': CDS_PINID='VSS97';
NODE_NAME     J22 226
 '@S9S_MB_2U_LIB.S9S_MB_2U(SCH_1):PAGE103_I176@PURE_QUANTA.SCONN288_ADR50017P087CC(CHIPS)':
 'VSS98': CDS_PINID='VSS98';
NODE_NAME     J22 228
 '@S9S_MB_2U_LIB.S9S_MB_2U(SCH_1):PAGE103_I176@PURE_QUANTA.SCONN288_ADR50017P087CC(CHIPS)':
 'VSS99': CDS_PINID='VSS99';
NODE_NAME     J22 230
 '@S9S_MB_2U_LIB.S9S_MB_2U(SCH_1):PAGE103_I176@PURE_QUANTA.SCONN288_ADR50017P087CC(CHIPS)':
 'VSS100': CDS_PINID='VSS100';
NODE_NAME     J22 233
 '@S9S_MB_2U_LIB.S9S_MB_2U(SCH_1):PAGE103_I176@PURE_QUANTA.SCONN288_ADR50017P087CC(CHIPS)':
 'VSS101': CDS_PINID='VSS101';
NODE_NAME     J22 235
 '@S9S_MB_2U_LIB.S9S_MB_2U(SCH_1):PAGE103_I176@PURE_QUANTA.SCONN288_ADR50017P087CC(CHIPS)':
 'VSS102': CDS_PINID='VSS102';
NODE_NAME     J22 237
 '@S9S_MB_2U_LIB.S9S_MB_2U(SCH_1):PAGE103_I176@PURE_QUANTA.SCONN288_ADR50017P087CC(CHIPS)':
 'VSS103': CDS_PINID='VSS103';
NODE_NAME     J22 240
 '@S9S_MB_2U_LIB.S9S_MB_2U(SCH_1):PAGE103_I176@PURE_QUANTA.SCONN288_ADR50017P087CC(CHIPS)':
 'VSS104': CDS_PINID='VSS104';
NODE_NAME     J22 242
 '@S9S_MB_2U_LIB.S9S_MB_2U(SCH_1):PAGE103_I176@PURE_QUANTA.SCONN288_ADR50017P087CC(CHIPS)':
 'VSS105': CDS_PINID='VSS105';
NODE_NAME     J22 244
 '@S9S_MB_2U_LIB.S9S_MB_2U(SCH_1):PAGE103_I176@PURE_QUANTA.SCONN288_ADR50017P087CC(CHIPS)':
 'VSS106': CDS_PINID='VSS106';
NODE_NAME     J22 246
 '@S9S_MB_2U_LIB.S9S_MB_2U(SCH_1):PAGE103_I176@PURE_QUANTA.SCONN288_ADR50017P087CC(CHIPS)':
 'VSS107': CDS_PINID='VSS107';
NODE_NAME     J22 248
 '@S9S_MB_2U_LIB.S9S_MB_2U(SCH_1):PAGE103_I176@PURE_QUANTA.SCONN288_ADR50017P087CC(CHIPS)':
 'VSS108': CDS_PINID='VSS108';
NODE_NAME     J22 251
 '@S9S_MB_2U_LIB.S9S_MB_2U(SCH_1):PAGE103_I176@PURE_QUANTA.SCONN288_ADR50017P087CC(CHIPS)':
 'VSS109': CDS_PINID='VSS109';
NODE_NAME     J22 253
 '@S9S_MB_2U_LIB.S9S_MB_2U(SCH_1):PAGE103_I176@PURE_QUANTA.SCONN288_ADR50017P087CC(CHIPS)':
 'VSS110': CDS_PINID='VSS110';
NODE_NAME     J22 255
 '@S9S_MB_2U_LIB.S9S_MB_2U(SCH_1):PAGE103_I176@PURE_QUANTA.SCONN288_ADR50017P087CC(CHIPS)':
 'VSS111': CDS_PINID='VSS111';
NODE_NAME     J22 257
 '@S9S_MB_2U_LIB.S9S_MB_2U(SCH_1):PAGE103_I176@PURE_QUANTA.SCONN288_ADR50017P087CC(CHIPS)':
 'VSS112': CDS_PINID='VSS112';
NODE_NAME     J22 259
 '@S9S_MB_2U_LIB.S9S_MB_2U(SCH_1):PAGE103_I176@PURE_QUANTA.SCONN288_ADR50017P087CC(CHIPS)':
 'VSS113': CDS_PINID='VSS113';
NODE_NAME     J22 262
 '@S9S_MB_2U_LIB.S9S_MB_2U(SCH_1):PAGE103_I176@PURE_QUANTA.SCONN288_ADR50017P087CC(CHIPS)':
 'VSS114': CDS_PINID='VSS114';
NODE_NAME     J22 264
 '@S9S_MB_2U_LIB.S9S_MB_2U(SCH_1):PAGE103_I176@PURE_QUANTA.SCONN288_ADR50017P087CC(CHIPS)':
 'VSS115': CDS_PINID='VSS115';
NODE_NAME     J22 266
 '@S9S_MB_2U_LIB.S9S_MB_2U(SCH_1):PAGE103_I176@PURE_QUANTA.SCONN288_ADR50017P087CC(CHIPS)':
 'VSS116': CDS_PINID='VSS116';
NODE_NAME     J22 268
 '@S9S_MB_2U_LIB.S9S_MB_2U(SCH_1):PAGE103_I176@PURE_QUANTA.SCONN288_ADR50017P087CC(CHIPS)':
 'VSS117': CDS_PINID='VSS117';
NODE_NAME     J22 270
 '@S9S_MB_2U_LIB.S9S_MB_2U(SCH_1):PAGE103_I176@PURE_QUANTA.SCONN288_ADR50017P087CC(CHIPS)':
 'VSS118': CDS_PINID='VSS118';
NODE_NAME     J22 273
 '@S9S_MB_2U_LIB.S9S_MB_2U(SCH_1):PAGE103_I176@PURE_QUANTA.SCONN288_ADR50017P087CC(CHIPS)':
 'VSS119': CDS_PINID='VSS119';
NODE_NAME     J22 275
 '@S9S_MB_2U_LIB.S9S_MB_2U(SCH_1):PAGE103_I176@PURE_QUANTA.SCONN288_ADR50017P087CC(CHIPS)':
 'VSS120': CDS_PINID='VSS120';
NODE_NAME     J22 277
 '@S9S_MB_2U_LIB.S9S_MB_2U(SCH_1):PAGE103_I176@PURE_QUANTA.SCONN288_ADR50017P087CC(CHIPS)':
 'VSS121': CDS_PINID='VSS121';
NODE_NAME     J22 279
 '@S9S_MB_2U_LIB.S9S_MB_2U(SCH_1):PAGE103_I176@PURE_QUANTA.SCONN288_ADR50017P087CC(CHIPS)':
 'VSS122': CDS_PINID='VSS122';
NODE_NAME     J22 281
 '@S9S_MB_2U_LIB.S9S_MB_2U(SCH_1):PAGE103_I176@PURE_QUANTA.SCONN288_ADR50017P087CC(CHIPS)':
 'VSS123': CDS_PINID='VSS123';
NODE_NAME     J22 284
 '@S9S_MB_2U_LIB.S9S_MB_2U(SCH_1):PAGE103_I176@PURE_QUANTA.SCONN288_ADR50017P087CC(CHIPS)':
 'VSS124': CDS_PINID='VSS124';
NODE_NAME     J22 286
 '@S9S_MB_2U_LIB.S9S_MB_2U(SCH_1):PAGE103_I176@PURE_QUANTA.SCONN288_ADR50017P087CC(CHIPS)':
 'VSS125': CDS_PINID='VSS125';
NODE_NAME     J22 288
 '@S9S_MB_2U_LIB.S9S_MB_2U(SCH_1):PAGE103_I176@PURE_QUANTA.SCONN288_ADR50017P087CC(CHIPS)':
 'VSS126': CDS_PINID='VSS126';
NODE_NAME     R48 2
 '@S9S_MB_2U_LIB.S9S_MB_2U(SCH_1):PAGE104_I2@PURE_QUANTA.Q_RES(CHIPS)':
 'B': CDS_PINID='B';
NODE_NAME     C68 2
 '@S9S_MB_2U_LIB.S9S_MB_2U(SCH_1):PAGE104_I122@PURE_QUANTA.Q_CAP(CHIPS)':
 'B': CDS_PINID='B';
NODE_NAME     C69 2
 '@S9S_MB_2U_LIB.S9S_MB_2U(SCH_1):PAGE104_I127@PURE_QUANTA.Q_CAP(CHIPS)':
 'B': CDS_PINID='B';
NODE_NAME     C70 2
 '@S9S_MB_2U_LIB.S9S_MB_2U(SCH_1):PAGE104_I129@PURE_QUANTA.Q_CAP(CHIPS)':
 'B': CDS_PINID='B';
NODE_NAME     J23 G1
 '@S9S_MB_2U_LIB.S9S_MB_2U(SCH_1):PAGE104_I175@PURE_QUANTA.SCONN288_ADR50017P130CC(CHIPS)':
 'G1': CDS_PINID='G1';
NODE_NAME     J23 G2
 '@S9S_MB_2U_LIB.S9S_MB_2U(SCH_1):PAGE104_I175@PURE_QUANTA.SCONN288_ADR50017P130CC(CHIPS)':
 'G2': CDS_PINID='G2';
NODE_NAME     J23 G3
 '@S9S_MB_2U_LIB.S9S_MB_2U(SCH_1):PAGE104_I175@PURE_QUANTA.SCONN288_ADR50017P130CC(CHIPS)':
 'G3': CDS_PINID='G3';
NODE_NAME     J23 6
 '@S9S_MB_2U_LIB.S9S_MB_2U(SCH_1):PAGE104_I175@PURE_QUANTA.SCONN288_ADR50017P130CC(CHIPS)':
 'VSS0': CDS_PINID='VSS0';
NODE_NAME     J23 8
 '@S9S_MB_2U_LIB.S9S_MB_2U(SCH_1):PAGE104_I175@PURE_QUANTA.SCONN288_ADR50017P130CC(CHIPS)':
 'VSS1': CDS_PINID='VSS1';
NODE_NAME     J23 10
 '@S9S_MB_2U_LIB.S9S_MB_2U(SCH_1):PAGE104_I175@PURE_QUANTA.SCONN288_ADR50017P130CC(CHIPS)':
 'VSS2': CDS_PINID='VSS2';
NODE_NAME     J23 13
 '@S9S_MB_2U_LIB.S9S_MB_2U(SCH_1):PAGE104_I175@PURE_QUANTA.SCONN288_ADR50017P130CC(CHIPS)':
 'VSS3': CDS_PINID='VSS3';
NODE_NAME     J23 15
 '@S9S_MB_2U_LIB.S9S_MB_2U(SCH_1):PAGE104_I175@PURE_QUANTA.SCONN288_ADR50017P130CC(CHIPS)':
 'VSS4': CDS_PINID='VSS4';
NODE_NAME     J23 17
 '@S9S_MB_2U_LIB.S9S_MB_2U(SCH_1):PAGE104_I175@PURE_QUANTA.SCONN288_ADR50017P130CC(CHIPS)':
 'VSS5': CDS_PINID='VSS5';
NODE_NAME     J23 19
 '@S9S_MB_2U_LIB.S9S_MB_2U(SCH_1):PAGE104_I175@PURE_QUANTA.SCONN288_ADR50017P130CC(CHIPS)':
 'VSS6': CDS_PINID='VSS6';
NODE_NAME     J23 21
 '@S9S_MB_2U_LIB.S9S_MB_2U(SCH_1):PAGE104_I175@PURE_QUANTA.SCONN288_ADR50017P130CC(CHIPS)':
 'VSS7': CDS_PINID='VSS7';
NODE_NAME     J23 24
 '@S9S_MB_2U_LIB.S9S_MB_2U(SCH_1):PAGE104_I175@PURE_QUANTA.SCONN288_ADR50017P130CC(CHIPS)':
 'VSS8': CDS_PINID='VSS8';
NODE_NAME     J23 26
 '@S9S_MB_2U_LIB.S9S_MB_2U(SCH_1):PAGE104_I175@PURE_QUANTA.SCONN288_ADR50017P130CC(CHIPS)':
 'VSS9': CDS_PINID='VSS9';
NODE_NAME     J23 28
 '@S9S_MB_2U_LIB.S9S_MB_2U(SCH_1):PAGE104_I175@PURE_QUANTA.SCONN288_ADR50017P130CC(CHIPS)':
 'VSS10': CDS_PINID='VSS10';
NODE_NAME     J23 30
 '@S9S_MB_2U_LIB.S9S_MB_2U(SCH_1):PAGE104_I175@PURE_QUANTA.SCONN288_ADR50017P130CC(CHIPS)':
 'VSS11': CDS_PINID='VSS11';
NODE_NAME     J23 32
 '@S9S_MB_2U_LIB.S9S_MB_2U(SCH_1):PAGE104_I175@PURE_QUANTA.SCONN288_ADR50017P130CC(CHIPS)':
 'VSS12': CDS_PINID='VSS12';
NODE_NAME     J23 35
 '@S9S_MB_2U_LIB.S9S_MB_2U(SCH_1):PAGE104_I175@PURE_QUANTA.SCONN288_ADR50017P130CC(CHIPS)':
 'VSS13': CDS_PINID='VSS13';
NODE_NAME     J23 37
 '@S9S_MB_2U_LIB.S9S_MB_2U(SCH_1):PAGE104_I175@PURE_QUANTA.SCONN288_ADR50017P130CC(CHIPS)':
 'VSS14': CDS_PINID='VSS14';
NODE_NAME     J23 39
 '@S9S_MB_2U_LIB.S9S_MB_2U(SCH_1):PAGE104_I175@PURE_QUANTA.SCONN288_ADR50017P130CC(CHIPS)':
 'VSS15': CDS_PINID='VSS15';
NODE_NAME     J23 41
 '@S9S_MB_2U_LIB.S9S_MB_2U(SCH_1):PAGE104_I175@PURE_QUANTA.SCONN288_ADR50017P130CC(CHIPS)':
 'VSS16': CDS_PINID='VSS16';
NODE_NAME     J23 43
 '@S9S_MB_2U_LIB.S9S_MB_2U(SCH_1):PAGE104_I175@PURE_QUANTA.SCONN288_ADR50017P130CC(CHIPS)':
 'VSS17': CDS_PINID='VSS17';
NODE_NAME     J23 46
 '@S9S_MB_2U_LIB.S9S_MB_2U(SCH_1):PAGE104_I175@PURE_QUANTA.SCONN288_ADR50017P130CC(CHIPS)':
 'VSS18': CDS_PINID='VSS18';
NODE_NAME     J23 48
 '@S9S_MB_2U_LIB.S9S_MB_2U(SCH_1):PAGE104_I175@PURE_QUANTA.SCONN288_ADR50017P130CC(CHIPS)':
 'VSS19': CDS_PINID='VSS19';
NODE_NAME     J23 50
 '@S9S_MB_2U_LIB.S9S_MB_2U(SCH_1):PAGE104_I175@PURE_QUANTA.SCONN288_ADR50017P130CC(CHIPS)':
 'VSS20': CDS_PINID='VSS20';
NODE_NAME     J23 52
 '@S9S_MB_2U_LIB.S9S_MB_2U(SCH_1):PAGE104_I175@PURE_QUANTA.SCONN288_ADR50017P130CC(CHIPS)':
 'VSS21': CDS_PINID='VSS21';
NODE_NAME     J23 54
 '@S9S_MB_2U_LIB.S9S_MB_2U(SCH_1):PAGE104_I175@PURE_QUANTA.SCONN288_ADR50017P130CC(CHIPS)':
 'VSS22': CDS_PINID='VSS22';
NODE_NAME     J23 57
 '@S9S_MB_2U_LIB.S9S_MB_2U(SCH_1):PAGE104_I175@PURE_QUANTA.SCONN288_ADR50017P130CC(CHIPS)':
 'VSS23': CDS_PINID='VSS23';
NODE_NAME     J23 59
 '@S9S_MB_2U_LIB.S9S_MB_2U(SCH_1):PAGE104_I175@PURE_QUANTA.SCONN288_ADR50017P130CC(CHIPS)':
 'VSS24': CDS_PINID='VSS24';
NODE_NAME     J23 61
 '@S9S_MB_2U_LIB.S9S_MB_2U(SCH_1):PAGE104_I175@PURE_QUANTA.SCONN288_ADR50017P130CC(CHIPS)':
 'VSS25': CDS_PINID='VSS25';
NODE_NAME     J23 63
 '@S9S_MB_2U_LIB.S9S_MB_2U(SCH_1):PAGE104_I175@PURE_QUANTA.SCONN288_ADR50017P130CC(CHIPS)':
 'VSS26': CDS_PINID='VSS26';
NODE_NAME     J23 65
 '@S9S_MB_2U_LIB.S9S_MB_2U(SCH_1):PAGE104_I175@PURE_QUANTA.SCONN288_ADR50017P130CC(CHIPS)':
 'VSS27': CDS_PINID='VSS27';
NODE_NAME     J23 67
 '@S9S_MB_2U_LIB.S9S_MB_2U(SCH_1):PAGE104_I175@PURE_QUANTA.SCONN288_ADR50017P130CC(CHIPS)':
 'VSS28': CDS_PINID='VSS28';
NODE_NAME     J23 69
 '@S9S_MB_2U_LIB.S9S_MB_2U(SCH_1):PAGE104_I175@PURE_QUANTA.SCONN288_ADR50017P130CC(CHIPS)':
 'VSS29': CDS_PINID='VSS29';
NODE_NAME     J23 71
 '@S9S_MB_2U_LIB.S9S_MB_2U(SCH_1):PAGE104_I175@PURE_QUANTA.SCONN288_ADR50017P130CC(CHIPS)':
 'VSS30': CDS_PINID='VSS30';
NODE_NAME     J23 73
 '@S9S_MB_2U_LIB.S9S_MB_2U(SCH_1):PAGE104_I175@PURE_QUANTA.SCONN288_ADR50017P130CC(CHIPS)':
 'VSS31': CDS_PINID='VSS31';
NODE_NAME     J23 75
 '@S9S_MB_2U_LIB.S9S_MB_2U(SCH_1):PAGE104_I175@PURE_QUANTA.SCONN288_ADR50017P130CC(CHIPS)':
 'VSS32': CDS_PINID='VSS32';
NODE_NAME     J23 77
 '@S9S_MB_2U_LIB.S9S_MB_2U(SCH_1):PAGE104_I175@PURE_QUANTA.SCONN288_ADR50017P130CC(CHIPS)':
 'VSS33': CDS_PINID='VSS33';
NODE_NAME     J23 79
 '@S9S_MB_2U_LIB.S9S_MB_2U(SCH_1):PAGE104_I175@PURE_QUANTA.SCONN288_ADR50017P130CC(CHIPS)':
 'VSS34': CDS_PINID='VSS34';
NODE_NAME     J23 81
 '@S9S_MB_2U_LIB.S9S_MB_2U(SCH_1):PAGE104_I175@PURE_QUANTA.SCONN288_ADR50017P130CC(CHIPS)':
 'VSS35': CDS_PINID='VSS35';
NODE_NAME     J23 83
 '@S9S_MB_2U_LIB.S9S_MB_2U(SCH_1):PAGE104_I175@PURE_QUANTA.SCONN288_ADR50017P130CC(CHIPS)':
 'VSS36': CDS_PINID='VSS36';
NODE_NAME     J23 85
 '@S9S_MB_2U_LIB.S9S_MB_2U(SCH_1):PAGE104_I175@PURE_QUANTA.SCONN288_ADR50017P130CC(CHIPS)':
 'VSS37': CDS_PINID='VSS37';
NODE_NAME     J23 88
 '@S9S_MB_2U_LIB.S9S_MB_2U(SCH_1):PAGE104_I175@PURE_QUANTA.SCONN288_ADR50017P130CC(CHIPS)':
 'VSS38': CDS_PINID='VSS38';
NODE_NAME     J23 90
 '@S9S_MB_2U_LIB.S9S_MB_2U(SCH_1):PAGE104_I175@PURE_QUANTA.SCONN288_ADR50017P130CC(CHIPS)':
 'VSS39': CDS_PINID='VSS39';
NODE_NAME     J23 92
 '@S9S_MB_2U_LIB.S9S_MB_2U(SCH_1):PAGE104_I175@PURE_QUANTA.SCONN288_ADR50017P130CC(CHIPS)':
 'VSS40': CDS_PINID='VSS40';
NODE_NAME     J23 95
 '@S9S_MB_2U_LIB.S9S_MB_2U(SCH_1):PAGE104_I175@PURE_QUANTA.SCONN288_ADR50017P130CC(CHIPS)':
 'VSS41': CDS_PINID='VSS41';
NODE_NAME     J23 97
 '@S9S_MB_2U_LIB.S9S_MB_2U(SCH_1):PAGE104_I175@PURE_QUANTA.SCONN288_ADR50017P130CC(CHIPS)':
 'VSS42': CDS_PINID='VSS42';
NODE_NAME     J23 99
 '@S9S_MB_2U_LIB.S9S_MB_2U(SCH_1):PAGE104_I175@PURE_QUANTA.SCONN288_ADR50017P130CC(CHIPS)':
 'VSS43': CDS_PINID='VSS43';
NODE_NAME     J23 101
 '@S9S_MB_2U_LIB.S9S_MB_2U(SCH_1):PAGE104_I175@PURE_QUANTA.SCONN288_ADR50017P130CC(CHIPS)':
 'VSS44': CDS_PINID='VSS44';
NODE_NAME     J23 103
 '@S9S_MB_2U_LIB.S9S_MB_2U(SCH_1):PAGE104_I175@PURE_QUANTA.SCONN288_ADR50017P130CC(CHIPS)':
 'VSS45': CDS_PINID='VSS45';
NODE_NAME     J23 106
 '@S9S_MB_2U_LIB.S9S_MB_2U(SCH_1):PAGE104_I175@PURE_QUANTA.SCONN288_ADR50017P130CC(CHIPS)':
 'VSS46': CDS_PINID='VSS46';
NODE_NAME     J23 108
 '@S9S_MB_2U_LIB.S9S_MB_2U(SCH_1):PAGE104_I175@PURE_QUANTA.SCONN288_ADR50017P130CC(CHIPS)':
 'VSS47': CDS_PINID='VSS47';
NODE_NAME     J23 110
 '@S9S_MB_2U_LIB.S9S_MB_2U(SCH_1):PAGE104_I175@PURE_QUANTA.SCONN288_ADR50017P130CC(CHIPS)':
 'VSS48': CDS_PINID='VSS48';
NODE_NAME     J23 112
 '@S9S_MB_2U_LIB.S9S_MB_2U(SCH_1):PAGE104_I175@PURE_QUANTA.SCONN288_ADR50017P130CC(CHIPS)':
 'VSS49': CDS_PINID='VSS49';
NODE_NAME     J23 114
 '@S9S_MB_2U_LIB.S9S_MB_2U(SCH_1):PAGE104_I175@PURE_QUANTA.SCONN288_ADR50017P130CC(CHIPS)':
 'VSS50': CDS_PINID='VSS50';
NODE_NAME     J23 117
 '@S9S_MB_2U_LIB.S9S_MB_2U(SCH_1):PAGE104_I175@PURE_QUANTA.SCONN288_ADR50017P130CC(CHIPS)':
 'VSS51': CDS_PINID='VSS51';
NODE_NAME     J23 119
 '@S9S_MB_2U_LIB.S9S_MB_2U(SCH_1):PAGE104_I175@PURE_QUANTA.SCONN288_ADR50017P130CC(CHIPS)':
 'VSS52': CDS_PINID='VSS52';
NODE_NAME     J23 121
 '@S9S_MB_2U_LIB.S9S_MB_2U(SCH_1):PAGE104_I175@PURE_QUANTA.SCONN288_ADR50017P130CC(CHIPS)':
 'VSS53': CDS_PINID='VSS53';
NODE_NAME     J23 123
 '@S9S_MB_2U_LIB.S9S_MB_2U(SCH_1):PAGE104_I175@PURE_QUANTA.SCONN288_ADR50017P130CC(CHIPS)':
 'VSS54': CDS_PINID='VSS54';
NODE_NAME     J23 125
 '@S9S_MB_2U_LIB.S9S_MB_2U(SCH_1):PAGE104_I175@PURE_QUANTA.SCONN288_ADR50017P130CC(CHIPS)':
 'VSS55': CDS_PINID='VSS55';
NODE_NAME     J23 128
 '@S9S_MB_2U_LIB.S9S_MB_2U(SCH_1):PAGE104_I175@PURE_QUANTA.SCONN288_ADR50017P130CC(CHIPS)':
 'VSS56': CDS_PINID='VSS56';
NODE_NAME     J23 130
 '@S9S_MB_2U_LIB.S9S_MB_2U(SCH_1):PAGE104_I175@PURE_QUANTA.SCONN288_ADR50017P130CC(CHIPS)':
 'VSS57': CDS_PINID='VSS57';
NODE_NAME     J23 132
 '@S9S_MB_2U_LIB.S9S_MB_2U(SCH_1):PAGE104_I175@PURE_QUANTA.SCONN288_ADR50017P130CC(CHIPS)':
 'VSS58': CDS_PINID='VSS58';
NODE_NAME     J23 134
 '@S9S_MB_2U_LIB.S9S_MB_2U(SCH_1):PAGE104_I175@PURE_QUANTA.SCONN288_ADR50017P130CC(CHIPS)':
 'VSS59': CDS_PINID='VSS59';
NODE_NAME     J23 136
 '@S9S_MB_2U_LIB.S9S_MB_2U(SCH_1):PAGE104_I175@PURE_QUANTA.SCONN288_ADR50017P130CC(CHIPS)':
 'VSS60': CDS_PINID='VSS60';
NODE_NAME     J23 139
 '@S9S_MB_2U_LIB.S9S_MB_2U(SCH_1):PAGE104_I175@PURE_QUANTA.SCONN288_ADR50017P130CC(CHIPS)':
 'VSS61': CDS_PINID='VSS61';
NODE_NAME     J23 141
 '@S9S_MB_2U_LIB.S9S_MB_2U(SCH_1):PAGE104_I175@PURE_QUANTA.SCONN288_ADR50017P130CC(CHIPS)':
 'VSS62': CDS_PINID='VSS62';
NODE_NAME     J23 143
 '@S9S_MB_2U_LIB.S9S_MB_2U(SCH_1):PAGE104_I175@PURE_QUANTA.SCONN288_ADR50017P130CC(CHIPS)':
 'VSS63': CDS_PINID='VSS63';
NODE_NAME     J23 151
 '@S9S_MB_2U_LIB.S9S_MB_2U(SCH_1):PAGE104_I175@PURE_QUANTA.SCONN288_ADR50017P130CC(CHIPS)':
 'VSS64': CDS_PINID='VSS64';
NODE_NAME     J23 153
 '@S9S_MB_2U_LIB.S9S_MB_2U(SCH_1):PAGE104_I175@PURE_QUANTA.SCONN288_ADR50017P130CC(CHIPS)':
 'VSS65': CDS_PINID='VSS65';
NODE_NAME     J23 155
 '@S9S_MB_2U_LIB.S9S_MB_2U(SCH_1):PAGE104_I175@PURE_QUANTA.SCONN288_ADR50017P130CC(CHIPS)':
 'VSS66': CDS_PINID='VSS66';
NODE_NAME     J23 158
 '@S9S_MB_2U_LIB.S9S_MB_2U(SCH_1):PAGE104_I175@PURE_QUANTA.SCONN288_ADR50017P130CC(CHIPS)':
 'VSS67': CDS_PINID='VSS67';
NODE_NAME     J23 160
 '@S9S_MB_2U_LIB.S9S_MB_2U(SCH_1):PAGE104_I175@PURE_QUANTA.SCONN288_ADR50017P130CC(CHIPS)':
 'VSS68': CDS_PINID='VSS68';
NODE_NAME     J23 162
 '@S9S_MB_2U_LIB.S9S_MB_2U(SCH_1):PAGE104_I175@PURE_QUANTA.SCONN288_ADR50017P130CC(CHIPS)':
 'VSS69': CDS_PINID='VSS69';
NODE_NAME     J23 164
 '@S9S_MB_2U_LIB.S9S_MB_2U(SCH_1):PAGE104_I175@PURE_QUANTA.SCONN288_ADR50017P130CC(CHIPS)':
 'VSS70': CDS_PINID='VSS70';
NODE_NAME     J23 166
 '@S9S_MB_2U_LIB.S9S_MB_2U(SCH_1):PAGE104_I175@PURE_QUANTA.SCONN288_ADR50017P130CC(CHIPS)':
 'VSS71': CDS_PINID='VSS71';
NODE_NAME     J23 169
 '@S9S_MB_2U_LIB.S9S_MB_2U(SCH_1):PAGE104_I175@PURE_QUANTA.SCONN288_ADR50017P130CC(CHIPS)':
 'VSS72': CDS_PINID='VSS72';
NODE_NAME     J23 171
 '@S9S_MB_2U_LIB.S9S_MB_2U(SCH_1):PAGE104_I175@PURE_QUANTA.SCONN288_ADR50017P130CC(CHIPS)':
 'VSS73': CDS_PINID='VSS73';
NODE_NAME     J23 173
 '@S9S_MB_2U_LIB.S9S_MB_2U(SCH_1):PAGE104_I175@PURE_QUANTA.SCONN288_ADR50017P130CC(CHIPS)':
 'VSS74': CDS_PINID='VSS74';
NODE_NAME     J23 175
 '@S9S_MB_2U_LIB.S9S_MB_2U(SCH_1):PAGE104_I175@PURE_QUANTA.SCONN288_ADR50017P130CC(CHIPS)':
 'VSS75': CDS_PINID='VSS75';
NODE_NAME     J23 177
 '@S9S_MB_2U_LIB.S9S_MB_2U(SCH_1):PAGE104_I175@PURE_QUANTA.SCONN288_ADR50017P130CC(CHIPS)':
 'VSS76': CDS_PINID='VSS76';
NODE_NAME     J23 180
 '@S9S_MB_2U_LIB.S9S_MB_2U(SCH_1):PAGE104_I175@PURE_QUANTA.SCONN288_ADR50017P130CC(CHIPS)':
 'VSS77': CDS_PINID='VSS77';
NODE_NAME     J23 182
 '@S9S_MB_2U_LIB.S9S_MB_2U(SCH_1):PAGE104_I175@PURE_QUANTA.SCONN288_ADR50017P130CC(CHIPS)':
 'VSS78': CDS_PINID='VSS78';
NODE_NAME     J23 184
 '@S9S_MB_2U_LIB.S9S_MB_2U(SCH_1):PAGE104_I175@PURE_QUANTA.SCONN288_ADR50017P130CC(CHIPS)':
 'VSS79': CDS_PINID='VSS79';
NODE_NAME     J23 186
 '@S9S_MB_2U_LIB.S9S_MB_2U(SCH_1):PAGE104_I175@PURE_QUANTA.SCONN288_ADR50017P130CC(CHIPS)':
 'VSS80': CDS_PINID='VSS80';
NODE_NAME     J23 188
 '@S9S_MB_2U_LIB.S9S_MB_2U(SCH_1):PAGE104_I175@PURE_QUANTA.SCONN288_ADR50017P130CC(CHIPS)':
 'VSS81': CDS_PINID='VSS81';
NODE_NAME     J23 191
 '@S9S_MB_2U_LIB.S9S_MB_2U(SCH_1):PAGE104_I175@PURE_QUANTA.SCONN288_ADR50017P130CC(CHIPS)':
 'VSS82': CDS_PINID='VSS82';
NODE_NAME     J23 193
 '@S9S_MB_2U_LIB.S9S_MB_2U(SCH_1):PAGE104_I175@PURE_QUANTA.SCONN288_ADR50017P130CC(CHIPS)':
 'VSS83': CDS_PINID='VSS83';
NODE_NAME     J23 195
 '@S9S_MB_2U_LIB.S9S_MB_2U(SCH_1):PAGE104_I175@PURE_QUANTA.SCONN288_ADR50017P130CC(CHIPS)':
 'VSS84': CDS_PINID='VSS84';
NODE_NAME     J23 197
 '@S9S_MB_2U_LIB.S9S_MB_2U(SCH_1):PAGE104_I175@PURE_QUANTA.SCONN288_ADR50017P130CC(CHIPS)':
 'VSS85': CDS_PINID='VSS85';
NODE_NAME     J23 199
 '@S9S_MB_2U_LIB.S9S_MB_2U(SCH_1):PAGE104_I175@PURE_QUANTA.SCONN288_ADR50017P130CC(CHIPS)':
 'VSS86': CDS_PINID='VSS86';
NODE_NAME     J23 202
 '@S9S_MB_2U_LIB.S9S_MB_2U(SCH_1):PAGE104_I175@PURE_QUANTA.SCONN288_ADR50017P130CC(CHIPS)':
 'VSS87': CDS_PINID='VSS87';
NODE_NAME     J23 204
 '@S9S_MB_2U_LIB.S9S_MB_2U(SCH_1):PAGE104_I175@PURE_QUANTA.SCONN288_ADR50017P130CC(CHIPS)':
 'VSS88': CDS_PINID='VSS88';
NODE_NAME     J23 206
 '@S9S_MB_2U_LIB.S9S_MB_2U(SCH_1):PAGE104_I175@PURE_QUANTA.SCONN288_ADR50017P130CC(CHIPS)':
 'VSS89': CDS_PINID='VSS89';
NODE_NAME     J23 208
 '@S9S_MB_2U_LIB.S9S_MB_2U(SCH_1):PAGE104_I175@PURE_QUANTA.SCONN288_ADR50017P130CC(CHIPS)':
 'VSS90': CDS_PINID='VSS90';
NODE_NAME     J23 210
 '@S9S_MB_2U_LIB.S9S_MB_2U(SCH_1):PAGE104_I175@PURE_QUANTA.SCONN288_ADR50017P130CC(CHIPS)':
 'VSS91': CDS_PINID='VSS91';
NODE_NAME     J23 212
 '@S9S_MB_2U_LIB.S9S_MB_2U(SCH_1):PAGE104_I175@PURE_QUANTA.SCONN288_ADR50017P130CC(CHIPS)':
 'VSS92': CDS_PINID='VSS92';
NODE_NAME     J23 214
 '@S9S_MB_2U_LIB.S9S_MB_2U(SCH_1):PAGE104_I175@PURE_QUANTA.SCONN288_ADR50017P130CC(CHIPS)':
 'VSS93': CDS_PINID='VSS93';
NODE_NAME     J23 216
 '@S9S_MB_2U_LIB.S9S_MB_2U(SCH_1):PAGE104_I175@PURE_QUANTA.SCONN288_ADR50017P130CC(CHIPS)':
 'VSS94': CDS_PINID='VSS94';
NODE_NAME     J23 219
 '@S9S_MB_2U_LIB.S9S_MB_2U(SCH_1):PAGE104_I175@PURE_QUANTA.SCONN288_ADR50017P130CC(CHIPS)':
 'VSS95': CDS_PINID='VSS95';
NODE_NAME     J23 222
 '@S9S_MB_2U_LIB.S9S_MB_2U(SCH_1):PAGE104_I175@PURE_QUANTA.SCONN288_ADR50017P130CC(CHIPS)':
 'VSS96': CDS_PINID='VSS96';
NODE_NAME     J23 224
 '@S9S_MB_2U_LIB.S9S_MB_2U(SCH_1):PAGE104_I175@PURE_QUANTA.SCONN288_ADR50017P130CC(CHIPS)':
 'VSS97': CDS_PINID='VSS97';
NODE_NAME     J23 226
 '@S9S_MB_2U_LIB.S9S_MB_2U(SCH_1):PAGE104_I175@PURE_QUANTA.SCONN288_ADR50017P130CC(CHIPS)':
 'VSS98': CDS_PINID='VSS98';
NODE_NAME     J23 228
 '@S9S_MB_2U_LIB.S9S_MB_2U(SCH_1):PAGE104_I175@PURE_QUANTA.SCONN288_ADR50017P130CC(CHIPS)':
 'VSS99': CDS_PINID='VSS99';
NODE_NAME     J23 230
 '@S9S_MB_2U_LIB.S9S_MB_2U(SCH_1):PAGE104_I175@PURE_QUANTA.SCONN288_ADR50017P130CC(CHIPS)':
 'VSS100': CDS_PINID='VSS100';
NODE_NAME     J23 233
 '@S9S_MB_2U_LIB.S9S_MB_2U(SCH_1):PAGE104_I175@PURE_QUANTA.SCONN288_ADR50017P130CC(CHIPS)':
 'VSS101': CDS_PINID='VSS101';
NODE_NAME     J23 235
 '@S9S_MB_2U_LIB.S9S_MB_2U(SCH_1):PAGE104_I175@PURE_QUANTA.SCONN288_ADR50017P130CC(CHIPS)':
 'VSS102': CDS_PINID='VSS102';
NODE_NAME     J23 237
 '@S9S_MB_2U_LIB.S9S_MB_2U(SCH_1):PAGE104_I175@PURE_QUANTA.SCONN288_ADR50017P130CC(CHIPS)':
 'VSS103': CDS_PINID='VSS103';
NODE_NAME     J23 240
 '@S9S_MB_2U_LIB.S9S_MB_2U(SCH_1):PAGE104_I175@PURE_QUANTA.SCONN288_ADR50017P130CC(CHIPS)':
 'VSS104': CDS_PINID='VSS104';
NODE_NAME     J23 242
 '@S9S_MB_2U_LIB.S9S_MB_2U(SCH_1):PAGE104_I175@PURE_QUANTA.SCONN288_ADR50017P130CC(CHIPS)':
 'VSS105': CDS_PINID='VSS105';
NODE_NAME     J23 244
 '@S9S_MB_2U_LIB.S9S_MB_2U(SCH_1):PAGE104_I175@PURE_QUANTA.SCONN288_ADR50017P130CC(CHIPS)':
 'VSS106': CDS_PINID='VSS106';
NODE_NAME     J23 246
 '@S9S_MB_2U_LIB.S9S_MB_2U(SCH_1):PAGE104_I175@PURE_QUANTA.SCONN288_ADR50017P130CC(CHIPS)':
 'VSS107': CDS_PINID='VSS107';
NODE_NAME     J23 248
 '@S9S_MB_2U_LIB.S9S_MB_2U(SCH_1):PAGE104_I175@PURE_QUANTA.SCONN288_ADR50017P130CC(CHIPS)':
 'VSS108': CDS_PINID='VSS108';
NODE_NAME     J23 251
 '@S9S_MB_2U_LIB.S9S_MB_2U(SCH_1):PAGE104_I175@PURE_QUANTA.SCONN288_ADR50017P130CC(CHIPS)':
 'VSS109': CDS_PINID='VSS109';
NODE_NAME     J23 253
 '@S9S_MB_2U_LIB.S9S_MB_2U(SCH_1):PAGE104_I175@PURE_QUANTA.SCONN288_ADR50017P130CC(CHIPS)':
 'VSS110': CDS_PINID='VSS110';
NODE_NAME     J23 255
 '@S9S_MB_2U_LIB.S9S_MB_2U(SCH_1):PAGE104_I175@PURE_QUANTA.SCONN288_ADR50017P130CC(CHIPS)':
 'VSS111': CDS_PINID='VSS111';
NODE_NAME     J23 257
 '@S9S_MB_2U_LIB.S9S_MB_2U(SCH_1):PAGE104_I175@PURE_QUANTA.SCONN288_ADR50017P130CC(CHIPS)':
 'VSS112': CDS_PINID='VSS112';
NODE_NAME     J23 259
 '@S9S_MB_2U_LIB.S9S_MB_2U(SCH_1):PAGE104_I175@PURE_QUANTA.SCONN288_ADR50017P130CC(CHIPS)':
 'VSS113': CDS_PINID='VSS113';
NODE_NAME     J23 262
 '@S9S_MB_2U_LIB.S9S_MB_2U(SCH_1):PAGE104_I175@PURE_QUANTA.SCONN288_ADR50017P130CC(CHIPS)':
 'VSS114': CDS_PINID='VSS114';
NODE_NAME     J23 264
 '@S9S_MB_2U_LIB.S9S_MB_2U(SCH_1):PAGE104_I175@PURE_QUANTA.SCONN288_ADR50017P130CC(CHIPS)':
 'VSS115': CDS_PINID='VSS115';
NODE_NAME     J23 266
 '@S9S_MB_2U_LIB.S9S_MB_2U(SCH_1):PAGE104_I175@PURE_QUANTA.SCONN288_ADR50017P130CC(CHIPS)':
 'VSS116': CDS_PINID='VSS116';
NODE_NAME     J23 268
 '@S9S_MB_2U_LIB.S9S_MB_2U(SCH_1):PAGE104_I175@PURE_QUANTA.SCONN288_ADR50017P130CC(CHIPS)':
 'VSS117': CDS_PINID='VSS117';
NODE_NAME     J23 270
 '@S9S_MB_2U_LIB.S9S_MB_2U(SCH_1):PAGE104_I175@PURE_QUANTA.SCONN288_ADR50017P130CC(CHIPS)':
 'VSS118': CDS_PINID='VSS118';
NODE_NAME     J23 273
 '@S9S_MB_2U_LIB.S9S_MB_2U(SCH_1):PAGE104_I175@PURE_QUANTA.SCONN288_ADR50017P130CC(CHIPS)':
 'VSS119': CDS_PINID='VSS119';
NODE_NAME     J23 275
 '@S9S_MB_2U_LIB.S9S_MB_2U(SCH_1):PAGE104_I175@PURE_QUANTA.SCONN288_ADR50017P130CC(CHIPS)':
 'VSS120': CDS_PINID='VSS120';
NODE_NAME     J23 277
 '@S9S_MB_2U_LIB.S9S_MB_2U(SCH_1):PAGE104_I175@PURE_QUANTA.SCONN288_ADR50017P130CC(CHIPS)':
 'VSS121': CDS_PINID='VSS121';
NODE_NAME     J23 279
 '@S9S_MB_2U_LIB.S9S_MB_2U(SCH_1):PAGE104_I175@PURE_QUANTA.SCONN288_ADR50017P130CC(CHIPS)':
 'VSS122': CDS_PINID='VSS122';
NODE_NAME     J23 281
 '@S9S_MB_2U_LIB.S9S_MB_2U(SCH_1):PAGE104_I175@PURE_QUANTA.SCONN288_ADR50017P130CC(CHIPS)':
 'VSS123': CDS_PINID='VSS123';
NODE_NAME     J23 284
 '@S9S_MB_2U_LIB.S9S_MB_2U(SCH_1):PAGE104_I175@PURE_QUANTA.SCONN288_ADR50017P130CC(CHIPS)':
 'VSS124': CDS_PINID='VSS124';
NODE_NAME     J23 286
 '@S9S_MB_2U_LIB.S9S_MB_2U(SCH_1):PAGE104_I175@PURE_QUANTA.SCONN288_ADR50017P130CC(CHIPS)':
 'VSS125': CDS_PINID='VSS125';
NODE_NAME     J23 288
 '@S9S_MB_2U_LIB.S9S_MB_2U(SCH_1):PAGE104_I175@PURE_QUANTA.SCONN288_ADR50017P130CC(CHIPS)':
 'VSS126': CDS_PINID='VSS126';
NODE_NAME     R80 2
 '@S9S_MB_2U_LIB.S9S_MB_2U(SCH_1):PAGE105_I2@PURE_QUANTA.Q_RES(CHIPS)':
 'B': CDS_PINID='B';
NODE_NAME     C96 2
 '@S9S_MB_2U_LIB.S9S_MB_2U(SCH_1):PAGE105_I123@PURE_QUANTA.Q_CAP(CHIPS)':
 'B': CDS_PINID='B';
NODE_NAME     C97 2
 '@S9S_MB_2U_LIB.S9S_MB_2U(SCH_1):PAGE105_I124@PURE_QUANTA.Q_CAP(CHIPS)':
 'B': CDS_PINID='B';
NODE_NAME     C98 2
 '@S9S_MB_2U_LIB.S9S_MB_2U(SCH_1):PAGE105_I146@PURE_QUANTA.Q_CAP(CHIPS)':
 'B': CDS_PINID='B';
NODE_NAME     J24 G1
 '@S9S_MB_2U_LIB.S9S_MB_2U(SCH_1):PAGE105_I180@PURE_QUANTA.SCONN288_ADR50017P087CC(CHIPS)':
 'G1': CDS_PINID='G1';
NODE_NAME     J24 G2
 '@S9S_MB_2U_LIB.S9S_MB_2U(SCH_1):PAGE105_I180@PURE_QUANTA.SCONN288_ADR50017P087CC(CHIPS)':
 'G2': CDS_PINID='G2';
NODE_NAME     J24 G3
 '@S9S_MB_2U_LIB.S9S_MB_2U(SCH_1):PAGE105_I180@PURE_QUANTA.SCONN288_ADR50017P087CC(CHIPS)':
 'G3': CDS_PINID='G3';
NODE_NAME     J24 6
 '@S9S_MB_2U_LIB.S9S_MB_2U(SCH_1):PAGE105_I180@PURE_QUANTA.SCONN288_ADR50017P087CC(CHIPS)':
 'VSS0': CDS_PINID='VSS0';
NODE_NAME     J24 8
 '@S9S_MB_2U_LIB.S9S_MB_2U(SCH_1):PAGE105_I180@PURE_QUANTA.SCONN288_ADR50017P087CC(CHIPS)':
 'VSS1': CDS_PINID='VSS1';
NODE_NAME     J24 10
 '@S9S_MB_2U_LIB.S9S_MB_2U(SCH_1):PAGE105_I180@PURE_QUANTA.SCONN288_ADR50017P087CC(CHIPS)':
 'VSS2': CDS_PINID='VSS2';
NODE_NAME     J24 13
 '@S9S_MB_2U_LIB.S9S_MB_2U(SCH_1):PAGE105_I180@PURE_QUANTA.SCONN288_ADR50017P087CC(CHIPS)':
 'VSS3': CDS_PINID='VSS3';
NODE_NAME     J24 15
 '@S9S_MB_2U_LIB.S9S_MB_2U(SCH_1):PAGE105_I180@PURE_QUANTA.SCONN288_ADR50017P087CC(CHIPS)':
 'VSS4': CDS_PINID='VSS4';
NODE_NAME     J24 17
 '@S9S_MB_2U_LIB.S9S_MB_2U(SCH_1):PAGE105_I180@PURE_QUANTA.SCONN288_ADR50017P087CC(CHIPS)':
 'VSS5': CDS_PINID='VSS5';
NODE_NAME     J24 19
 '@S9S_MB_2U_LIB.S9S_MB_2U(SCH_1):PAGE105_I180@PURE_QUANTA.SCONN288_ADR50017P087CC(CHIPS)':
 'VSS6': CDS_PINID='VSS6';
NODE_NAME     J24 21
 '@S9S_MB_2U_LIB.S9S_MB_2U(SCH_1):PAGE105_I180@PURE_QUANTA.SCONN288_ADR50017P087CC(CHIPS)':
 'VSS7': CDS_PINID='VSS7';
NODE_NAME     J24 24
 '@S9S_MB_2U_LIB.S9S_MB_2U(SCH_1):PAGE105_I180@PURE_QUANTA.SCONN288_ADR50017P087CC(CHIPS)':
 'VSS8': CDS_PINID='VSS8';
NODE_NAME     J24 26
 '@S9S_MB_2U_LIB.S9S_MB_2U(SCH_1):PAGE105_I180@PURE_QUANTA.SCONN288_ADR50017P087CC(CHIPS)':
 'VSS9': CDS_PINID='VSS9';
NODE_NAME     J24 28
 '@S9S_MB_2U_LIB.S9S_MB_2U(SCH_1):PAGE105_I180@PURE_QUANTA.SCONN288_ADR50017P087CC(CHIPS)':
 'VSS10': CDS_PINID='VSS10';
NODE_NAME     J24 30
 '@S9S_MB_2U_LIB.S9S_MB_2U(SCH_1):PAGE105_I180@PURE_QUANTA.SCONN288_ADR50017P087CC(CHIPS)':
 'VSS11': CDS_PINID='VSS11';
NODE_NAME     J24 32
 '@S9S_MB_2U_LIB.S9S_MB_2U(SCH_1):PAGE105_I180@PURE_QUANTA.SCONN288_ADR50017P087CC(CHIPS)':
 'VSS12': CDS_PINID='VSS12';
NODE_NAME     J24 35
 '@S9S_MB_2U_LIB.S9S_MB_2U(SCH_1):PAGE105_I180@PURE_QUANTA.SCONN288_ADR50017P087CC(CHIPS)':
 'VSS13': CDS_PINID='VSS13';
NODE_NAME     J24 37
 '@S9S_MB_2U_LIB.S9S_MB_2U(SCH_1):PAGE105_I180@PURE_QUANTA.SCONN288_ADR50017P087CC(CHIPS)':
 'VSS14': CDS_PINID='VSS14';
NODE_NAME     J24 39
 '@S9S_MB_2U_LIB.S9S_MB_2U(SCH_1):PAGE105_I180@PURE_QUANTA.SCONN288_ADR50017P087CC(CHIPS)':
 'VSS15': CDS_PINID='VSS15';
NODE_NAME     J24 41
 '@S9S_MB_2U_LIB.S9S_MB_2U(SCH_1):PAGE105_I180@PURE_QUANTA.SCONN288_ADR50017P087CC(CHIPS)':
 'VSS16': CDS_PINID='VSS16';
NODE_NAME     J24 43
 '@S9S_MB_2U_LIB.S9S_MB_2U(SCH_1):PAGE105_I180@PURE_QUANTA.SCONN288_ADR50017P087CC(CHIPS)':
 'VSS17': CDS_PINID='VSS17';
NODE_NAME     J24 46
 '@S9S_MB_2U_LIB.S9S_MB_2U(SCH_1):PAGE105_I180@PURE_QUANTA.SCONN288_ADR50017P087CC(CHIPS)':
 'VSS18': CDS_PINID='VSS18';
NODE_NAME     J24 48
 '@S9S_MB_2U_LIB.S9S_MB_2U(SCH_1):PAGE105_I180@PURE_QUANTA.SCONN288_ADR50017P087CC(CHIPS)':
 'VSS19': CDS_PINID='VSS19';
NODE_NAME     J24 50
 '@S9S_MB_2U_LIB.S9S_MB_2U(SCH_1):PAGE105_I180@PURE_QUANTA.SCONN288_ADR50017P087CC(CHIPS)':
 'VSS20': CDS_PINID='VSS20';
NODE_NAME     J24 52
 '@S9S_MB_2U_LIB.S9S_MB_2U(SCH_1):PAGE105_I180@PURE_QUANTA.SCONN288_ADR50017P087CC(CHIPS)':
 'VSS21': CDS_PINID='VSS21';
NODE_NAME     J24 54
 '@S9S_MB_2U_LIB.S9S_MB_2U(SCH_1):PAGE105_I180@PURE_QUANTA.SCONN288_ADR50017P087CC(CHIPS)':
 'VSS22': CDS_PINID='VSS22';
NODE_NAME     J24 57
 '@S9S_MB_2U_LIB.S9S_MB_2U(SCH_1):PAGE105_I180@PURE_QUANTA.SCONN288_ADR50017P087CC(CHIPS)':
 'VSS23': CDS_PINID='VSS23';
NODE_NAME     J24 59
 '@S9S_MB_2U_LIB.S9S_MB_2U(SCH_1):PAGE105_I180@PURE_QUANTA.SCONN288_ADR50017P087CC(CHIPS)':
 'VSS24': CDS_PINID='VSS24';
NODE_NAME     J24 61
 '@S9S_MB_2U_LIB.S9S_MB_2U(SCH_1):PAGE105_I180@PURE_QUANTA.SCONN288_ADR50017P087CC(CHIPS)':
 'VSS25': CDS_PINID='VSS25';
NODE_NAME     J24 63
 '@S9S_MB_2U_LIB.S9S_MB_2U(SCH_1):PAGE105_I180@PURE_QUANTA.SCONN288_ADR50017P087CC(CHIPS)':
 'VSS26': CDS_PINID='VSS26';
NODE_NAME     J24 65
 '@S9S_MB_2U_LIB.S9S_MB_2U(SCH_1):PAGE105_I180@PURE_QUANTA.SCONN288_ADR50017P087CC(CHIPS)':
 'VSS27': CDS_PINID='VSS27';
NODE_NAME     J24 67
 '@S9S_MB_2U_LIB.S9S_MB_2U(SCH_1):PAGE105_I180@PURE_QUANTA.SCONN288_ADR50017P087CC(CHIPS)':
 'VSS28': CDS_PINID='VSS28';
NODE_NAME     J24 69
 '@S9S_MB_2U_LIB.S9S_MB_2U(SCH_1):PAGE105_I180@PURE_QUANTA.SCONN288_ADR50017P087CC(CHIPS)':
 'VSS29': CDS_PINID='VSS29';
NODE_NAME     J24 71
 '@S9S_MB_2U_LIB.S9S_MB_2U(SCH_1):PAGE105_I180@PURE_QUANTA.SCONN288_ADR50017P087CC(CHIPS)':
 'VSS30': CDS_PINID='VSS30';
NODE_NAME     J24 73
 '@S9S_MB_2U_LIB.S9S_MB_2U(SCH_1):PAGE105_I180@PURE_QUANTA.SCONN288_ADR50017P087CC(CHIPS)':
 'VSS31': CDS_PINID='VSS31';
NODE_NAME     J24 75
 '@S9S_MB_2U_LIB.S9S_MB_2U(SCH_1):PAGE105_I180@PURE_QUANTA.SCONN288_ADR50017P087CC(CHIPS)':
 'VSS32': CDS_PINID='VSS32';
NODE_NAME     J24 77
 '@S9S_MB_2U_LIB.S9S_MB_2U(SCH_1):PAGE105_I180@PURE_QUANTA.SCONN288_ADR50017P087CC(CHIPS)':
 'VSS33': CDS_PINID='VSS33';
NODE_NAME     J24 79
 '@S9S_MB_2U_LIB.S9S_MB_2U(SCH_1):PAGE105_I180@PURE_QUANTA.SCONN288_ADR50017P087CC(CHIPS)':
 'VSS34': CDS_PINID='VSS34';
NODE_NAME     J24 81
 '@S9S_MB_2U_LIB.S9S_MB_2U(SCH_1):PAGE105_I180@PURE_QUANTA.SCONN288_ADR50017P087CC(CHIPS)':
 'VSS35': CDS_PINID='VSS35';
NODE_NAME     J24 83
 '@S9S_MB_2U_LIB.S9S_MB_2U(SCH_1):PAGE105_I180@PURE_QUANTA.SCONN288_ADR50017P087CC(CHIPS)':
 'VSS36': CDS_PINID='VSS36';
NODE_NAME     J24 85
 '@S9S_MB_2U_LIB.S9S_MB_2U(SCH_1):PAGE105_I180@PURE_QUANTA.SCONN288_ADR50017P087CC(CHIPS)':
 'VSS37': CDS_PINID='VSS37';
NODE_NAME     J24 88
 '@S9S_MB_2U_LIB.S9S_MB_2U(SCH_1):PAGE105_I180@PURE_QUANTA.SCONN288_ADR50017P087CC(CHIPS)':
 'VSS38': CDS_PINID='VSS38';
NODE_NAME     J24 90
 '@S9S_MB_2U_LIB.S9S_MB_2U(SCH_1):PAGE105_I180@PURE_QUANTA.SCONN288_ADR50017P087CC(CHIPS)':
 'VSS39': CDS_PINID='VSS39';
NODE_NAME     J24 92
 '@S9S_MB_2U_LIB.S9S_MB_2U(SCH_1):PAGE105_I180@PURE_QUANTA.SCONN288_ADR50017P087CC(CHIPS)':
 'VSS40': CDS_PINID='VSS40';
NODE_NAME     J24 95
 '@S9S_MB_2U_LIB.S9S_MB_2U(SCH_1):PAGE105_I180@PURE_QUANTA.SCONN288_ADR50017P087CC(CHIPS)':
 'VSS41': CDS_PINID='VSS41';
NODE_NAME     J24 97
 '@S9S_MB_2U_LIB.S9S_MB_2U(SCH_1):PAGE105_I180@PURE_QUANTA.SCONN288_ADR50017P087CC(CHIPS)':
 'VSS42': CDS_PINID='VSS42';
NODE_NAME     J24 99
 '@S9S_MB_2U_LIB.S9S_MB_2U(SCH_1):PAGE105_I180@PURE_QUANTA.SCONN288_ADR50017P087CC(CHIPS)':
 'VSS43': CDS_PINID='VSS43';
NODE_NAME     J24 101
 '@S9S_MB_2U_LIB.S9S_MB_2U(SCH_1):PAGE105_I180@PURE_QUANTA.SCONN288_ADR50017P087CC(CHIPS)':
 'VSS44': CDS_PINID='VSS44';
NODE_NAME     J24 103
 '@S9S_MB_2U_LIB.S9S_MB_2U(SCH_1):PAGE105_I180@PURE_QUANTA.SCONN288_ADR50017P087CC(CHIPS)':
 'VSS45': CDS_PINID='VSS45';
NODE_NAME     J24 106
 '@S9S_MB_2U_LIB.S9S_MB_2U(SCH_1):PAGE105_I180@PURE_QUANTA.SCONN288_ADR50017P087CC(CHIPS)':
 'VSS46': CDS_PINID='VSS46';
NODE_NAME     J24 108
 '@S9S_MB_2U_LIB.S9S_MB_2U(SCH_1):PAGE105_I180@PURE_QUANTA.SCONN288_ADR50017P087CC(CHIPS)':
 'VSS47': CDS_PINID='VSS47';
NODE_NAME     J24 110
 '@S9S_MB_2U_LIB.S9S_MB_2U(SCH_1):PAGE105_I180@PURE_QUANTA.SCONN288_ADR50017P087CC(CHIPS)':
 'VSS48': CDS_PINID='VSS48';
NODE_NAME     J24 112
 '@S9S_MB_2U_LIB.S9S_MB_2U(SCH_1):PAGE105_I180@PURE_QUANTA.SCONN288_ADR50017P087CC(CHIPS)':
 'VSS49': CDS_PINID='VSS49';
NODE_NAME     J24 114
 '@S9S_MB_2U_LIB.S9S_MB_2U(SCH_1):PAGE105_I180@PURE_QUANTA.SCONN288_ADR50017P087CC(CHIPS)':
 'VSS50': CDS_PINID='VSS50';
NODE_NAME     J24 117
 '@S9S_MB_2U_LIB.S9S_MB_2U(SCH_1):PAGE105_I180@PURE_QUANTA.SCONN288_ADR50017P087CC(CHIPS)':
 'VSS51': CDS_PINID='VSS51';
NODE_NAME     J24 119
 '@S9S_MB_2U_LIB.S9S_MB_2U(SCH_1):PAGE105_I180@PURE_QUANTA.SCONN288_ADR50017P087CC(CHIPS)':
 'VSS52': CDS_PINID='VSS52';
NODE_NAME     J24 121
 '@S9S_MB_2U_LIB.S9S_MB_2U(SCH_1):PAGE105_I180@PURE_QUANTA.SCONN288_ADR50017P087CC(CHIPS)':
 'VSS53': CDS_PINID='VSS53';
NODE_NAME     J24 123
 '@S9S_MB_2U_LIB.S9S_MB_2U(SCH_1):PAGE105_I180@PURE_QUANTA.SCONN288_ADR50017P087CC(CHIPS)':
 'VSS54': CDS_PINID='VSS54';
NODE_NAME     J24 125
 '@S9S_MB_2U_LIB.S9S_MB_2U(SCH_1):PAGE105_I180@PURE_QUANTA.SCONN288_ADR50017P087CC(CHIPS)':
 'VSS55': CDS_PINID='VSS55';
NODE_NAME     J24 128
 '@S9S_MB_2U_LIB.S9S_MB_2U(SCH_1):PAGE105_I180@PURE_QUANTA.SCONN288_ADR50017P087CC(CHIPS)':
 'VSS56': CDS_PINID='VSS56';
NODE_NAME     J24 130
 '@S9S_MB_2U_LIB.S9S_MB_2U(SCH_1):PAGE105_I180@PURE_QUANTA.SCONN288_ADR50017P087CC(CHIPS)':
 'VSS57': CDS_PINID='VSS57';
NODE_NAME     J24 132
 '@S9S_MB_2U_LIB.S9S_MB_2U(SCH_1):PAGE105_I180@PURE_QUANTA.SCONN288_ADR50017P087CC(CHIPS)':
 'VSS58': CDS_PINID='VSS58';
NODE_NAME     J24 134
 '@S9S_MB_2U_LIB.S9S_MB_2U(SCH_1):PAGE105_I180@PURE_QUANTA.SCONN288_ADR50017P087CC(CHIPS)':
 'VSS59': CDS_PINID='VSS59';
NODE_NAME     J24 136
 '@S9S_MB_2U_LIB.S9S_MB_2U(SCH_1):PAGE105_I180@PURE_QUANTA.SCONN288_ADR50017P087CC(CHIPS)':
 'VSS60': CDS_PINID='VSS60';
NODE_NAME     J24 139
 '@S9S_MB_2U_LIB.S9S_MB_2U(SCH_1):PAGE105_I180@PURE_QUANTA.SCONN288_ADR50017P087CC(CHIPS)':
 'VSS61': CDS_PINID='VSS61';
NODE_NAME     J24 141
 '@S9S_MB_2U_LIB.S9S_MB_2U(SCH_1):PAGE105_I180@PURE_QUANTA.SCONN288_ADR50017P087CC(CHIPS)':
 'VSS62': CDS_PINID='VSS62';
NODE_NAME     J24 143
 '@S9S_MB_2U_LIB.S9S_MB_2U(SCH_1):PAGE105_I180@PURE_QUANTA.SCONN288_ADR50017P087CC(CHIPS)':
 'VSS63': CDS_PINID='VSS63';
NODE_NAME     J24 151
 '@S9S_MB_2U_LIB.S9S_MB_2U(SCH_1):PAGE105_I180@PURE_QUANTA.SCONN288_ADR50017P087CC(CHIPS)':
 'VSS64': CDS_PINID='VSS64';
NODE_NAME     J24 153
 '@S9S_MB_2U_LIB.S9S_MB_2U(SCH_1):PAGE105_I180@PURE_QUANTA.SCONN288_ADR50017P087CC(CHIPS)':
 'VSS65': CDS_PINID='VSS65';
NODE_NAME     J24 155
 '@S9S_MB_2U_LIB.S9S_MB_2U(SCH_1):PAGE105_I180@PURE_QUANTA.SCONN288_ADR50017P087CC(CHIPS)':
 'VSS66': CDS_PINID='VSS66';
NODE_NAME     J24 158
 '@S9S_MB_2U_LIB.S9S_MB_2U(SCH_1):PAGE105_I180@PURE_QUANTA.SCONN288_ADR50017P087CC(CHIPS)':
 'VSS67': CDS_PINID='VSS67';
NODE_NAME     J24 160
 '@S9S_MB_2U_LIB.S9S_MB_2U(SCH_1):PAGE105_I180@PURE_QUANTA.SCONN288_ADR50017P087CC(CHIPS)':
 'VSS68': CDS_PINID='VSS68';
NODE_NAME     J24 162
 '@S9S_MB_2U_LIB.S9S_MB_2U(SCH_1):PAGE105_I180@PURE_QUANTA.SCONN288_ADR50017P087CC(CHIPS)':
 'VSS69': CDS_PINID='VSS69';
NODE_NAME     J24 164
 '@S9S_MB_2U_LIB.S9S_MB_2U(SCH_1):PAGE105_I180@PURE_QUANTA.SCONN288_ADR50017P087CC(CHIPS)':
 'VSS70': CDS_PINID='VSS70';
NODE_NAME     J24 166
 '@S9S_MB_2U_LIB.S9S_MB_2U(SCH_1):PAGE105_I180@PURE_QUANTA.SCONN288_ADR50017P087CC(CHIPS)':
 'VSS71': CDS_PINID='VSS71';
NODE_NAME     J24 169
 '@S9S_MB_2U_LIB.S9S_MB_2U(SCH_1):PAGE105_I180@PURE_QUANTA.SCONN288_ADR50017P087CC(CHIPS)':
 'VSS72': CDS_PINID='VSS72';
NODE_NAME     J24 171
 '@S9S_MB_2U_LIB.S9S_MB_2U(SCH_1):PAGE105_I180@PURE_QUANTA.SCONN288_ADR50017P087CC(CHIPS)':
 'VSS73': CDS_PINID='VSS73';
NODE_NAME     J24 173
 '@S9S_MB_2U_LIB.S9S_MB_2U(SCH_1):PAGE105_I180@PURE_QUANTA.SCONN288_ADR50017P087CC(CHIPS)':
 'VSS74': CDS_PINID='VSS74';
NODE_NAME     J24 175
 '@S9S_MB_2U_LIB.S9S_MB_2U(SCH_1):PAGE105_I180@PURE_QUANTA.SCONN288_ADR50017P087CC(CHIPS)':
 'VSS75': CDS_PINID='VSS75';
NODE_NAME     J24 177
 '@S9S_MB_2U_LIB.S9S_MB_2U(SCH_1):PAGE105_I180@PURE_QUANTA.SCONN288_ADR50017P087CC(CHIPS)':
 'VSS76': CDS_PINID='VSS76';
NODE_NAME     J24 180
 '@S9S_MB_2U_LIB.S9S_MB_2U(SCH_1):PAGE105_I180@PURE_QUANTA.SCONN288_ADR50017P087CC(CHIPS)':
 'VSS77': CDS_PINID='VSS77';
NODE_NAME     J24 182
 '@S9S_MB_2U_LIB.S9S_MB_2U(SCH_1):PAGE105_I180@PURE_QUANTA.SCONN288_ADR50017P087CC(CHIPS)':
 'VSS78': CDS_PINID='VSS78';
NODE_NAME     J24 184
 '@S9S_MB_2U_LIB.S9S_MB_2U(SCH_1):PAGE105_I180@PURE_QUANTA.SCONN288_ADR50017P087CC(CHIPS)':
 'VSS79': CDS_PINID='VSS79';
NODE_NAME     J24 186
 '@S9S_MB_2U_LIB.S9S_MB_2U(SCH_1):PAGE105_I180@PURE_QUANTA.SCONN288_ADR50017P087CC(CHIPS)':
 'VSS80': CDS_PINID='VSS80';
NODE_NAME     J24 188
 '@S9S_MB_2U_LIB.S9S_MB_2U(SCH_1):PAGE105_I180@PURE_QUANTA.SCONN288_ADR50017P087CC(CHIPS)':
 'VSS81': CDS_PINID='VSS81';
NODE_NAME     J24 191
 '@S9S_MB_2U_LIB.S9S_MB_2U(SCH_1):PAGE105_I180@PURE_QUANTA.SCONN288_ADR50017P087CC(CHIPS)':
 'VSS82': CDS_PINID='VSS82';
NODE_NAME     J24 193
 '@S9S_MB_2U_LIB.S9S_MB_2U(SCH_1):PAGE105_I180@PURE_QUANTA.SCONN288_ADR50017P087CC(CHIPS)':
 'VSS83': CDS_PINID='VSS83';
NODE_NAME     J24 195
 '@S9S_MB_2U_LIB.S9S_MB_2U(SCH_1):PAGE105_I180@PURE_QUANTA.SCONN288_ADR50017P087CC(CHIPS)':
 'VSS84': CDS_PINID='VSS84';
NODE_NAME     J24 197
 '@S9S_MB_2U_LIB.S9S_MB_2U(SCH_1):PAGE105_I180@PURE_QUANTA.SCONN288_ADR50017P087CC(CHIPS)':
 'VSS85': CDS_PINID='VSS85';
NODE_NAME     J24 199
 '@S9S_MB_2U_LIB.S9S_MB_2U(SCH_1):PAGE105_I180@PURE_QUANTA.SCONN288_ADR50017P087CC(CHIPS)':
 'VSS86': CDS_PINID='VSS86';
NODE_NAME     J24 202
 '@S9S_MB_2U_LIB.S9S_MB_2U(SCH_1):PAGE105_I180@PURE_QUANTA.SCONN288_ADR50017P087CC(CHIPS)':
 'VSS87': CDS_PINID='VSS87';
NODE_NAME     J24 204
 '@S9S_MB_2U_LIB.S9S_MB_2U(SCH_1):PAGE105_I180@PURE_QUANTA.SCONN288_ADR50017P087CC(CHIPS)':
 'VSS88': CDS_PINID='VSS88';
NODE_NAME     J24 206
 '@S9S_MB_2U_LIB.S9S_MB_2U(SCH_1):PAGE105_I180@PURE_QUANTA.SCONN288_ADR50017P087CC(CHIPS)':
 'VSS89': CDS_PINID='VSS89';
NODE_NAME     J24 208
 '@S9S_MB_2U_LIB.S9S_MB_2U(SCH_1):PAGE105_I180@PURE_QUANTA.SCONN288_ADR50017P087CC(CHIPS)':
 'VSS90': CDS_PINID='VSS90';
NODE_NAME     J24 210
 '@S9S_MB_2U_LIB.S9S_MB_2U(SCH_1):PAGE105_I180@PURE_QUANTA.SCONN288_ADR50017P087CC(CHIPS)':
 'VSS91': CDS_PINID='VSS91';
NODE_NAME     J24 212
 '@S9S_MB_2U_LIB.S9S_MB_2U(SCH_1):PAGE105_I180@PURE_QUANTA.SCONN288_ADR50017P087CC(CHIPS)':
 'VSS92': CDS_PINID='VSS92';
NODE_NAME     J24 214
 '@S9S_MB_2U_LIB.S9S_MB_2U(SCH_1):PAGE105_I180@PURE_QUANTA.SCONN288_ADR50017P087CC(CHIPS)':
 'VSS93': CDS_PINID='VSS93';
NODE_NAME     J24 216
 '@S9S_MB_2U_LIB.S9S_MB_2U(SCH_1):PAGE105_I180@PURE_QUANTA.SCONN288_ADR50017P087CC(CHIPS)':
 'VSS94': CDS_PINID='VSS94';
NODE_NAME     J24 219
 '@S9S_MB_2U_LIB.S9S_MB_2U(SCH_1):PAGE105_I180@PURE_QUANTA.SCONN288_ADR50017P087CC(CHIPS)':
 'VSS95': CDS_PINID='VSS95';
NODE_NAME     J24 222
 '@S9S_MB_2U_LIB.S9S_MB_2U(SCH_1):PAGE105_I180@PURE_QUANTA.SCONN288_ADR50017P087CC(CHIPS)':
 'VSS96': CDS_PINID='VSS96';
NODE_NAME     J24 224
 '@S9S_MB_2U_LIB.S9S_MB_2U(SCH_1):PAGE105_I180@PURE_QUANTA.SCONN288_ADR50017P087CC(CHIPS)':
 'VSS97': CDS_PINID='VSS97';
NODE_NAME     J24 226
 '@S9S_MB_2U_LIB.S9S_MB_2U(SCH_1):PAGE105_I180@PURE_QUANTA.SCONN288_ADR50017P087CC(CHIPS)':
 'VSS98': CDS_PINID='VSS98';
NODE_NAME     J24 228
 '@S9S_MB_2U_LIB.S9S_MB_2U(SCH_1):PAGE105_I180@PURE_QUANTA.SCONN288_ADR50017P087CC(CHIPS)':
 'VSS99': CDS_PINID='VSS99';
NODE_NAME     J24 230
 '@S9S_MB_2U_LIB.S9S_MB_2U(SCH_1):PAGE105_I180@PURE_QUANTA.SCONN288_ADR50017P087CC(CHIPS)':
 'VSS100': CDS_PINID='VSS100';
NODE_NAME     J24 233
 '@S9S_MB_2U_LIB.S9S_MB_2U(SCH_1):PAGE105_I180@PURE_QUANTA.SCONN288_ADR50017P087CC(CHIPS)':
 'VSS101': CDS_PINID='VSS101';
NODE_NAME     J24 235
 '@S9S_MB_2U_LIB.S9S_MB_2U(SCH_1):PAGE105_I180@PURE_QUANTA.SCONN288_ADR50017P087CC(CHIPS)':
 'VSS102': CDS_PINID='VSS102';
NODE_NAME     J24 237
 '@S9S_MB_2U_LIB.S9S_MB_2U(SCH_1):PAGE105_I180@PURE_QUANTA.SCONN288_ADR50017P087CC(CHIPS)':
 'VSS103': CDS_PINID='VSS103';
NODE_NAME     J24 240
 '@S9S_MB_2U_LIB.S9S_MB_2U(SCH_1):PAGE105_I180@PURE_QUANTA.SCONN288_ADR50017P087CC(CHIPS)':
 'VSS104': CDS_PINID='VSS104';
NODE_NAME     J24 242
 '@S9S_MB_2U_LIB.S9S_MB_2U(SCH_1):PAGE105_I180@PURE_QUANTA.SCONN288_ADR50017P087CC(CHIPS)':
 'VSS105': CDS_PINID='VSS105';
NODE_NAME     J24 244
 '@S9S_MB_2U_LIB.S9S_MB_2U(SCH_1):PAGE105_I180@PURE_QUANTA.SCONN288_ADR50017P087CC(CHIPS)':
 'VSS106': CDS_PINID='VSS106';
NODE_NAME     J24 246
 '@S9S_MB_2U_LIB.S9S_MB_2U(SCH_1):PAGE105_I180@PURE_QUANTA.SCONN288_ADR50017P087CC(CHIPS)':
 'VSS107': CDS_PINID='VSS107';
NODE_NAME     J24 248
 '@S9S_MB_2U_LIB.S9S_MB_2U(SCH_1):PAGE105_I180@PURE_QUANTA.SCONN288_ADR50017P087CC(CHIPS)':
 'VSS108': CDS_PINID='VSS108';
NODE_NAME     J24 251
 '@S9S_MB_2U_LIB.S9S_MB_2U(SCH_1):PAGE105_I180@PURE_QUANTA.SCONN288_ADR50017P087CC(CHIPS)':
 'VSS109': CDS_PINID='VSS109';
NODE_NAME     J24 253
 '@S9S_MB_2U_LIB.S9S_MB_2U(SCH_1):PAGE105_I180@PURE_QUANTA.SCONN288_ADR50017P087CC(CHIPS)':
 'VSS110': CDS_PINID='VSS110';
NODE_NAME     J24 255
 '@S9S_MB_2U_LIB.S9S_MB_2U(SCH_1):PAGE105_I180@PURE_QUANTA.SCONN288_ADR50017P087CC(CHIPS)':
 'VSS111': CDS_PINID='VSS111';
NODE_NAME     J24 257
 '@S9S_MB_2U_LIB.S9S_MB_2U(SCH_1):PAGE105_I180@PURE_QUANTA.SCONN288_ADR50017P087CC(CHIPS)':
 'VSS112': CDS_PINID='VSS112';
NODE_NAME     J24 259
 '@S9S_MB_2U_LIB.S9S_MB_2U(SCH_1):PAGE105_I180@PURE_QUANTA.SCONN288_ADR50017P087CC(CHIPS)':
 'VSS113': CDS_PINID='VSS113';
NODE_NAME     J24 262
 '@S9S_MB_2U_LIB.S9S_MB_2U(SCH_1):PAGE105_I180@PURE_QUANTA.SCONN288_ADR50017P087CC(CHIPS)':
 'VSS114': CDS_PINID='VSS114';
NODE_NAME     J24 264
 '@S9S_MB_2U_LIB.S9S_MB_2U(SCH_1):PAGE105_I180@PURE_QUANTA.SCONN288_ADR50017P087CC(CHIPS)':
 'VSS115': CDS_PINID='VSS115';
NODE_NAME     J24 266
 '@S9S_MB_2U_LIB.S9S_MB_2U(SCH_1):PAGE105_I180@PURE_QUANTA.SCONN288_ADR50017P087CC(CHIPS)':
 'VSS116': CDS_PINID='VSS116';
NODE_NAME     J24 268
 '@S9S_MB_2U_LIB.S9S_MB_2U(SCH_1):PAGE105_I180@PURE_QUANTA.SCONN288_ADR50017P087CC(CHIPS)':
 'VSS117': CDS_PINID='VSS117';
NODE_NAME     J24 270
 '@S9S_MB_2U_LIB.S9S_MB_2U(SCH_1):PAGE105_I180@PURE_QUANTA.SCONN288_ADR50017P087CC(CHIPS)':
 'VSS118': CDS_PINID='VSS118';
NODE_NAME     J24 273
 '@S9S_MB_2U_LIB.S9S_MB_2U(SCH_1):PAGE105_I180@PURE_QUANTA.SCONN288_ADR50017P087CC(CHIPS)':
 'VSS119': CDS_PINID='VSS119';
NODE_NAME     J24 275
 '@S9S_MB_2U_LIB.S9S_MB_2U(SCH_1):PAGE105_I180@PURE_QUANTA.SCONN288_ADR50017P087CC(CHIPS)':
 'VSS120': CDS_PINID='VSS120';
NODE_NAME     J24 277
 '@S9S_MB_2U_LIB.S9S_MB_2U(SCH_1):PAGE105_I180@PURE_QUANTA.SCONN288_ADR50017P087CC(CHIPS)':
 'VSS121': CDS_PINID='VSS121';
NODE_NAME     J24 279
 '@S9S_MB_2U_LIB.S9S_MB_2U(SCH_1):PAGE105_I180@PURE_QUANTA.SCONN288_ADR50017P087CC(CHIPS)':
 'VSS122': CDS_PINID='VSS122';
NODE_NAME     J24 281
 '@S9S_MB_2U_LIB.S9S_MB_2U(SCH_1):PAGE105_I180@PURE_QUANTA.SCONN288_ADR50017P087CC(CHIPS)':
 'VSS123': CDS_PINID='VSS123';
NODE_NAME     J24 284
 '@S9S_MB_2U_LIB.S9S_MB_2U(SCH_1):PAGE105_I180@PURE_QUANTA.SCONN288_ADR50017P087CC(CHIPS)':
 'VSS124': CDS_PINID='VSS124';
NODE_NAME     J24 286
 '@S9S_MB_2U_LIB.S9S_MB_2U(SCH_1):PAGE105_I180@PURE_QUANTA.SCONN288_ADR50017P087CC(CHIPS)':
 'VSS125': CDS_PINID='VSS125';
NODE_NAME     J24 288
 '@S9S_MB_2U_LIB.S9S_MB_2U(SCH_1):PAGE105_I180@PURE_QUANTA.SCONN288_ADR50017P087CC(CHIPS)':
 'VSS126': CDS_PINID='VSS126';
NODE_NAME     R79 2
 '@S9S_MB_2U_LIB.S9S_MB_2U(SCH_1):PAGE106_I2@PURE_QUANTA.Q_RES(CHIPS)':
 'B': CDS_PINID='B';
NODE_NAME     C93 2
 '@S9S_MB_2U_LIB.S9S_MB_2U(SCH_1):PAGE106_I122@PURE_QUANTA.Q_CAP(CHIPS)':
 'B': CDS_PINID='B';
NODE_NAME     C94 2
 '@S9S_MB_2U_LIB.S9S_MB_2U(SCH_1):PAGE106_I127@PURE_QUANTA.Q_CAP(CHIPS)':
 'B': CDS_PINID='B';
NODE_NAME     C95 2
 '@S9S_MB_2U_LIB.S9S_MB_2U(SCH_1):PAGE106_I130@PURE_QUANTA.Q_CAP(CHIPS)':
 'B': CDS_PINID='B';
NODE_NAME     J25 G1
 '@S9S_MB_2U_LIB.S9S_MB_2U(SCH_1):PAGE106_I178@PURE_QUANTA.SCONN288_ADR50017P130CC(CHIPS)':
 'G1': CDS_PINID='G1';
NODE_NAME     J25 G2
 '@S9S_MB_2U_LIB.S9S_MB_2U(SCH_1):PAGE106_I178@PURE_QUANTA.SCONN288_ADR50017P130CC(CHIPS)':
 'G2': CDS_PINID='G2';
NODE_NAME     J25 G3
 '@S9S_MB_2U_LIB.S9S_MB_2U(SCH_1):PAGE106_I178@PURE_QUANTA.SCONN288_ADR50017P130CC(CHIPS)':
 'G3': CDS_PINID='G3';
NODE_NAME     J25 6
 '@S9S_MB_2U_LIB.S9S_MB_2U(SCH_1):PAGE106_I178@PURE_QUANTA.SCONN288_ADR50017P130CC(CHIPS)':
 'VSS0': CDS_PINID='VSS0';
NODE_NAME     J25 8
 '@S9S_MB_2U_LIB.S9S_MB_2U(SCH_1):PAGE106_I178@PURE_QUANTA.SCONN288_ADR50017P130CC(CHIPS)':
 'VSS1': CDS_PINID='VSS1';
NODE_NAME     J25 10
 '@S9S_MB_2U_LIB.S9S_MB_2U(SCH_1):PAGE106_I178@PURE_QUANTA.SCONN288_ADR50017P130CC(CHIPS)':
 'VSS2': CDS_PINID='VSS2';
NODE_NAME     J25 13
 '@S9S_MB_2U_LIB.S9S_MB_2U(SCH_1):PAGE106_I178@PURE_QUANTA.SCONN288_ADR50017P130CC(CHIPS)':
 'VSS3': CDS_PINID='VSS3';
NODE_NAME     J25 15
 '@S9S_MB_2U_LIB.S9S_MB_2U(SCH_1):PAGE106_I178@PURE_QUANTA.SCONN288_ADR50017P130CC(CHIPS)':
 'VSS4': CDS_PINID='VSS4';
NODE_NAME     J25 17
 '@S9S_MB_2U_LIB.S9S_MB_2U(SCH_1):PAGE106_I178@PURE_QUANTA.SCONN288_ADR50017P130CC(CHIPS)':
 'VSS5': CDS_PINID='VSS5';
NODE_NAME     J25 19
 '@S9S_MB_2U_LIB.S9S_MB_2U(SCH_1):PAGE106_I178@PURE_QUANTA.SCONN288_ADR50017P130CC(CHIPS)':
 'VSS6': CDS_PINID='VSS6';
NODE_NAME     J25 21
 '@S9S_MB_2U_LIB.S9S_MB_2U(SCH_1):PAGE106_I178@PURE_QUANTA.SCONN288_ADR50017P130CC(CHIPS)':
 'VSS7': CDS_PINID='VSS7';
NODE_NAME     J25 24
 '@S9S_MB_2U_LIB.S9S_MB_2U(SCH_1):PAGE106_I178@PURE_QUANTA.SCONN288_ADR50017P130CC(CHIPS)':
 'VSS8': CDS_PINID='VSS8';
NODE_NAME     J25 26
 '@S9S_MB_2U_LIB.S9S_MB_2U(SCH_1):PAGE106_I178@PURE_QUANTA.SCONN288_ADR50017P130CC(CHIPS)':
 'VSS9': CDS_PINID='VSS9';
NODE_NAME     J25 28
 '@S9S_MB_2U_LIB.S9S_MB_2U(SCH_1):PAGE106_I178@PURE_QUANTA.SCONN288_ADR50017P130CC(CHIPS)':
 'VSS10': CDS_PINID='VSS10';
NODE_NAME     J25 30
 '@S9S_MB_2U_LIB.S9S_MB_2U(SCH_1):PAGE106_I178@PURE_QUANTA.SCONN288_ADR50017P130CC(CHIPS)':
 'VSS11': CDS_PINID='VSS11';
NODE_NAME     J25 32
 '@S9S_MB_2U_LIB.S9S_MB_2U(SCH_1):PAGE106_I178@PURE_QUANTA.SCONN288_ADR50017P130CC(CHIPS)':
 'VSS12': CDS_PINID='VSS12';
NODE_NAME     J25 35
 '@S9S_MB_2U_LIB.S9S_MB_2U(SCH_1):PAGE106_I178@PURE_QUANTA.SCONN288_ADR50017P130CC(CHIPS)':
 'VSS13': CDS_PINID='VSS13';
NODE_NAME     J25 37
 '@S9S_MB_2U_LIB.S9S_MB_2U(SCH_1):PAGE106_I178@PURE_QUANTA.SCONN288_ADR50017P130CC(CHIPS)':
 'VSS14': CDS_PINID='VSS14';
NODE_NAME     J25 39
 '@S9S_MB_2U_LIB.S9S_MB_2U(SCH_1):PAGE106_I178@PURE_QUANTA.SCONN288_ADR50017P130CC(CHIPS)':
 'VSS15': CDS_PINID='VSS15';
NODE_NAME     J25 41
 '@S9S_MB_2U_LIB.S9S_MB_2U(SCH_1):PAGE106_I178@PURE_QUANTA.SCONN288_ADR50017P130CC(CHIPS)':
 'VSS16': CDS_PINID='VSS16';
NODE_NAME     J25 43
 '@S9S_MB_2U_LIB.S9S_MB_2U(SCH_1):PAGE106_I178@PURE_QUANTA.SCONN288_ADR50017P130CC(CHIPS)':
 'VSS17': CDS_PINID='VSS17';
NODE_NAME     J25 46
 '@S9S_MB_2U_LIB.S9S_MB_2U(SCH_1):PAGE106_I178@PURE_QUANTA.SCONN288_ADR50017P130CC(CHIPS)':
 'VSS18': CDS_PINID='VSS18';
NODE_NAME     J25 48
 '@S9S_MB_2U_LIB.S9S_MB_2U(SCH_1):PAGE106_I178@PURE_QUANTA.SCONN288_ADR50017P130CC(CHIPS)':
 'VSS19': CDS_PINID='VSS19';
NODE_NAME     J25 50
 '@S9S_MB_2U_LIB.S9S_MB_2U(SCH_1):PAGE106_I178@PURE_QUANTA.SCONN288_ADR50017P130CC(CHIPS)':
 'VSS20': CDS_PINID='VSS20';
NODE_NAME     J25 52
 '@S9S_MB_2U_LIB.S9S_MB_2U(SCH_1):PAGE106_I178@PURE_QUANTA.SCONN288_ADR50017P130CC(CHIPS)':
 'VSS21': CDS_PINID='VSS21';
NODE_NAME     J25 54
 '@S9S_MB_2U_LIB.S9S_MB_2U(SCH_1):PAGE106_I178@PURE_QUANTA.SCONN288_ADR50017P130CC(CHIPS)':
 'VSS22': CDS_PINID='VSS22';
NODE_NAME     J25 57
 '@S9S_MB_2U_LIB.S9S_MB_2U(SCH_1):PAGE106_I178@PURE_QUANTA.SCONN288_ADR50017P130CC(CHIPS)':
 'VSS23': CDS_PINID='VSS23';
NODE_NAME     J25 59
 '@S9S_MB_2U_LIB.S9S_MB_2U(SCH_1):PAGE106_I178@PURE_QUANTA.SCONN288_ADR50017P130CC(CHIPS)':
 'VSS24': CDS_PINID='VSS24';
NODE_NAME     J25 61
 '@S9S_MB_2U_LIB.S9S_MB_2U(SCH_1):PAGE106_I178@PURE_QUANTA.SCONN288_ADR50017P130CC(CHIPS)':
 'VSS25': CDS_PINID='VSS25';
NODE_NAME     J25 63
 '@S9S_MB_2U_LIB.S9S_MB_2U(SCH_1):PAGE106_I178@PURE_QUANTA.SCONN288_ADR50017P130CC(CHIPS)':
 'VSS26': CDS_PINID='VSS26';
NODE_NAME     J25 65
 '@S9S_MB_2U_LIB.S9S_MB_2U(SCH_1):PAGE106_I178@PURE_QUANTA.SCONN288_ADR50017P130CC(CHIPS)':
 'VSS27': CDS_PINID='VSS27';
NODE_NAME     J25 67
 '@S9S_MB_2U_LIB.S9S_MB_2U(SCH_1):PAGE106_I178@PURE_QUANTA.SCONN288_ADR50017P130CC(CHIPS)':
 'VSS28': CDS_PINID='VSS28';
NODE_NAME     J25 69
 '@S9S_MB_2U_LIB.S9S_MB_2U(SCH_1):PAGE106_I178@PURE_QUANTA.SCONN288_ADR50017P130CC(CHIPS)':
 'VSS29': CDS_PINID='VSS29';
NODE_NAME     J25 71
 '@S9S_MB_2U_LIB.S9S_MB_2U(SCH_1):PAGE106_I178@PURE_QUANTA.SCONN288_ADR50017P130CC(CHIPS)':
 'VSS30': CDS_PINID='VSS30';
NODE_NAME     J25 73
 '@S9S_MB_2U_LIB.S9S_MB_2U(SCH_1):PAGE106_I178@PURE_QUANTA.SCONN288_ADR50017P130CC(CHIPS)':
 'VSS31': CDS_PINID='VSS31';
NODE_NAME     J25 75
 '@S9S_MB_2U_LIB.S9S_MB_2U(SCH_1):PAGE106_I178@PURE_QUANTA.SCONN288_ADR50017P130CC(CHIPS)':
 'VSS32': CDS_PINID='VSS32';
NODE_NAME     J25 77
 '@S9S_MB_2U_LIB.S9S_MB_2U(SCH_1):PAGE106_I178@PURE_QUANTA.SCONN288_ADR50017P130CC(CHIPS)':
 'VSS33': CDS_PINID='VSS33';
NODE_NAME     J25 79
 '@S9S_MB_2U_LIB.S9S_MB_2U(SCH_1):PAGE106_I178@PURE_QUANTA.SCONN288_ADR50017P130CC(CHIPS)':
 'VSS34': CDS_PINID='VSS34';
NODE_NAME     J25 81
 '@S9S_MB_2U_LIB.S9S_MB_2U(SCH_1):PAGE106_I178@PURE_QUANTA.SCONN288_ADR50017P130CC(CHIPS)':
 'VSS35': CDS_PINID='VSS35';
NODE_NAME     J25 83
 '@S9S_MB_2U_LIB.S9S_MB_2U(SCH_1):PAGE106_I178@PURE_QUANTA.SCONN288_ADR50017P130CC(CHIPS)':
 'VSS36': CDS_PINID='VSS36';
NODE_NAME     J25 85
 '@S9S_MB_2U_LIB.S9S_MB_2U(SCH_1):PAGE106_I178@PURE_QUANTA.SCONN288_ADR50017P130CC(CHIPS)':
 'VSS37': CDS_PINID='VSS37';
NODE_NAME     J25 88
 '@S9S_MB_2U_LIB.S9S_MB_2U(SCH_1):PAGE106_I178@PURE_QUANTA.SCONN288_ADR50017P130CC(CHIPS)':
 'VSS38': CDS_PINID='VSS38';
NODE_NAME     J25 90
 '@S9S_MB_2U_LIB.S9S_MB_2U(SCH_1):PAGE106_I178@PURE_QUANTA.SCONN288_ADR50017P130CC(CHIPS)':
 'VSS39': CDS_PINID='VSS39';
NODE_NAME     J25 92
 '@S9S_MB_2U_LIB.S9S_MB_2U(SCH_1):PAGE106_I178@PURE_QUANTA.SCONN288_ADR50017P130CC(CHIPS)':
 'VSS40': CDS_PINID='VSS40';
NODE_NAME     J25 95
 '@S9S_MB_2U_LIB.S9S_MB_2U(SCH_1):PAGE106_I178@PURE_QUANTA.SCONN288_ADR50017P130CC(CHIPS)':
 'VSS41': CDS_PINID='VSS41';
NODE_NAME     J25 97
 '@S9S_MB_2U_LIB.S9S_MB_2U(SCH_1):PAGE106_I178@PURE_QUANTA.SCONN288_ADR50017P130CC(CHIPS)':
 'VSS42': CDS_PINID='VSS42';
NODE_NAME     J25 99
 '@S9S_MB_2U_LIB.S9S_MB_2U(SCH_1):PAGE106_I178@PURE_QUANTA.SCONN288_ADR50017P130CC(CHIPS)':
 'VSS43': CDS_PINID='VSS43';
NODE_NAME     J25 101
 '@S9S_MB_2U_LIB.S9S_MB_2U(SCH_1):PAGE106_I178@PURE_QUANTA.SCONN288_ADR50017P130CC(CHIPS)':
 'VSS44': CDS_PINID='VSS44';
NODE_NAME     J25 103
 '@S9S_MB_2U_LIB.S9S_MB_2U(SCH_1):PAGE106_I178@PURE_QUANTA.SCONN288_ADR50017P130CC(CHIPS)':
 'VSS45': CDS_PINID='VSS45';
NODE_NAME     J25 106
 '@S9S_MB_2U_LIB.S9S_MB_2U(SCH_1):PAGE106_I178@PURE_QUANTA.SCONN288_ADR50017P130CC(CHIPS)':
 'VSS46': CDS_PINID='VSS46';
NODE_NAME     J25 108
 '@S9S_MB_2U_LIB.S9S_MB_2U(SCH_1):PAGE106_I178@PURE_QUANTA.SCONN288_ADR50017P130CC(CHIPS)':
 'VSS47': CDS_PINID='VSS47';
NODE_NAME     J25 110
 '@S9S_MB_2U_LIB.S9S_MB_2U(SCH_1):PAGE106_I178@PURE_QUANTA.SCONN288_ADR50017P130CC(CHIPS)':
 'VSS48': CDS_PINID='VSS48';
NODE_NAME     J25 112
 '@S9S_MB_2U_LIB.S9S_MB_2U(SCH_1):PAGE106_I178@PURE_QUANTA.SCONN288_ADR50017P130CC(CHIPS)':
 'VSS49': CDS_PINID='VSS49';
NODE_NAME     J25 114
 '@S9S_MB_2U_LIB.S9S_MB_2U(SCH_1):PAGE106_I178@PURE_QUANTA.SCONN288_ADR50017P130CC(CHIPS)':
 'VSS50': CDS_PINID='VSS50';
NODE_NAME     J25 117
 '@S9S_MB_2U_LIB.S9S_MB_2U(SCH_1):PAGE106_I178@PURE_QUANTA.SCONN288_ADR50017P130CC(CHIPS)':
 'VSS51': CDS_PINID='VSS51';
NODE_NAME     J25 119
 '@S9S_MB_2U_LIB.S9S_MB_2U(SCH_1):PAGE106_I178@PURE_QUANTA.SCONN288_ADR50017P130CC(CHIPS)':
 'VSS52': CDS_PINID='VSS52';
NODE_NAME     J25 121
 '@S9S_MB_2U_LIB.S9S_MB_2U(SCH_1):PAGE106_I178@PURE_QUANTA.SCONN288_ADR50017P130CC(CHIPS)':
 'VSS53': CDS_PINID='VSS53';
NODE_NAME     J25 123
 '@S9S_MB_2U_LIB.S9S_MB_2U(SCH_1):PAGE106_I178@PURE_QUANTA.SCONN288_ADR50017P130CC(CHIPS)':
 'VSS54': CDS_PINID='VSS54';
NODE_NAME     J25 125
 '@S9S_MB_2U_LIB.S9S_MB_2U(SCH_1):PAGE106_I178@PURE_QUANTA.SCONN288_ADR50017P130CC(CHIPS)':
 'VSS55': CDS_PINID='VSS55';
NODE_NAME     J25 128
 '@S9S_MB_2U_LIB.S9S_MB_2U(SCH_1):PAGE106_I178@PURE_QUANTA.SCONN288_ADR50017P130CC(CHIPS)':
 'VSS56': CDS_PINID='VSS56';
NODE_NAME     J25 130
 '@S9S_MB_2U_LIB.S9S_MB_2U(SCH_1):PAGE106_I178@PURE_QUANTA.SCONN288_ADR50017P130CC(CHIPS)':
 'VSS57': CDS_PINID='VSS57';
NODE_NAME     J25 132
 '@S9S_MB_2U_LIB.S9S_MB_2U(SCH_1):PAGE106_I178@PURE_QUANTA.SCONN288_ADR50017P130CC(CHIPS)':
 'VSS58': CDS_PINID='VSS58';
NODE_NAME     J25 134
 '@S9S_MB_2U_LIB.S9S_MB_2U(SCH_1):PAGE106_I178@PURE_QUANTA.SCONN288_ADR50017P130CC(CHIPS)':
 'VSS59': CDS_PINID='VSS59';
NODE_NAME     J25 136
 '@S9S_MB_2U_LIB.S9S_MB_2U(SCH_1):PAGE106_I178@PURE_QUANTA.SCONN288_ADR50017P130CC(CHIPS)':
 'VSS60': CDS_PINID='VSS60';
NODE_NAME     J25 139
 '@S9S_MB_2U_LIB.S9S_MB_2U(SCH_1):PAGE106_I178@PURE_QUANTA.SCONN288_ADR50017P130CC(CHIPS)':
 'VSS61': CDS_PINID='VSS61';
NODE_NAME     J25 141
 '@S9S_MB_2U_LIB.S9S_MB_2U(SCH_1):PAGE106_I178@PURE_QUANTA.SCONN288_ADR50017P130CC(CHIPS)':
 'VSS62': CDS_PINID='VSS62';
NODE_NAME     J25 143
 '@S9S_MB_2U_LIB.S9S_MB_2U(SCH_1):PAGE106_I178@PURE_QUANTA.SCONN288_ADR50017P130CC(CHIPS)':
 'VSS63': CDS_PINID='VSS63';
NODE_NAME     J25 151
 '@S9S_MB_2U_LIB.S9S_MB_2U(SCH_1):PAGE106_I178@PURE_QUANTA.SCONN288_ADR50017P130CC(CHIPS)':
 'VSS64': CDS_PINID='VSS64';
NODE_NAME     J25 153
 '@S9S_MB_2U_LIB.S9S_MB_2U(SCH_1):PAGE106_I178@PURE_QUANTA.SCONN288_ADR50017P130CC(CHIPS)':
 'VSS65': CDS_PINID='VSS65';
NODE_NAME     J25 155
 '@S9S_MB_2U_LIB.S9S_MB_2U(SCH_1):PAGE106_I178@PURE_QUANTA.SCONN288_ADR50017P130CC(CHIPS)':
 'VSS66': CDS_PINID='VSS66';
NODE_NAME     J25 158
 '@S9S_MB_2U_LIB.S9S_MB_2U(SCH_1):PAGE106_I178@PURE_QUANTA.SCONN288_ADR50017P130CC(CHIPS)':
 'VSS67': CDS_PINID='VSS67';
NODE_NAME     J25 160
 '@S9S_MB_2U_LIB.S9S_MB_2U(SCH_1):PAGE106_I178@PURE_QUANTA.SCONN288_ADR50017P130CC(CHIPS)':
 'VSS68': CDS_PINID='VSS68';
NODE_NAME     J25 162
 '@S9S_MB_2U_LIB.S9S_MB_2U(SCH_1):PAGE106_I178@PURE_QUANTA.SCONN288_ADR50017P130CC(CHIPS)':
 'VSS69': CDS_PINID='VSS69';
NODE_NAME     J25 164
 '@S9S_MB_2U_LIB.S9S_MB_2U(SCH_1):PAGE106_I178@PURE_QUANTA.SCONN288_ADR50017P130CC(CHIPS)':
 'VSS70': CDS_PINID='VSS70';
NODE_NAME     J25 166
 '@S9S_MB_2U_LIB.S9S_MB_2U(SCH_1):PAGE106_I178@PURE_QUANTA.SCONN288_ADR50017P130CC(CHIPS)':
 'VSS71': CDS_PINID='VSS71';
NODE_NAME     J25 169
 '@S9S_MB_2U_LIB.S9S_MB_2U(SCH_1):PAGE106_I178@PURE_QUANTA.SCONN288_ADR50017P130CC(CHIPS)':
 'VSS72': CDS_PINID='VSS72';
NODE_NAME     J25 171
 '@S9S_MB_2U_LIB.S9S_MB_2U(SCH_1):PAGE106_I178@PURE_QUANTA.SCONN288_ADR50017P130CC(CHIPS)':
 'VSS73': CDS_PINID='VSS73';
NODE_NAME     J25 173
 '@S9S_MB_2U_LIB.S9S_MB_2U(SCH_1):PAGE106_I178@PURE_QUANTA.SCONN288_ADR50017P130CC(CHIPS)':
 'VSS74': CDS_PINID='VSS74';
NODE_NAME     J25 175
 '@S9S_MB_2U_LIB.S9S_MB_2U(SCH_1):PAGE106_I178@PURE_QUANTA.SCONN288_ADR50017P130CC(CHIPS)':
 'VSS75': CDS_PINID='VSS75';
NODE_NAME     J25 177
 '@S9S_MB_2U_LIB.S9S_MB_2U(SCH_1):PAGE106_I178@PURE_QUANTA.SCONN288_ADR50017P130CC(CHIPS)':
 'VSS76': CDS_PINID='VSS76';
NODE_NAME     J25 180
 '@S9S_MB_2U_LIB.S9S_MB_2U(SCH_1):PAGE106_I178@PURE_QUANTA.SCONN288_ADR50017P130CC(CHIPS)':
 'VSS77': CDS_PINID='VSS77';
NODE_NAME     J25 182
 '@S9S_MB_2U_LIB.S9S_MB_2U(SCH_1):PAGE106_I178@PURE_QUANTA.SCONN288_ADR50017P130CC(CHIPS)':
 'VSS78': CDS_PINID='VSS78';
NODE_NAME     J25 184
 '@S9S_MB_2U_LIB.S9S_MB_2U(SCH_1):PAGE106_I178@PURE_QUANTA.SCONN288_ADR50017P130CC(CHIPS)':
 'VSS79': CDS_PINID='VSS79';
NODE_NAME     J25 186
 '@S9S_MB_2U_LIB.S9S_MB_2U(SCH_1):PAGE106_I178@PURE_QUANTA.SCONN288_ADR50017P130CC(CHIPS)':
 'VSS80': CDS_PINID='VSS80';
NODE_NAME     J25 188
 '@S9S_MB_2U_LIB.S9S_MB_2U(SCH_1):PAGE106_I178@PURE_QUANTA.SCONN288_ADR50017P130CC(CHIPS)':
 'VSS81': CDS_PINID='VSS81';
NODE_NAME     J25 191
 '@S9S_MB_2U_LIB.S9S_MB_2U(SCH_1):PAGE106_I178@PURE_QUANTA.SCONN288_ADR50017P130CC(CHIPS)':
 'VSS82': CDS_PINID='VSS82';
NODE_NAME     J25 193
 '@S9S_MB_2U_LIB.S9S_MB_2U(SCH_1):PAGE106_I178@PURE_QUANTA.SCONN288_ADR50017P130CC(CHIPS)':
 'VSS83': CDS_PINID='VSS83';
NODE_NAME     J25 195
 '@S9S_MB_2U_LIB.S9S_MB_2U(SCH_1):PAGE106_I178@PURE_QUANTA.SCONN288_ADR50017P130CC(CHIPS)':
 'VSS84': CDS_PINID='VSS84';
NODE_NAME     J25 197
 '@S9S_MB_2U_LIB.S9S_MB_2U(SCH_1):PAGE106_I178@PURE_QUANTA.SCONN288_ADR50017P130CC(CHIPS)':
 'VSS85': CDS_PINID='VSS85';
NODE_NAME     J25 199
 '@S9S_MB_2U_LIB.S9S_MB_2U(SCH_1):PAGE106_I178@PURE_QUANTA.SCONN288_ADR50017P130CC(CHIPS)':
 'VSS86': CDS_PINID='VSS86';
NODE_NAME     J25 202
 '@S9S_MB_2U_LIB.S9S_MB_2U(SCH_1):PAGE106_I178@PURE_QUANTA.SCONN288_ADR50017P130CC(CHIPS)':
 'VSS87': CDS_PINID='VSS87';
NODE_NAME     J25 204
 '@S9S_MB_2U_LIB.S9S_MB_2U(SCH_1):PAGE106_I178@PURE_QUANTA.SCONN288_ADR50017P130CC(CHIPS)':
 'VSS88': CDS_PINID='VSS88';
NODE_NAME     J25 206
 '@S9S_MB_2U_LIB.S9S_MB_2U(SCH_1):PAGE106_I178@PURE_QUANTA.SCONN288_ADR50017P130CC(CHIPS)':
 'VSS89': CDS_PINID='VSS89';
NODE_NAME     J25 208
 '@S9S_MB_2U_LIB.S9S_MB_2U(SCH_1):PAGE106_I178@PURE_QUANTA.SCONN288_ADR50017P130CC(CHIPS)':
 'VSS90': CDS_PINID='VSS90';
NODE_NAME     J25 210
 '@S9S_MB_2U_LIB.S9S_MB_2U(SCH_1):PAGE106_I178@PURE_QUANTA.SCONN288_ADR50017P130CC(CHIPS)':
 'VSS91': CDS_PINID='VSS91';
NODE_NAME     J25 212
 '@S9S_MB_2U_LIB.S9S_MB_2U(SCH_1):PAGE106_I178@PURE_QUANTA.SCONN288_ADR50017P130CC(CHIPS)':
 'VSS92': CDS_PINID='VSS92';
NODE_NAME     J25 214
 '@S9S_MB_2U_LIB.S9S_MB_2U(SCH_1):PAGE106_I178@PURE_QUANTA.SCONN288_ADR50017P130CC(CHIPS)':
 'VSS93': CDS_PINID='VSS93';
NODE_NAME     J25 216
 '@S9S_MB_2U_LIB.S9S_MB_2U(SCH_1):PAGE106_I178@PURE_QUANTA.SCONN288_ADR50017P130CC(CHIPS)':
 'VSS94': CDS_PINID='VSS94';
NODE_NAME     J25 219
 '@S9S_MB_2U_LIB.S9S_MB_2U(SCH_1):PAGE106_I178@PURE_QUANTA.SCONN288_ADR50017P130CC(CHIPS)':
 'VSS95': CDS_PINID='VSS95';
NODE_NAME     J25 222
 '@S9S_MB_2U_LIB.S9S_MB_2U(SCH_1):PAGE106_I178@PURE_QUANTA.SCONN288_ADR50017P130CC(CHIPS)':
 'VSS96': CDS_PINID='VSS96';
NODE_NAME     J25 224
 '@S9S_MB_2U_LIB.S9S_MB_2U(SCH_1):PAGE106_I178@PURE_QUANTA.SCONN288_ADR50017P130CC(CHIPS)':
 'VSS97': CDS_PINID='VSS97';
NODE_NAME     J25 226
 '@S9S_MB_2U_LIB.S9S_MB_2U(SCH_1):PAGE106_I178@PURE_QUANTA.SCONN288_ADR50017P130CC(CHIPS)':
 'VSS98': CDS_PINID='VSS98';
NODE_NAME     J25 228
 '@S9S_MB_2U_LIB.S9S_MB_2U(SCH_1):PAGE106_I178@PURE_QUANTA.SCONN288_ADR50017P130CC(CHIPS)':
 'VSS99': CDS_PINID='VSS99';
NODE_NAME     J25 230
 '@S9S_MB_2U_LIB.S9S_MB_2U(SCH_1):PAGE106_I178@PURE_QUANTA.SCONN288_ADR50017P130CC(CHIPS)':
 'VSS100': CDS_PINID='VSS100';
NODE_NAME     J25 233
 '@S9S_MB_2U_LIB.S9S_MB_2U(SCH_1):PAGE106_I178@PURE_QUANTA.SCONN288_ADR50017P130CC(CHIPS)':
 'VSS101': CDS_PINID='VSS101';
NODE_NAME     J25 235
 '@S9S_MB_2U_LIB.S9S_MB_2U(SCH_1):PAGE106_I178@PURE_QUANTA.SCONN288_ADR50017P130CC(CHIPS)':
 'VSS102': CDS_PINID='VSS102';
NODE_NAME     J25 237
 '@S9S_MB_2U_LIB.S9S_MB_2U(SCH_1):PAGE106_I178@PURE_QUANTA.SCONN288_ADR50017P130CC(CHIPS)':
 'VSS103': CDS_PINID='VSS103';
NODE_NAME     J25 240
 '@S9S_MB_2U_LIB.S9S_MB_2U(SCH_1):PAGE106_I178@PURE_QUANTA.SCONN288_ADR50017P130CC(CHIPS)':
 'VSS104': CDS_PINID='VSS104';
NODE_NAME     J25 242
 '@S9S_MB_2U_LIB.S9S_MB_2U(SCH_1):PAGE106_I178@PURE_QUANTA.SCONN288_ADR50017P130CC(CHIPS)':
 'VSS105': CDS_PINID='VSS105';
NODE_NAME     J25 244
 '@S9S_MB_2U_LIB.S9S_MB_2U(SCH_1):PAGE106_I178@PURE_QUANTA.SCONN288_ADR50017P130CC(CHIPS)':
 'VSS106': CDS_PINID='VSS106';
NODE_NAME     J25 246
 '@S9S_MB_2U_LIB.S9S_MB_2U(SCH_1):PAGE106_I178@PURE_QUANTA.SCONN288_ADR50017P130CC(CHIPS)':
 'VSS107': CDS_PINID='VSS107';
NODE_NAME     J25 248
 '@S9S_MB_2U_LIB.S9S_MB_2U(SCH_1):PAGE106_I178@PURE_QUANTA.SCONN288_ADR50017P130CC(CHIPS)':
 'VSS108': CDS_PINID='VSS108';
NODE_NAME     J25 251
 '@S9S_MB_2U_LIB.S9S_MB_2U(SCH_1):PAGE106_I178@PURE_QUANTA.SCONN288_ADR50017P130CC(CHIPS)':
 'VSS109': CDS_PINID='VSS109';
NODE_NAME     J25 253
 '@S9S_MB_2U_LIB.S9S_MB_2U(SCH_1):PAGE106_I178@PURE_QUANTA.SCONN288_ADR50017P130CC(CHIPS)':
 'VSS110': CDS_PINID='VSS110';
NODE_NAME     J25 255
 '@S9S_MB_2U_LIB.S9S_MB_2U(SCH_1):PAGE106_I178@PURE_QUANTA.SCONN288_ADR50017P130CC(CHIPS)':
 'VSS111': CDS_PINID='VSS111';
NODE_NAME     J25 257
 '@S9S_MB_2U_LIB.S9S_MB_2U(SCH_1):PAGE106_I178@PURE_QUANTA.SCONN288_ADR50017P130CC(CHIPS)':
 'VSS112': CDS_PINID='VSS112';
NODE_NAME     J25 259
 '@S9S_MB_2U_LIB.S9S_MB_2U(SCH_1):PAGE106_I178@PURE_QUANTA.SCONN288_ADR50017P130CC(CHIPS)':
 'VSS113': CDS_PINID='VSS113';
NODE_NAME     J25 262
 '@S9S_MB_2U_LIB.S9S_MB_2U(SCH_1):PAGE106_I178@PURE_QUANTA.SCONN288_ADR50017P130CC(CHIPS)':
 'VSS114': CDS_PINID='VSS114';
NODE_NAME     J25 264
 '@S9S_MB_2U_LIB.S9S_MB_2U(SCH_1):PAGE106_I178@PURE_QUANTA.SCONN288_ADR50017P130CC(CHIPS)':
 'VSS115': CDS_PINID='VSS115';
NODE_NAME     J25 266
 '@S9S_MB_2U_LIB.S9S_MB_2U(SCH_1):PAGE106_I178@PURE_QUANTA.SCONN288_ADR50017P130CC(CHIPS)':
 'VSS116': CDS_PINID='VSS116';
NODE_NAME     J25 268
 '@S9S_MB_2U_LIB.S9S_MB_2U(SCH_1):PAGE106_I178@PURE_QUANTA.SCONN288_ADR50017P130CC(CHIPS)':
 'VSS117': CDS_PINID='VSS117';
NODE_NAME     J25 270
 '@S9S_MB_2U_LIB.S9S_MB_2U(SCH_1):PAGE106_I178@PURE_QUANTA.SCONN288_ADR50017P130CC(CHIPS)':
 'VSS118': CDS_PINID='VSS118';
NODE_NAME     J25 273
 '@S9S_MB_2U_LIB.S9S_MB_2U(SCH_1):PAGE106_I178@PURE_QUANTA.SCONN288_ADR50017P130CC(CHIPS)':
 'VSS119': CDS_PINID='VSS119';
NODE_NAME     J25 275
 '@S9S_MB_2U_LIB.S9S_MB_2U(SCH_1):PAGE106_I178@PURE_QUANTA.SCONN288_ADR50017P130CC(CHIPS)':
 'VSS120': CDS_PINID='VSS120';
NODE_NAME     J25 277
 '@S9S_MB_2U_LIB.S9S_MB_2U(SCH_1):PAGE106_I178@PURE_QUANTA.SCONN288_ADR50017P130CC(CHIPS)':
 'VSS121': CDS_PINID='VSS121';
NODE_NAME     J25 279
 '@S9S_MB_2U_LIB.S9S_MB_2U(SCH_1):PAGE106_I178@PURE_QUANTA.SCONN288_ADR50017P130CC(CHIPS)':
 'VSS122': CDS_PINID='VSS122';
NODE_NAME     J25 281
 '@S9S_MB_2U_LIB.S9S_MB_2U(SCH_1):PAGE106_I178@PURE_QUANTA.SCONN288_ADR50017P130CC(CHIPS)':
 'VSS123': CDS_PINID='VSS123';
NODE_NAME     J25 284
 '@S9S_MB_2U_LIB.S9S_MB_2U(SCH_1):PAGE106_I178@PURE_QUANTA.SCONN288_ADR50017P130CC(CHIPS)':
 'VSS124': CDS_PINID='VSS124';
NODE_NAME     J25 286
 '@S9S_MB_2U_LIB.S9S_MB_2U(SCH_1):PAGE106_I178@PURE_QUANTA.SCONN288_ADR50017P130CC(CHIPS)':
 'VSS125': CDS_PINID='VSS125';
NODE_NAME     J25 288
 '@S9S_MB_2U_LIB.S9S_MB_2U(SCH_1):PAGE106_I178@PURE_QUANTA.SCONN288_ADR50017P130CC(CHIPS)':
 'VSS126': CDS_PINID='VSS126';
NODE_NAME     R78 2
 '@S9S_MB_2U_LIB.S9S_MB_2U(SCH_1):PAGE107_I2@PURE_QUANTA.Q_RES(CHIPS)':
 'B': CDS_PINID='B';
NODE_NAME     C90 2
 '@S9S_MB_2U_LIB.S9S_MB_2U(SCH_1):PAGE107_I122@PURE_QUANTA.Q_CAP(CHIPS)':
 'B': CDS_PINID='B';
NODE_NAME     C91 2
 '@S9S_MB_2U_LIB.S9S_MB_2U(SCH_1):PAGE107_I126@PURE_QUANTA.Q_CAP(CHIPS)':
 'B': CDS_PINID='B';
NODE_NAME     C92 2
 '@S9S_MB_2U_LIB.S9S_MB_2U(SCH_1):PAGE107_I128@PURE_QUANTA.Q_CAP(CHIPS)':
 'B': CDS_PINID='B';
NODE_NAME     J26 G1
 '@S9S_MB_2U_LIB.S9S_MB_2U(SCH_1):PAGE107_I179@PURE_QUANTA.SCONN288_ADR50017P087CC(CHIPS)':
 'G1': CDS_PINID='G1';
NODE_NAME     J26 G2
 '@S9S_MB_2U_LIB.S9S_MB_2U(SCH_1):PAGE107_I179@PURE_QUANTA.SCONN288_ADR50017P087CC(CHIPS)':
 'G2': CDS_PINID='G2';
NODE_NAME     J26 G3
 '@S9S_MB_2U_LIB.S9S_MB_2U(SCH_1):PAGE107_I179@PURE_QUANTA.SCONN288_ADR50017P087CC(CHIPS)':
 'G3': CDS_PINID='G3';
NODE_NAME     J26 6
 '@S9S_MB_2U_LIB.S9S_MB_2U(SCH_1):PAGE107_I179@PURE_QUANTA.SCONN288_ADR50017P087CC(CHIPS)':
 'VSS0': CDS_PINID='VSS0';
NODE_NAME     J26 8
 '@S9S_MB_2U_LIB.S9S_MB_2U(SCH_1):PAGE107_I179@PURE_QUANTA.SCONN288_ADR50017P087CC(CHIPS)':
 'VSS1': CDS_PINID='VSS1';
NODE_NAME     J26 10
 '@S9S_MB_2U_LIB.S9S_MB_2U(SCH_1):PAGE107_I179@PURE_QUANTA.SCONN288_ADR50017P087CC(CHIPS)':
 'VSS2': CDS_PINID='VSS2';
NODE_NAME     J26 13
 '@S9S_MB_2U_LIB.S9S_MB_2U(SCH_1):PAGE107_I179@PURE_QUANTA.SCONN288_ADR50017P087CC(CHIPS)':
 'VSS3': CDS_PINID='VSS3';
NODE_NAME     J26 15
 '@S9S_MB_2U_LIB.S9S_MB_2U(SCH_1):PAGE107_I179@PURE_QUANTA.SCONN288_ADR50017P087CC(CHIPS)':
 'VSS4': CDS_PINID='VSS4';
NODE_NAME     J26 17
 '@S9S_MB_2U_LIB.S9S_MB_2U(SCH_1):PAGE107_I179@PURE_QUANTA.SCONN288_ADR50017P087CC(CHIPS)':
 'VSS5': CDS_PINID='VSS5';
NODE_NAME     J26 19
 '@S9S_MB_2U_LIB.S9S_MB_2U(SCH_1):PAGE107_I179@PURE_QUANTA.SCONN288_ADR50017P087CC(CHIPS)':
 'VSS6': CDS_PINID='VSS6';
NODE_NAME     J26 21
 '@S9S_MB_2U_LIB.S9S_MB_2U(SCH_1):PAGE107_I179@PURE_QUANTA.SCONN288_ADR50017P087CC(CHIPS)':
 'VSS7': CDS_PINID='VSS7';
NODE_NAME     J26 24
 '@S9S_MB_2U_LIB.S9S_MB_2U(SCH_1):PAGE107_I179@PURE_QUANTA.SCONN288_ADR50017P087CC(CHIPS)':
 'VSS8': CDS_PINID='VSS8';
NODE_NAME     J26 26
 '@S9S_MB_2U_LIB.S9S_MB_2U(SCH_1):PAGE107_I179@PURE_QUANTA.SCONN288_ADR50017P087CC(CHIPS)':
 'VSS9': CDS_PINID='VSS9';
NODE_NAME     J26 28
 '@S9S_MB_2U_LIB.S9S_MB_2U(SCH_1):PAGE107_I179@PURE_QUANTA.SCONN288_ADR50017P087CC(CHIPS)':
 'VSS10': CDS_PINID='VSS10';
NODE_NAME     J26 30
 '@S9S_MB_2U_LIB.S9S_MB_2U(SCH_1):PAGE107_I179@PURE_QUANTA.SCONN288_ADR50017P087CC(CHIPS)':
 'VSS11': CDS_PINID='VSS11';
NODE_NAME     J26 32
 '@S9S_MB_2U_LIB.S9S_MB_2U(SCH_1):PAGE107_I179@PURE_QUANTA.SCONN288_ADR50017P087CC(CHIPS)':
 'VSS12': CDS_PINID='VSS12';
NODE_NAME     J26 35
 '@S9S_MB_2U_LIB.S9S_MB_2U(SCH_1):PAGE107_I179@PURE_QUANTA.SCONN288_ADR50017P087CC(CHIPS)':
 'VSS13': CDS_PINID='VSS13';
NODE_NAME     J26 37
 '@S9S_MB_2U_LIB.S9S_MB_2U(SCH_1):PAGE107_I179@PURE_QUANTA.SCONN288_ADR50017P087CC(CHIPS)':
 'VSS14': CDS_PINID='VSS14';
NODE_NAME     J26 39
 '@S9S_MB_2U_LIB.S9S_MB_2U(SCH_1):PAGE107_I179@PURE_QUANTA.SCONN288_ADR50017P087CC(CHIPS)':
 'VSS15': CDS_PINID='VSS15';
NODE_NAME     J26 41
 '@S9S_MB_2U_LIB.S9S_MB_2U(SCH_1):PAGE107_I179@PURE_QUANTA.SCONN288_ADR50017P087CC(CHIPS)':
 'VSS16': CDS_PINID='VSS16';
NODE_NAME     J26 43
 '@S9S_MB_2U_LIB.S9S_MB_2U(SCH_1):PAGE107_I179@PURE_QUANTA.SCONN288_ADR50017P087CC(CHIPS)':
 'VSS17': CDS_PINID='VSS17';
NODE_NAME     J26 46
 '@S9S_MB_2U_LIB.S9S_MB_2U(SCH_1):PAGE107_I179@PURE_QUANTA.SCONN288_ADR50017P087CC(CHIPS)':
 'VSS18': CDS_PINID='VSS18';
NODE_NAME     J26 48
 '@S9S_MB_2U_LIB.S9S_MB_2U(SCH_1):PAGE107_I179@PURE_QUANTA.SCONN288_ADR50017P087CC(CHIPS)':
 'VSS19': CDS_PINID='VSS19';
NODE_NAME     J26 50
 '@S9S_MB_2U_LIB.S9S_MB_2U(SCH_1):PAGE107_I179@PURE_QUANTA.SCONN288_ADR50017P087CC(CHIPS)':
 'VSS20': CDS_PINID='VSS20';
NODE_NAME     J26 52
 '@S9S_MB_2U_LIB.S9S_MB_2U(SCH_1):PAGE107_I179@PURE_QUANTA.SCONN288_ADR50017P087CC(CHIPS)':
 'VSS21': CDS_PINID='VSS21';
NODE_NAME     J26 54
 '@S9S_MB_2U_LIB.S9S_MB_2U(SCH_1):PAGE107_I179@PURE_QUANTA.SCONN288_ADR50017P087CC(CHIPS)':
 'VSS22': CDS_PINID='VSS22';
NODE_NAME     J26 57
 '@S9S_MB_2U_LIB.S9S_MB_2U(SCH_1):PAGE107_I179@PURE_QUANTA.SCONN288_ADR50017P087CC(CHIPS)':
 'VSS23': CDS_PINID='VSS23';
NODE_NAME     J26 59
 '@S9S_MB_2U_LIB.S9S_MB_2U(SCH_1):PAGE107_I179@PURE_QUANTA.SCONN288_ADR50017P087CC(CHIPS)':
 'VSS24': CDS_PINID='VSS24';
NODE_NAME     J26 61
 '@S9S_MB_2U_LIB.S9S_MB_2U(SCH_1):PAGE107_I179@PURE_QUANTA.SCONN288_ADR50017P087CC(CHIPS)':
 'VSS25': CDS_PINID='VSS25';
NODE_NAME     J26 63
 '@S9S_MB_2U_LIB.S9S_MB_2U(SCH_1):PAGE107_I179@PURE_QUANTA.SCONN288_ADR50017P087CC(CHIPS)':
 'VSS26': CDS_PINID='VSS26';
NODE_NAME     J26 65
 '@S9S_MB_2U_LIB.S9S_MB_2U(SCH_1):PAGE107_I179@PURE_QUANTA.SCONN288_ADR50017P087CC(CHIPS)':
 'VSS27': CDS_PINID='VSS27';
NODE_NAME     J26 67
 '@S9S_MB_2U_LIB.S9S_MB_2U(SCH_1):PAGE107_I179@PURE_QUANTA.SCONN288_ADR50017P087CC(CHIPS)':
 'VSS28': CDS_PINID='VSS28';
NODE_NAME     J26 69
 '@S9S_MB_2U_LIB.S9S_MB_2U(SCH_1):PAGE107_I179@PURE_QUANTA.SCONN288_ADR50017P087CC(CHIPS)':
 'VSS29': CDS_PINID='VSS29';
NODE_NAME     J26 71
 '@S9S_MB_2U_LIB.S9S_MB_2U(SCH_1):PAGE107_I179@PURE_QUANTA.SCONN288_ADR50017P087CC(CHIPS)':
 'VSS30': CDS_PINID='VSS30';
NODE_NAME     J26 73
 '@S9S_MB_2U_LIB.S9S_MB_2U(SCH_1):PAGE107_I179@PURE_QUANTA.SCONN288_ADR50017P087CC(CHIPS)':
 'VSS31': CDS_PINID='VSS31';
NODE_NAME     J26 75
 '@S9S_MB_2U_LIB.S9S_MB_2U(SCH_1):PAGE107_I179@PURE_QUANTA.SCONN288_ADR50017P087CC(CHIPS)':
 'VSS32': CDS_PINID='VSS32';
NODE_NAME     J26 77
 '@S9S_MB_2U_LIB.S9S_MB_2U(SCH_1):PAGE107_I179@PURE_QUANTA.SCONN288_ADR50017P087CC(CHIPS)':
 'VSS33': CDS_PINID='VSS33';
NODE_NAME     J26 79
 '@S9S_MB_2U_LIB.S9S_MB_2U(SCH_1):PAGE107_I179@PURE_QUANTA.SCONN288_ADR50017P087CC(CHIPS)':
 'VSS34': CDS_PINID='VSS34';
NODE_NAME     J26 81
 '@S9S_MB_2U_LIB.S9S_MB_2U(SCH_1):PAGE107_I179@PURE_QUANTA.SCONN288_ADR50017P087CC(CHIPS)':
 'VSS35': CDS_PINID='VSS35';
NODE_NAME     J26 83
 '@S9S_MB_2U_LIB.S9S_MB_2U(SCH_1):PAGE107_I179@PURE_QUANTA.SCONN288_ADR50017P087CC(CHIPS)':
 'VSS36': CDS_PINID='VSS36';
NODE_NAME     J26 85
 '@S9S_MB_2U_LIB.S9S_MB_2U(SCH_1):PAGE107_I179@PURE_QUANTA.SCONN288_ADR50017P087CC(CHIPS)':
 'VSS37': CDS_PINID='VSS37';
NODE_NAME     J26 88
 '@S9S_MB_2U_LIB.S9S_MB_2U(SCH_1):PAGE107_I179@PURE_QUANTA.SCONN288_ADR50017P087CC(CHIPS)':
 'VSS38': CDS_PINID='VSS38';
NODE_NAME     J26 90
 '@S9S_MB_2U_LIB.S9S_MB_2U(SCH_1):PAGE107_I179@PURE_QUANTA.SCONN288_ADR50017P087CC(CHIPS)':
 'VSS39': CDS_PINID='VSS39';
NODE_NAME     J26 92
 '@S9S_MB_2U_LIB.S9S_MB_2U(SCH_1):PAGE107_I179@PURE_QUANTA.SCONN288_ADR50017P087CC(CHIPS)':
 'VSS40': CDS_PINID='VSS40';
NODE_NAME     J26 95
 '@S9S_MB_2U_LIB.S9S_MB_2U(SCH_1):PAGE107_I179@PURE_QUANTA.SCONN288_ADR50017P087CC(CHIPS)':
 'VSS41': CDS_PINID='VSS41';
NODE_NAME     J26 97
 '@S9S_MB_2U_LIB.S9S_MB_2U(SCH_1):PAGE107_I179@PURE_QUANTA.SCONN288_ADR50017P087CC(CHIPS)':
 'VSS42': CDS_PINID='VSS42';
NODE_NAME     J26 99
 '@S9S_MB_2U_LIB.S9S_MB_2U(SCH_1):PAGE107_I179@PURE_QUANTA.SCONN288_ADR50017P087CC(CHIPS)':
 'VSS43': CDS_PINID='VSS43';
NODE_NAME     J26 101
 '@S9S_MB_2U_LIB.S9S_MB_2U(SCH_1):PAGE107_I179@PURE_QUANTA.SCONN288_ADR50017P087CC(CHIPS)':
 'VSS44': CDS_PINID='VSS44';
NODE_NAME     J26 103
 '@S9S_MB_2U_LIB.S9S_MB_2U(SCH_1):PAGE107_I179@PURE_QUANTA.SCONN288_ADR50017P087CC(CHIPS)':
 'VSS45': CDS_PINID='VSS45';
NODE_NAME     J26 106
 '@S9S_MB_2U_LIB.S9S_MB_2U(SCH_1):PAGE107_I179@PURE_QUANTA.SCONN288_ADR50017P087CC(CHIPS)':
 'VSS46': CDS_PINID='VSS46';
NODE_NAME     J26 108
 '@S9S_MB_2U_LIB.S9S_MB_2U(SCH_1):PAGE107_I179@PURE_QUANTA.SCONN288_ADR50017P087CC(CHIPS)':
 'VSS47': CDS_PINID='VSS47';
NODE_NAME     J26 110
 '@S9S_MB_2U_LIB.S9S_MB_2U(SCH_1):PAGE107_I179@PURE_QUANTA.SCONN288_ADR50017P087CC(CHIPS)':
 'VSS48': CDS_PINID='VSS48';
NODE_NAME     J26 112
 '@S9S_MB_2U_LIB.S9S_MB_2U(SCH_1):PAGE107_I179@PURE_QUANTA.SCONN288_ADR50017P087CC(CHIPS)':
 'VSS49': CDS_PINID='VSS49';
NODE_NAME     J26 114
 '@S9S_MB_2U_LIB.S9S_MB_2U(SCH_1):PAGE107_I179@PURE_QUANTA.SCONN288_ADR50017P087CC(CHIPS)':
 'VSS50': CDS_PINID='VSS50';
NODE_NAME     J26 117
 '@S9S_MB_2U_LIB.S9S_MB_2U(SCH_1):PAGE107_I179@PURE_QUANTA.SCONN288_ADR50017P087CC(CHIPS)':
 'VSS51': CDS_PINID='VSS51';
NODE_NAME     J26 119
 '@S9S_MB_2U_LIB.S9S_MB_2U(SCH_1):PAGE107_I179@PURE_QUANTA.SCONN288_ADR50017P087CC(CHIPS)':
 'VSS52': CDS_PINID='VSS52';
NODE_NAME     J26 121
 '@S9S_MB_2U_LIB.S9S_MB_2U(SCH_1):PAGE107_I179@PURE_QUANTA.SCONN288_ADR50017P087CC(CHIPS)':
 'VSS53': CDS_PINID='VSS53';
NODE_NAME     J26 123
 '@S9S_MB_2U_LIB.S9S_MB_2U(SCH_1):PAGE107_I179@PURE_QUANTA.SCONN288_ADR50017P087CC(CHIPS)':
 'VSS54': CDS_PINID='VSS54';
NODE_NAME     J26 125
 '@S9S_MB_2U_LIB.S9S_MB_2U(SCH_1):PAGE107_I179@PURE_QUANTA.SCONN288_ADR50017P087CC(CHIPS)':
 'VSS55': CDS_PINID='VSS55';
NODE_NAME     J26 128
 '@S9S_MB_2U_LIB.S9S_MB_2U(SCH_1):PAGE107_I179@PURE_QUANTA.SCONN288_ADR50017P087CC(CHIPS)':
 'VSS56': CDS_PINID='VSS56';
NODE_NAME     J26 130
 '@S9S_MB_2U_LIB.S9S_MB_2U(SCH_1):PAGE107_I179@PURE_QUANTA.SCONN288_ADR50017P087CC(CHIPS)':
 'VSS57': CDS_PINID='VSS57';
NODE_NAME     J26 132
 '@S9S_MB_2U_LIB.S9S_MB_2U(SCH_1):PAGE107_I179@PURE_QUANTA.SCONN288_ADR50017P087CC(CHIPS)':
 'VSS58': CDS_PINID='VSS58';
NODE_NAME     J26 134
 '@S9S_MB_2U_LIB.S9S_MB_2U(SCH_1):PAGE107_I179@PURE_QUANTA.SCONN288_ADR50017P087CC(CHIPS)':
 'VSS59': CDS_PINID='VSS59';
NODE_NAME     J26 136
 '@S9S_MB_2U_LIB.S9S_MB_2U(SCH_1):PAGE107_I179@PURE_QUANTA.SCONN288_ADR50017P087CC(CHIPS)':
 'VSS60': CDS_PINID='VSS60';
NODE_NAME     J26 139
 '@S9S_MB_2U_LIB.S9S_MB_2U(SCH_1):PAGE107_I179@PURE_QUANTA.SCONN288_ADR50017P087CC(CHIPS)':
 'VSS61': CDS_PINID='VSS61';
NODE_NAME     J26 141
 '@S9S_MB_2U_LIB.S9S_MB_2U(SCH_1):PAGE107_I179@PURE_QUANTA.SCONN288_ADR50017P087CC(CHIPS)':
 'VSS62': CDS_PINID='VSS62';
NODE_NAME     J26 143
 '@S9S_MB_2U_LIB.S9S_MB_2U(SCH_1):PAGE107_I179@PURE_QUANTA.SCONN288_ADR50017P087CC(CHIPS)':
 'VSS63': CDS_PINID='VSS63';
NODE_NAME     J26 151
 '@S9S_MB_2U_LIB.S9S_MB_2U(SCH_1):PAGE107_I179@PURE_QUANTA.SCONN288_ADR50017P087CC(CHIPS)':
 'VSS64': CDS_PINID='VSS64';
NODE_NAME     J26 153
 '@S9S_MB_2U_LIB.S9S_MB_2U(SCH_1):PAGE107_I179@PURE_QUANTA.SCONN288_ADR50017P087CC(CHIPS)':
 'VSS65': CDS_PINID='VSS65';
NODE_NAME     J26 155
 '@S9S_MB_2U_LIB.S9S_MB_2U(SCH_1):PAGE107_I179@PURE_QUANTA.SCONN288_ADR50017P087CC(CHIPS)':
 'VSS66': CDS_PINID='VSS66';
NODE_NAME     J26 158
 '@S9S_MB_2U_LIB.S9S_MB_2U(SCH_1):PAGE107_I179@PURE_QUANTA.SCONN288_ADR50017P087CC(CHIPS)':
 'VSS67': CDS_PINID='VSS67';
NODE_NAME     J26 160
 '@S9S_MB_2U_LIB.S9S_MB_2U(SCH_1):PAGE107_I179@PURE_QUANTA.SCONN288_ADR50017P087CC(CHIPS)':
 'VSS68': CDS_PINID='VSS68';
NODE_NAME     J26 162
 '@S9S_MB_2U_LIB.S9S_MB_2U(SCH_1):PAGE107_I179@PURE_QUANTA.SCONN288_ADR50017P087CC(CHIPS)':
 'VSS69': CDS_PINID='VSS69';
NODE_NAME     J26 164
 '@S9S_MB_2U_LIB.S9S_MB_2U(SCH_1):PAGE107_I179@PURE_QUANTA.SCONN288_ADR50017P087CC(CHIPS)':
 'VSS70': CDS_PINID='VSS70';
NODE_NAME     J26 166
 '@S9S_MB_2U_LIB.S9S_MB_2U(SCH_1):PAGE107_I179@PURE_QUANTA.SCONN288_ADR50017P087CC(CHIPS)':
 'VSS71': CDS_PINID='VSS71';
NODE_NAME     J26 169
 '@S9S_MB_2U_LIB.S9S_MB_2U(SCH_1):PAGE107_I179@PURE_QUANTA.SCONN288_ADR50017P087CC(CHIPS)':
 'VSS72': CDS_PINID='VSS72';
NODE_NAME     J26 171
 '@S9S_MB_2U_LIB.S9S_MB_2U(SCH_1):PAGE107_I179@PURE_QUANTA.SCONN288_ADR50017P087CC(CHIPS)':
 'VSS73': CDS_PINID='VSS73';
NODE_NAME     J26 173
 '@S9S_MB_2U_LIB.S9S_MB_2U(SCH_1):PAGE107_I179@PURE_QUANTA.SCONN288_ADR50017P087CC(CHIPS)':
 'VSS74': CDS_PINID='VSS74';
NODE_NAME     J26 175
 '@S9S_MB_2U_LIB.S9S_MB_2U(SCH_1):PAGE107_I179@PURE_QUANTA.SCONN288_ADR50017P087CC(CHIPS)':
 'VSS75': CDS_PINID='VSS75';
NODE_NAME     J26 177
 '@S9S_MB_2U_LIB.S9S_MB_2U(SCH_1):PAGE107_I179@PURE_QUANTA.SCONN288_ADR50017P087CC(CHIPS)':
 'VSS76': CDS_PINID='VSS76';
NODE_NAME     J26 180
 '@S9S_MB_2U_LIB.S9S_MB_2U(SCH_1):PAGE107_I179@PURE_QUANTA.SCONN288_ADR50017P087CC(CHIPS)':
 'VSS77': CDS_PINID='VSS77';
NODE_NAME     J26 182
 '@S9S_MB_2U_LIB.S9S_MB_2U(SCH_1):PAGE107_I179@PURE_QUANTA.SCONN288_ADR50017P087CC(CHIPS)':
 'VSS78': CDS_PINID='VSS78';
NODE_NAME     J26 184
 '@S9S_MB_2U_LIB.S9S_MB_2U(SCH_1):PAGE107_I179@PURE_QUANTA.SCONN288_ADR50017P087CC(CHIPS)':
 'VSS79': CDS_PINID='VSS79';
NODE_NAME     J26 186
 '@S9S_MB_2U_LIB.S9S_MB_2U(SCH_1):PAGE107_I179@PURE_QUANTA.SCONN288_ADR50017P087CC(CHIPS)':
 'VSS80': CDS_PINID='VSS80';
NODE_NAME     J26 188
 '@S9S_MB_2U_LIB.S9S_MB_2U(SCH_1):PAGE107_I179@PURE_QUANTA.SCONN288_ADR50017P087CC(CHIPS)':
 'VSS81': CDS_PINID='VSS81';
NODE_NAME     J26 191
 '@S9S_MB_2U_LIB.S9S_MB_2U(SCH_1):PAGE107_I179@PURE_QUANTA.SCONN288_ADR50017P087CC(CHIPS)':
 'VSS82': CDS_PINID='VSS82';
NODE_NAME     J26 193
 '@S9S_MB_2U_LIB.S9S_MB_2U(SCH_1):PAGE107_I179@PURE_QUANTA.SCONN288_ADR50017P087CC(CHIPS)':
 'VSS83': CDS_PINID='VSS83';
NODE_NAME     J26 195
 '@S9S_MB_2U_LIB.S9S_MB_2U(SCH_1):PAGE107_I179@PURE_QUANTA.SCONN288_ADR50017P087CC(CHIPS)':
 'VSS84': CDS_PINID='VSS84';
NODE_NAME     J26 197
 '@S9S_MB_2U_LIB.S9S_MB_2U(SCH_1):PAGE107_I179@PURE_QUANTA.SCONN288_ADR50017P087CC(CHIPS)':
 'VSS85': CDS_PINID='VSS85';
NODE_NAME     J26 199
 '@S9S_MB_2U_LIB.S9S_MB_2U(SCH_1):PAGE107_I179@PURE_QUANTA.SCONN288_ADR50017P087CC(CHIPS)':
 'VSS86': CDS_PINID='VSS86';
NODE_NAME     J26 202
 '@S9S_MB_2U_LIB.S9S_MB_2U(SCH_1):PAGE107_I179@PURE_QUANTA.SCONN288_ADR50017P087CC(CHIPS)':
 'VSS87': CDS_PINID='VSS87';
NODE_NAME     J26 204
 '@S9S_MB_2U_LIB.S9S_MB_2U(SCH_1):PAGE107_I179@PURE_QUANTA.SCONN288_ADR50017P087CC(CHIPS)':
 'VSS88': CDS_PINID='VSS88';
NODE_NAME     J26 206
 '@S9S_MB_2U_LIB.S9S_MB_2U(SCH_1):PAGE107_I179@PURE_QUANTA.SCONN288_ADR50017P087CC(CHIPS)':
 'VSS89': CDS_PINID='VSS89';
NODE_NAME     J26 208
 '@S9S_MB_2U_LIB.S9S_MB_2U(SCH_1):PAGE107_I179@PURE_QUANTA.SCONN288_ADR50017P087CC(CHIPS)':
 'VSS90': CDS_PINID='VSS90';
NODE_NAME     J26 210
 '@S9S_MB_2U_LIB.S9S_MB_2U(SCH_1):PAGE107_I179@PURE_QUANTA.SCONN288_ADR50017P087CC(CHIPS)':
 'VSS91': CDS_PINID='VSS91';
NODE_NAME     J26 212
 '@S9S_MB_2U_LIB.S9S_MB_2U(SCH_1):PAGE107_I179@PURE_QUANTA.SCONN288_ADR50017P087CC(CHIPS)':
 'VSS92': CDS_PINID='VSS92';
NODE_NAME     J26 214
 '@S9S_MB_2U_LIB.S9S_MB_2U(SCH_1):PAGE107_I179@PURE_QUANTA.SCONN288_ADR50017P087CC(CHIPS)':
 'VSS93': CDS_PINID='VSS93';
NODE_NAME     J26 216
 '@S9S_MB_2U_LIB.S9S_MB_2U(SCH_1):PAGE107_I179@PURE_QUANTA.SCONN288_ADR50017P087CC(CHIPS)':
 'VSS94': CDS_PINID='VSS94';
NODE_NAME     J26 219
 '@S9S_MB_2U_LIB.S9S_MB_2U(SCH_1):PAGE107_I179@PURE_QUANTA.SCONN288_ADR50017P087CC(CHIPS)':
 'VSS95': CDS_PINID='VSS95';
NODE_NAME     J26 222
 '@S9S_MB_2U_LIB.S9S_MB_2U(SCH_1):PAGE107_I179@PURE_QUANTA.SCONN288_ADR50017P087CC(CHIPS)':
 'VSS96': CDS_PINID='VSS96';
NODE_NAME     J26 224
 '@S9S_MB_2U_LIB.S9S_MB_2U(SCH_1):PAGE107_I179@PURE_QUANTA.SCONN288_ADR50017P087CC(CHIPS)':
 'VSS97': CDS_PINID='VSS97';
NODE_NAME     J26 226
 '@S9S_MB_2U_LIB.S9S_MB_2U(SCH_1):PAGE107_I179@PURE_QUANTA.SCONN288_ADR50017P087CC(CHIPS)':
 'VSS98': CDS_PINID='VSS98';
NODE_NAME     J26 228
 '@S9S_MB_2U_LIB.S9S_MB_2U(SCH_1):PAGE107_I179@PURE_QUANTA.SCONN288_ADR50017P087CC(CHIPS)':
 'VSS99': CDS_PINID='VSS99';
NODE_NAME     J26 230
 '@S9S_MB_2U_LIB.S9S_MB_2U(SCH_1):PAGE107_I179@PURE_QUANTA.SCONN288_ADR50017P087CC(CHIPS)':
 'VSS100': CDS_PINID='VSS100';
NODE_NAME     J26 233
 '@S9S_MB_2U_LIB.S9S_MB_2U(SCH_1):PAGE107_I179@PURE_QUANTA.SCONN288_ADR50017P087CC(CHIPS)':
 'VSS101': CDS_PINID='VSS101';
NODE_NAME     J26 235
 '@S9S_MB_2U_LIB.S9S_MB_2U(SCH_1):PAGE107_I179@PURE_QUANTA.SCONN288_ADR50017P087CC(CHIPS)':
 'VSS102': CDS_PINID='VSS102';
NODE_NAME     J26 237
 '@S9S_MB_2U_LIB.S9S_MB_2U(SCH_1):PAGE107_I179@PURE_QUANTA.SCONN288_ADR50017P087CC(CHIPS)':
 'VSS103': CDS_PINID='VSS103';
NODE_NAME     J26 240
 '@S9S_MB_2U_LIB.S9S_MB_2U(SCH_1):PAGE107_I179@PURE_QUANTA.SCONN288_ADR50017P087CC(CHIPS)':
 'VSS104': CDS_PINID='VSS104';
NODE_NAME     J26 242
 '@S9S_MB_2U_LIB.S9S_MB_2U(SCH_1):PAGE107_I179@PURE_QUANTA.SCONN288_ADR50017P087CC(CHIPS)':
 'VSS105': CDS_PINID='VSS105';
NODE_NAME     J26 244
 '@S9S_MB_2U_LIB.S9S_MB_2U(SCH_1):PAGE107_I179@PURE_QUANTA.SCONN288_ADR50017P087CC(CHIPS)':
 'VSS106': CDS_PINID='VSS106';
NODE_NAME     J26 246
 '@S9S_MB_2U_LIB.S9S_MB_2U(SCH_1):PAGE107_I179@PURE_QUANTA.SCONN288_ADR50017P087CC(CHIPS)':
 'VSS107': CDS_PINID='VSS107';
NODE_NAME     J26 248
 '@S9S_MB_2U_LIB.S9S_MB_2U(SCH_1):PAGE107_I179@PURE_QUANTA.SCONN288_ADR50017P087CC(CHIPS)':
 'VSS108': CDS_PINID='VSS108';
NODE_NAME     J26 251
 '@S9S_MB_2U_LIB.S9S_MB_2U(SCH_1):PAGE107_I179@PURE_QUANTA.SCONN288_ADR50017P087CC(CHIPS)':
 'VSS109': CDS_PINID='VSS109';
NODE_NAME     J26 253
 '@S9S_MB_2U_LIB.S9S_MB_2U(SCH_1):PAGE107_I179@PURE_QUANTA.SCONN288_ADR50017P087CC(CHIPS)':
 'VSS110': CDS_PINID='VSS110';
NODE_NAME     J26 255
 '@S9S_MB_2U_LIB.S9S_MB_2U(SCH_1):PAGE107_I179@PURE_QUANTA.SCONN288_ADR50017P087CC(CHIPS)':
 'VSS111': CDS_PINID='VSS111';
NODE_NAME     J26 257
 '@S9S_MB_2U_LIB.S9S_MB_2U(SCH_1):PAGE107_I179@PURE_QUANTA.SCONN288_ADR50017P087CC(CHIPS)':
 'VSS112': CDS_PINID='VSS112';
NODE_NAME     J26 259
 '@S9S_MB_2U_LIB.S9S_MB_2U(SCH_1):PAGE107_I179@PURE_QUANTA.SCONN288_ADR50017P087CC(CHIPS)':
 'VSS113': CDS_PINID='VSS113';
NODE_NAME     J26 262
 '@S9S_MB_2U_LIB.S9S_MB_2U(SCH_1):PAGE107_I179@PURE_QUANTA.SCONN288_ADR50017P087CC(CHIPS)':
 'VSS114': CDS_PINID='VSS114';
NODE_NAME     J26 264
 '@S9S_MB_2U_LIB.S9S_MB_2U(SCH_1):PAGE107_I179@PURE_QUANTA.SCONN288_ADR50017P087CC(CHIPS)':
 'VSS115': CDS_PINID='VSS115';
NODE_NAME     J26 266
 '@S9S_MB_2U_LIB.S9S_MB_2U(SCH_1):PAGE107_I179@PURE_QUANTA.SCONN288_ADR50017P087CC(CHIPS)':
 'VSS116': CDS_PINID='VSS116';
NODE_NAME     J26 268
 '@S9S_MB_2U_LIB.S9S_MB_2U(SCH_1):PAGE107_I179@PURE_QUANTA.SCONN288_ADR50017P087CC(CHIPS)':
 'VSS117': CDS_PINID='VSS117';
NODE_NAME     J26 270
 '@S9S_MB_2U_LIB.S9S_MB_2U(SCH_1):PAGE107_I179@PURE_QUANTA.SCONN288_ADR50017P087CC(CHIPS)':
 'VSS118': CDS_PINID='VSS118';
NODE_NAME     J26 273
 '@S9S_MB_2U_LIB.S9S_MB_2U(SCH_1):PAGE107_I179@PURE_QUANTA.SCONN288_ADR50017P087CC(CHIPS)':
 'VSS119': CDS_PINID='VSS119';
NODE_NAME     J26 275
 '@S9S_MB_2U_LIB.S9S_MB_2U(SCH_1):PAGE107_I179@PURE_QUANTA.SCONN288_ADR50017P087CC(CHIPS)':
 'VSS120': CDS_PINID='VSS120';
NODE_NAME     J26 277
 '@S9S_MB_2U_LIB.S9S_MB_2U(SCH_1):PAGE107_I179@PURE_QUANTA.SCONN288_ADR50017P087CC(CHIPS)':
 'VSS121': CDS_PINID='VSS121';
NODE_NAME     J26 279
 '@S9S_MB_2U_LIB.S9S_MB_2U(SCH_1):PAGE107_I179@PURE_QUANTA.SCONN288_ADR50017P087CC(CHIPS)':
 'VSS122': CDS_PINID='VSS122';
NODE_NAME     J26 281
 '@S9S_MB_2U_LIB.S9S_MB_2U(SCH_1):PAGE107_I179@PURE_QUANTA.SCONN288_ADR50017P087CC(CHIPS)':
 'VSS123': CDS_PINID='VSS123';
NODE_NAME     J26 284
 '@S9S_MB_2U_LIB.S9S_MB_2U(SCH_1):PAGE107_I179@PURE_QUANTA.SCONN288_ADR50017P087CC(CHIPS)':
 'VSS124': CDS_PINID='VSS124';
NODE_NAME     J26 286
 '@S9S_MB_2U_LIB.S9S_MB_2U(SCH_1):PAGE107_I179@PURE_QUANTA.SCONN288_ADR50017P087CC(CHIPS)':
 'VSS125': CDS_PINID='VSS125';
NODE_NAME     J26 288
 '@S9S_MB_2U_LIB.S9S_MB_2U(SCH_1):PAGE107_I179@PURE_QUANTA.SCONN288_ADR50017P087CC(CHIPS)':
 'VSS126': CDS_PINID='VSS126';
NODE_NAME     R77 2
 '@S9S_MB_2U_LIB.S9S_MB_2U(SCH_1):PAGE108_I10@PURE_QUANTA.Q_RES(CHIPS)':
 'B': CDS_PINID='B';
NODE_NAME     C87 2
 '@S9S_MB_2U_LIB.S9S_MB_2U(SCH_1):PAGE108_I121@PURE_QUANTA.Q_CAP(CHIPS)':
 'B': CDS_PINID='B';
NODE_NAME     C88 2
 '@S9S_MB_2U_LIB.S9S_MB_2U(SCH_1):PAGE108_I123@PURE_QUANTA.Q_CAP(CHIPS)':
 'B': CDS_PINID='B';
NODE_NAME     C89 2
 '@S9S_MB_2U_LIB.S9S_MB_2U(SCH_1):PAGE108_I160@PURE_QUANTA.Q_CAP(CHIPS)':
 'B': CDS_PINID='B';
NODE_NAME     J27 G1
 '@S9S_MB_2U_LIB.S9S_MB_2U(SCH_1):PAGE108_I178@PURE_QUANTA.SCONN288_ADR50017P130CC(CHIPS)':
 'G1': CDS_PINID='G1';
NODE_NAME     J27 G2
 '@S9S_MB_2U_LIB.S9S_MB_2U(SCH_1):PAGE108_I178@PURE_QUANTA.SCONN288_ADR50017P130CC(CHIPS)':
 'G2': CDS_PINID='G2';
NODE_NAME     J27 G3
 '@S9S_MB_2U_LIB.S9S_MB_2U(SCH_1):PAGE108_I178@PURE_QUANTA.SCONN288_ADR50017P130CC(CHIPS)':
 'G3': CDS_PINID='G3';
NODE_NAME     J27 6
 '@S9S_MB_2U_LIB.S9S_MB_2U(SCH_1):PAGE108_I178@PURE_QUANTA.SCONN288_ADR50017P130CC(CHIPS)':
 'VSS0': CDS_PINID='VSS0';
NODE_NAME     J27 8
 '@S9S_MB_2U_LIB.S9S_MB_2U(SCH_1):PAGE108_I178@PURE_QUANTA.SCONN288_ADR50017P130CC(CHIPS)':
 'VSS1': CDS_PINID='VSS1';
NODE_NAME     J27 10
 '@S9S_MB_2U_LIB.S9S_MB_2U(SCH_1):PAGE108_I178@PURE_QUANTA.SCONN288_ADR50017P130CC(CHIPS)':
 'VSS2': CDS_PINID='VSS2';
NODE_NAME     J27 13
 '@S9S_MB_2U_LIB.S9S_MB_2U(SCH_1):PAGE108_I178@PURE_QUANTA.SCONN288_ADR50017P130CC(CHIPS)':
 'VSS3': CDS_PINID='VSS3';
NODE_NAME     J27 15
 '@S9S_MB_2U_LIB.S9S_MB_2U(SCH_1):PAGE108_I178@PURE_QUANTA.SCONN288_ADR50017P130CC(CHIPS)':
 'VSS4': CDS_PINID='VSS4';
NODE_NAME     J27 17
 '@S9S_MB_2U_LIB.S9S_MB_2U(SCH_1):PAGE108_I178@PURE_QUANTA.SCONN288_ADR50017P130CC(CHIPS)':
 'VSS5': CDS_PINID='VSS5';
NODE_NAME     J27 19
 '@S9S_MB_2U_LIB.S9S_MB_2U(SCH_1):PAGE108_I178@PURE_QUANTA.SCONN288_ADR50017P130CC(CHIPS)':
 'VSS6': CDS_PINID='VSS6';
NODE_NAME     J27 21
 '@S9S_MB_2U_LIB.S9S_MB_2U(SCH_1):PAGE108_I178@PURE_QUANTA.SCONN288_ADR50017P130CC(CHIPS)':
 'VSS7': CDS_PINID='VSS7';
NODE_NAME     J27 24
 '@S9S_MB_2U_LIB.S9S_MB_2U(SCH_1):PAGE108_I178@PURE_QUANTA.SCONN288_ADR50017P130CC(CHIPS)':
 'VSS8': CDS_PINID='VSS8';
NODE_NAME     J27 26
 '@S9S_MB_2U_LIB.S9S_MB_2U(SCH_1):PAGE108_I178@PURE_QUANTA.SCONN288_ADR50017P130CC(CHIPS)':
 'VSS9': CDS_PINID='VSS9';
NODE_NAME     J27 28
 '@S9S_MB_2U_LIB.S9S_MB_2U(SCH_1):PAGE108_I178@PURE_QUANTA.SCONN288_ADR50017P130CC(CHIPS)':
 'VSS10': CDS_PINID='VSS10';
NODE_NAME     J27 30
 '@S9S_MB_2U_LIB.S9S_MB_2U(SCH_1):PAGE108_I178@PURE_QUANTA.SCONN288_ADR50017P130CC(CHIPS)':
 'VSS11': CDS_PINID='VSS11';
NODE_NAME     J27 32
 '@S9S_MB_2U_LIB.S9S_MB_2U(SCH_1):PAGE108_I178@PURE_QUANTA.SCONN288_ADR50017P130CC(CHIPS)':
 'VSS12': CDS_PINID='VSS12';
NODE_NAME     J27 35
 '@S9S_MB_2U_LIB.S9S_MB_2U(SCH_1):PAGE108_I178@PURE_QUANTA.SCONN288_ADR50017P130CC(CHIPS)':
 'VSS13': CDS_PINID='VSS13';
NODE_NAME     J27 37
 '@S9S_MB_2U_LIB.S9S_MB_2U(SCH_1):PAGE108_I178@PURE_QUANTA.SCONN288_ADR50017P130CC(CHIPS)':
 'VSS14': CDS_PINID='VSS14';
NODE_NAME     J27 39
 '@S9S_MB_2U_LIB.S9S_MB_2U(SCH_1):PAGE108_I178@PURE_QUANTA.SCONN288_ADR50017P130CC(CHIPS)':
 'VSS15': CDS_PINID='VSS15';
NODE_NAME     J27 41
 '@S9S_MB_2U_LIB.S9S_MB_2U(SCH_1):PAGE108_I178@PURE_QUANTA.SCONN288_ADR50017P130CC(CHIPS)':
 'VSS16': CDS_PINID='VSS16';
NODE_NAME     J27 43
 '@S9S_MB_2U_LIB.S9S_MB_2U(SCH_1):PAGE108_I178@PURE_QUANTA.SCONN288_ADR50017P130CC(CHIPS)':
 'VSS17': CDS_PINID='VSS17';
NODE_NAME     J27 46
 '@S9S_MB_2U_LIB.S9S_MB_2U(SCH_1):PAGE108_I178@PURE_QUANTA.SCONN288_ADR50017P130CC(CHIPS)':
 'VSS18': CDS_PINID='VSS18';
NODE_NAME     J27 48
 '@S9S_MB_2U_LIB.S9S_MB_2U(SCH_1):PAGE108_I178@PURE_QUANTA.SCONN288_ADR50017P130CC(CHIPS)':
 'VSS19': CDS_PINID='VSS19';
NODE_NAME     J27 50
 '@S9S_MB_2U_LIB.S9S_MB_2U(SCH_1):PAGE108_I178@PURE_QUANTA.SCONN288_ADR50017P130CC(CHIPS)':
 'VSS20': CDS_PINID='VSS20';
NODE_NAME     J27 52
 '@S9S_MB_2U_LIB.S9S_MB_2U(SCH_1):PAGE108_I178@PURE_QUANTA.SCONN288_ADR50017P130CC(CHIPS)':
 'VSS21': CDS_PINID='VSS21';
NODE_NAME     J27 54
 '@S9S_MB_2U_LIB.S9S_MB_2U(SCH_1):PAGE108_I178@PURE_QUANTA.SCONN288_ADR50017P130CC(CHIPS)':
 'VSS22': CDS_PINID='VSS22';
NODE_NAME     J27 57
 '@S9S_MB_2U_LIB.S9S_MB_2U(SCH_1):PAGE108_I178@PURE_QUANTA.SCONN288_ADR50017P130CC(CHIPS)':
 'VSS23': CDS_PINID='VSS23';
NODE_NAME     J27 59
 '@S9S_MB_2U_LIB.S9S_MB_2U(SCH_1):PAGE108_I178@PURE_QUANTA.SCONN288_ADR50017P130CC(CHIPS)':
 'VSS24': CDS_PINID='VSS24';
NODE_NAME     J27 61
 '@S9S_MB_2U_LIB.S9S_MB_2U(SCH_1):PAGE108_I178@PURE_QUANTA.SCONN288_ADR50017P130CC(CHIPS)':
 'VSS25': CDS_PINID='VSS25';
NODE_NAME     J27 63
 '@S9S_MB_2U_LIB.S9S_MB_2U(SCH_1):PAGE108_I178@PURE_QUANTA.SCONN288_ADR50017P130CC(CHIPS)':
 'VSS26': CDS_PINID='VSS26';
NODE_NAME     J27 65
 '@S9S_MB_2U_LIB.S9S_MB_2U(SCH_1):PAGE108_I178@PURE_QUANTA.SCONN288_ADR50017P130CC(CHIPS)':
 'VSS27': CDS_PINID='VSS27';
NODE_NAME     J27 67
 '@S9S_MB_2U_LIB.S9S_MB_2U(SCH_1):PAGE108_I178@PURE_QUANTA.SCONN288_ADR50017P130CC(CHIPS)':
 'VSS28': CDS_PINID='VSS28';
NODE_NAME     J27 69
 '@S9S_MB_2U_LIB.S9S_MB_2U(SCH_1):PAGE108_I178@PURE_QUANTA.SCONN288_ADR50017P130CC(CHIPS)':
 'VSS29': CDS_PINID='VSS29';
NODE_NAME     J27 71
 '@S9S_MB_2U_LIB.S9S_MB_2U(SCH_1):PAGE108_I178@PURE_QUANTA.SCONN288_ADR50017P130CC(CHIPS)':
 'VSS30': CDS_PINID='VSS30';
NODE_NAME     J27 73
 '@S9S_MB_2U_LIB.S9S_MB_2U(SCH_1):PAGE108_I178@PURE_QUANTA.SCONN288_ADR50017P130CC(CHIPS)':
 'VSS31': CDS_PINID='VSS31';
NODE_NAME     J27 75
 '@S9S_MB_2U_LIB.S9S_MB_2U(SCH_1):PAGE108_I178@PURE_QUANTA.SCONN288_ADR50017P130CC(CHIPS)':
 'VSS32': CDS_PINID='VSS32';
NODE_NAME     J27 77
 '@S9S_MB_2U_LIB.S9S_MB_2U(SCH_1):PAGE108_I178@PURE_QUANTA.SCONN288_ADR50017P130CC(CHIPS)':
 'VSS33': CDS_PINID='VSS33';
NODE_NAME     J27 79
 '@S9S_MB_2U_LIB.S9S_MB_2U(SCH_1):PAGE108_I178@PURE_QUANTA.SCONN288_ADR50017P130CC(CHIPS)':
 'VSS34': CDS_PINID='VSS34';
NODE_NAME     J27 81
 '@S9S_MB_2U_LIB.S9S_MB_2U(SCH_1):PAGE108_I178@PURE_QUANTA.SCONN288_ADR50017P130CC(CHIPS)':
 'VSS35': CDS_PINID='VSS35';
NODE_NAME     J27 83
 '@S9S_MB_2U_LIB.S9S_MB_2U(SCH_1):PAGE108_I178@PURE_QUANTA.SCONN288_ADR50017P130CC(CHIPS)':
 'VSS36': CDS_PINID='VSS36';
NODE_NAME     J27 85
 '@S9S_MB_2U_LIB.S9S_MB_2U(SCH_1):PAGE108_I178@PURE_QUANTA.SCONN288_ADR50017P130CC(CHIPS)':
 'VSS37': CDS_PINID='VSS37';
NODE_NAME     J27 88
 '@S9S_MB_2U_LIB.S9S_MB_2U(SCH_1):PAGE108_I178@PURE_QUANTA.SCONN288_ADR50017P130CC(CHIPS)':
 'VSS38': CDS_PINID='VSS38';
NODE_NAME     J27 90
 '@S9S_MB_2U_LIB.S9S_MB_2U(SCH_1):PAGE108_I178@PURE_QUANTA.SCONN288_ADR50017P130CC(CHIPS)':
 'VSS39': CDS_PINID='VSS39';
NODE_NAME     J27 92
 '@S9S_MB_2U_LIB.S9S_MB_2U(SCH_1):PAGE108_I178@PURE_QUANTA.SCONN288_ADR50017P130CC(CHIPS)':
 'VSS40': CDS_PINID='VSS40';
NODE_NAME     J27 95
 '@S9S_MB_2U_LIB.S9S_MB_2U(SCH_1):PAGE108_I178@PURE_QUANTA.SCONN288_ADR50017P130CC(CHIPS)':
 'VSS41': CDS_PINID='VSS41';
NODE_NAME     J27 97
 '@S9S_MB_2U_LIB.S9S_MB_2U(SCH_1):PAGE108_I178@PURE_QUANTA.SCONN288_ADR50017P130CC(CHIPS)':
 'VSS42': CDS_PINID='VSS42';
NODE_NAME     J27 99
 '@S9S_MB_2U_LIB.S9S_MB_2U(SCH_1):PAGE108_I178@PURE_QUANTA.SCONN288_ADR50017P130CC(CHIPS)':
 'VSS43': CDS_PINID='VSS43';
NODE_NAME     J27 101
 '@S9S_MB_2U_LIB.S9S_MB_2U(SCH_1):PAGE108_I178@PURE_QUANTA.SCONN288_ADR50017P130CC(CHIPS)':
 'VSS44': CDS_PINID='VSS44';
NODE_NAME     J27 103
 '@S9S_MB_2U_LIB.S9S_MB_2U(SCH_1):PAGE108_I178@PURE_QUANTA.SCONN288_ADR50017P130CC(CHIPS)':
 'VSS45': CDS_PINID='VSS45';
NODE_NAME     J27 106
 '@S9S_MB_2U_LIB.S9S_MB_2U(SCH_1):PAGE108_I178@PURE_QUANTA.SCONN288_ADR50017P130CC(CHIPS)':
 'VSS46': CDS_PINID='VSS46';
NODE_NAME     J27 108
 '@S9S_MB_2U_LIB.S9S_MB_2U(SCH_1):PAGE108_I178@PURE_QUANTA.SCONN288_ADR50017P130CC(CHIPS)':
 'VSS47': CDS_PINID='VSS47';
NODE_NAME     J27 110
 '@S9S_MB_2U_LIB.S9S_MB_2U(SCH_1):PAGE108_I178@PURE_QUANTA.SCONN288_ADR50017P130CC(CHIPS)':
 'VSS48': CDS_PINID='VSS48';
NODE_NAME     J27 112
 '@S9S_MB_2U_LIB.S9S_MB_2U(SCH_1):PAGE108_I178@PURE_QUANTA.SCONN288_ADR50017P130CC(CHIPS)':
 'VSS49': CDS_PINID='VSS49';
NODE_NAME     J27 114
 '@S9S_MB_2U_LIB.S9S_MB_2U(SCH_1):PAGE108_I178@PURE_QUANTA.SCONN288_ADR50017P130CC(CHIPS)':
 'VSS50': CDS_PINID='VSS50';
NODE_NAME     J27 117
 '@S9S_MB_2U_LIB.S9S_MB_2U(SCH_1):PAGE108_I178@PURE_QUANTA.SCONN288_ADR50017P130CC(CHIPS)':
 'VSS51': CDS_PINID='VSS51';
NODE_NAME     J27 119
 '@S9S_MB_2U_LIB.S9S_MB_2U(SCH_1):PAGE108_I178@PURE_QUANTA.SCONN288_ADR50017P130CC(CHIPS)':
 'VSS52': CDS_PINID='VSS52';
NODE_NAME     J27 121
 '@S9S_MB_2U_LIB.S9S_MB_2U(SCH_1):PAGE108_I178@PURE_QUANTA.SCONN288_ADR50017P130CC(CHIPS)':
 'VSS53': CDS_PINID='VSS53';
NODE_NAME     J27 123
 '@S9S_MB_2U_LIB.S9S_MB_2U(SCH_1):PAGE108_I178@PURE_QUANTA.SCONN288_ADR50017P130CC(CHIPS)':
 'VSS54': CDS_PINID='VSS54';
NODE_NAME     J27 125
 '@S9S_MB_2U_LIB.S9S_MB_2U(SCH_1):PAGE108_I178@PURE_QUANTA.SCONN288_ADR50017P130CC(CHIPS)':
 'VSS55': CDS_PINID='VSS55';
NODE_NAME     J27 128
 '@S9S_MB_2U_LIB.S9S_MB_2U(SCH_1):PAGE108_I178@PURE_QUANTA.SCONN288_ADR50017P130CC(CHIPS)':
 'VSS56': CDS_PINID='VSS56';
NODE_NAME     J27 130
 '@S9S_MB_2U_LIB.S9S_MB_2U(SCH_1):PAGE108_I178@PURE_QUANTA.SCONN288_ADR50017P130CC(CHIPS)':
 'VSS57': CDS_PINID='VSS57';
NODE_NAME     J27 132
 '@S9S_MB_2U_LIB.S9S_MB_2U(SCH_1):PAGE108_I178@PURE_QUANTA.SCONN288_ADR50017P130CC(CHIPS)':
 'VSS58': CDS_PINID='VSS58';
NODE_NAME     J27 134
 '@S9S_MB_2U_LIB.S9S_MB_2U(SCH_1):PAGE108_I178@PURE_QUANTA.SCONN288_ADR50017P130CC(CHIPS)':
 'VSS59': CDS_PINID='VSS59';
NODE_NAME     J27 136
 '@S9S_MB_2U_LIB.S9S_MB_2U(SCH_1):PAGE108_I178@PURE_QUANTA.SCONN288_ADR50017P130CC(CHIPS)':
 'VSS60': CDS_PINID='VSS60';
NODE_NAME     J27 139
 '@S9S_MB_2U_LIB.S9S_MB_2U(SCH_1):PAGE108_I178@PURE_QUANTA.SCONN288_ADR50017P130CC(CHIPS)':
 'VSS61': CDS_PINID='VSS61';
NODE_NAME     J27 141
 '@S9S_MB_2U_LIB.S9S_MB_2U(SCH_1):PAGE108_I178@PURE_QUANTA.SCONN288_ADR50017P130CC(CHIPS)':
 'VSS62': CDS_PINID='VSS62';
NODE_NAME     J27 143
 '@S9S_MB_2U_LIB.S9S_MB_2U(SCH_1):PAGE108_I178@PURE_QUANTA.SCONN288_ADR50017P130CC(CHIPS)':
 'VSS63': CDS_PINID='VSS63';
NODE_NAME     J27 151
 '@S9S_MB_2U_LIB.S9S_MB_2U(SCH_1):PAGE108_I178@PURE_QUANTA.SCONN288_ADR50017P130CC(CHIPS)':
 'VSS64': CDS_PINID='VSS64';
NODE_NAME     J27 153
 '@S9S_MB_2U_LIB.S9S_MB_2U(SCH_1):PAGE108_I178@PURE_QUANTA.SCONN288_ADR50017P130CC(CHIPS)':
 'VSS65': CDS_PINID='VSS65';
NODE_NAME     J27 155
 '@S9S_MB_2U_LIB.S9S_MB_2U(SCH_1):PAGE108_I178@PURE_QUANTA.SCONN288_ADR50017P130CC(CHIPS)':
 'VSS66': CDS_PINID='VSS66';
NODE_NAME     J27 158
 '@S9S_MB_2U_LIB.S9S_MB_2U(SCH_1):PAGE108_I178@PURE_QUANTA.SCONN288_ADR50017P130CC(CHIPS)':
 'VSS67': CDS_PINID='VSS67';
NODE_NAME     J27 160
 '@S9S_MB_2U_LIB.S9S_MB_2U(SCH_1):PAGE108_I178@PURE_QUANTA.SCONN288_ADR50017P130CC(CHIPS)':
 'VSS68': CDS_PINID='VSS68';
NODE_NAME     J27 162
 '@S9S_MB_2U_LIB.S9S_MB_2U(SCH_1):PAGE108_I178@PURE_QUANTA.SCONN288_ADR50017P130CC(CHIPS)':
 'VSS69': CDS_PINID='VSS69';
NODE_NAME     J27 164
 '@S9S_MB_2U_LIB.S9S_MB_2U(SCH_1):PAGE108_I178@PURE_QUANTA.SCONN288_ADR50017P130CC(CHIPS)':
 'VSS70': CDS_PINID='VSS70';
NODE_NAME     J27 166
 '@S9S_MB_2U_LIB.S9S_MB_2U(SCH_1):PAGE108_I178@PURE_QUANTA.SCONN288_ADR50017P130CC(CHIPS)':
 'VSS71': CDS_PINID='VSS71';
NODE_NAME     J27 169
 '@S9S_MB_2U_LIB.S9S_MB_2U(SCH_1):PAGE108_I178@PURE_QUANTA.SCONN288_ADR50017P130CC(CHIPS)':
 'VSS72': CDS_PINID='VSS72';
NODE_NAME     J27 171
 '@S9S_MB_2U_LIB.S9S_MB_2U(SCH_1):PAGE108_I178@PURE_QUANTA.SCONN288_ADR50017P130CC(CHIPS)':
 'VSS73': CDS_PINID='VSS73';
NODE_NAME     J27 173
 '@S9S_MB_2U_LIB.S9S_MB_2U(SCH_1):PAGE108_I178@PURE_QUANTA.SCONN288_ADR50017P130CC(CHIPS)':
 'VSS74': CDS_PINID='VSS74';
NODE_NAME     J27 175
 '@S9S_MB_2U_LIB.S9S_MB_2U(SCH_1):PAGE108_I178@PURE_QUANTA.SCONN288_ADR50017P130CC(CHIPS)':
 'VSS75': CDS_PINID='VSS75';
NODE_NAME     J27 177
 '@S9S_MB_2U_LIB.S9S_MB_2U(SCH_1):PAGE108_I178@PURE_QUANTA.SCONN288_ADR50017P130CC(CHIPS)':
 'VSS76': CDS_PINID='VSS76';
NODE_NAME     J27 180
 '@S9S_MB_2U_LIB.S9S_MB_2U(SCH_1):PAGE108_I178@PURE_QUANTA.SCONN288_ADR50017P130CC(CHIPS)':
 'VSS77': CDS_PINID='VSS77';
NODE_NAME     J27 182
 '@S9S_MB_2U_LIB.S9S_MB_2U(SCH_1):PAGE108_I178@PURE_QUANTA.SCONN288_ADR50017P130CC(CHIPS)':
 'VSS78': CDS_PINID='VSS78';
NODE_NAME     J27 184
 '@S9S_MB_2U_LIB.S9S_MB_2U(SCH_1):PAGE108_I178@PURE_QUANTA.SCONN288_ADR50017P130CC(CHIPS)':
 'VSS79': CDS_PINID='VSS79';
NODE_NAME     J27 186
 '@S9S_MB_2U_LIB.S9S_MB_2U(SCH_1):PAGE108_I178@PURE_QUANTA.SCONN288_ADR50017P130CC(CHIPS)':
 'VSS80': CDS_PINID='VSS80';
NODE_NAME     J27 188
 '@S9S_MB_2U_LIB.S9S_MB_2U(SCH_1):PAGE108_I178@PURE_QUANTA.SCONN288_ADR50017P130CC(CHIPS)':
 'VSS81': CDS_PINID='VSS81';
NODE_NAME     J27 191
 '@S9S_MB_2U_LIB.S9S_MB_2U(SCH_1):PAGE108_I178@PURE_QUANTA.SCONN288_ADR50017P130CC(CHIPS)':
 'VSS82': CDS_PINID='VSS82';
NODE_NAME     J27 193
 '@S9S_MB_2U_LIB.S9S_MB_2U(SCH_1):PAGE108_I178@PURE_QUANTA.SCONN288_ADR50017P130CC(CHIPS)':
 'VSS83': CDS_PINID='VSS83';
NODE_NAME     J27 195
 '@S9S_MB_2U_LIB.S9S_MB_2U(SCH_1):PAGE108_I178@PURE_QUANTA.SCONN288_ADR50017P130CC(CHIPS)':
 'VSS84': CDS_PINID='VSS84';
NODE_NAME     J27 197
 '@S9S_MB_2U_LIB.S9S_MB_2U(SCH_1):PAGE108_I178@PURE_QUANTA.SCONN288_ADR50017P130CC(CHIPS)':
 'VSS85': CDS_PINID='VSS85';
NODE_NAME     J27 199
 '@S9S_MB_2U_LIB.S9S_MB_2U(SCH_1):PAGE108_I178@PURE_QUANTA.SCONN288_ADR50017P130CC(CHIPS)':
 'VSS86': CDS_PINID='VSS86';
NODE_NAME     J27 202
 '@S9S_MB_2U_LIB.S9S_MB_2U(SCH_1):PAGE108_I178@PURE_QUANTA.SCONN288_ADR50017P130CC(CHIPS)':
 'VSS87': CDS_PINID='VSS87';
NODE_NAME     J27 204
 '@S9S_MB_2U_LIB.S9S_MB_2U(SCH_1):PAGE108_I178@PURE_QUANTA.SCONN288_ADR50017P130CC(CHIPS)':
 'VSS88': CDS_PINID='VSS88';
NODE_NAME     J27 206
 '@S9S_MB_2U_LIB.S9S_MB_2U(SCH_1):PAGE108_I178@PURE_QUANTA.SCONN288_ADR50017P130CC(CHIPS)':
 'VSS89': CDS_PINID='VSS89';
NODE_NAME     J27 208
 '@S9S_MB_2U_LIB.S9S_MB_2U(SCH_1):PAGE108_I178@PURE_QUANTA.SCONN288_ADR50017P130CC(CHIPS)':
 'VSS90': CDS_PINID='VSS90';
NODE_NAME     J27 210
 '@S9S_MB_2U_LIB.S9S_MB_2U(SCH_1):PAGE108_I178@PURE_QUANTA.SCONN288_ADR50017P130CC(CHIPS)':
 'VSS91': CDS_PINID='VSS91';
NODE_NAME     J27 212
 '@S9S_MB_2U_LIB.S9S_MB_2U(SCH_1):PAGE108_I178@PURE_QUANTA.SCONN288_ADR50017P130CC(CHIPS)':
 'VSS92': CDS_PINID='VSS92';
NODE_NAME     J27 214
 '@S9S_MB_2U_LIB.S9S_MB_2U(SCH_1):PAGE108_I178@PURE_QUANTA.SCONN288_ADR50017P130CC(CHIPS)':
 'VSS93': CDS_PINID='VSS93';
NODE_NAME     J27 216
 '@S9S_MB_2U_LIB.S9S_MB_2U(SCH_1):PAGE108_I178@PURE_QUANTA.SCONN288_ADR50017P130CC(CHIPS)':
 'VSS94': CDS_PINID='VSS94';
NODE_NAME     J27 219
 '@S9S_MB_2U_LIB.S9S_MB_2U(SCH_1):PAGE108_I178@PURE_QUANTA.SCONN288_ADR50017P130CC(CHIPS)':
 'VSS95': CDS_PINID='VSS95';
NODE_NAME     J27 222
 '@S9S_MB_2U_LIB.S9S_MB_2U(SCH_1):PAGE108_I178@PURE_QUANTA.SCONN288_ADR50017P130CC(CHIPS)':
 'VSS96': CDS_PINID='VSS96';
NODE_NAME     J27 224
 '@S9S_MB_2U_LIB.S9S_MB_2U(SCH_1):PAGE108_I178@PURE_QUANTA.SCONN288_ADR50017P130CC(CHIPS)':
 'VSS97': CDS_PINID='VSS97';
NODE_NAME     J27 226
 '@S9S_MB_2U_LIB.S9S_MB_2U(SCH_1):PAGE108_I178@PURE_QUANTA.SCONN288_ADR50017P130CC(CHIPS)':
 'VSS98': CDS_PINID='VSS98';
NODE_NAME     J27 228
 '@S9S_MB_2U_LIB.S9S_MB_2U(SCH_1):PAGE108_I178@PURE_QUANTA.SCONN288_ADR50017P130CC(CHIPS)':
 'VSS99': CDS_PINID='VSS99';
NODE_NAME     J27 230
 '@S9S_MB_2U_LIB.S9S_MB_2U(SCH_1):PAGE108_I178@PURE_QUANTA.SCONN288_ADR50017P130CC(CHIPS)':
 'VSS100': CDS_PINID='VSS100';
NODE_NAME     J27 233
 '@S9S_MB_2U_LIB.S9S_MB_2U(SCH_1):PAGE108_I178@PURE_QUANTA.SCONN288_ADR50017P130CC(CHIPS)':
 'VSS101': CDS_PINID='VSS101';
NODE_NAME     J27 235
 '@S9S_MB_2U_LIB.S9S_MB_2U(SCH_1):PAGE108_I178@PURE_QUANTA.SCONN288_ADR50017P130CC(CHIPS)':
 'VSS102': CDS_PINID='VSS102';
NODE_NAME     J27 237
 '@S9S_MB_2U_LIB.S9S_MB_2U(SCH_1):PAGE108_I178@PURE_QUANTA.SCONN288_ADR50017P130CC(CHIPS)':
 'VSS103': CDS_PINID='VSS103';
NODE_NAME     J27 240
 '@S9S_MB_2U_LIB.S9S_MB_2U(SCH_1):PAGE108_I178@PURE_QUANTA.SCONN288_ADR50017P130CC(CHIPS)':
 'VSS104': CDS_PINID='VSS104';
NODE_NAME     J27 242
 '@S9S_MB_2U_LIB.S9S_MB_2U(SCH_1):PAGE108_I178@PURE_QUANTA.SCONN288_ADR50017P130CC(CHIPS)':
 'VSS105': CDS_PINID='VSS105';
NODE_NAME     J27 244
 '@S9S_MB_2U_LIB.S9S_MB_2U(SCH_1):PAGE108_I178@PURE_QUANTA.SCONN288_ADR50017P130CC(CHIPS)':
 'VSS106': CDS_PINID='VSS106';
NODE_NAME     J27 246
 '@S9S_MB_2U_LIB.S9S_MB_2U(SCH_1):PAGE108_I178@PURE_QUANTA.SCONN288_ADR50017P130CC(CHIPS)':
 'VSS107': CDS_PINID='VSS107';
NODE_NAME     J27 248
 '@S9S_MB_2U_LIB.S9S_MB_2U(SCH_1):PAGE108_I178@PURE_QUANTA.SCONN288_ADR50017P130CC(CHIPS)':
 'VSS108': CDS_PINID='VSS108';
NODE_NAME     J27 251
 '@S9S_MB_2U_LIB.S9S_MB_2U(SCH_1):PAGE108_I178@PURE_QUANTA.SCONN288_ADR50017P130CC(CHIPS)':
 'VSS109': CDS_PINID='VSS109';
NODE_NAME     J27 253
 '@S9S_MB_2U_LIB.S9S_MB_2U(SCH_1):PAGE108_I178@PURE_QUANTA.SCONN288_ADR50017P130CC(CHIPS)':
 'VSS110': CDS_PINID='VSS110';
NODE_NAME     J27 255
 '@S9S_MB_2U_LIB.S9S_MB_2U(SCH_1):PAGE108_I178@PURE_QUANTA.SCONN288_ADR50017P130CC(CHIPS)':
 'VSS111': CDS_PINID='VSS111';
NODE_NAME     J27 257
 '@S9S_MB_2U_LIB.S9S_MB_2U(SCH_1):PAGE108_I178@PURE_QUANTA.SCONN288_ADR50017P130CC(CHIPS)':
 'VSS112': CDS_PINID='VSS112';
NODE_NAME     J27 259
 '@S9S_MB_2U_LIB.S9S_MB_2U(SCH_1):PAGE108_I178@PURE_QUANTA.SCONN288_ADR50017P130CC(CHIPS)':
 'VSS113': CDS_PINID='VSS113';
NODE_NAME     J27 262
 '@S9S_MB_2U_LIB.S9S_MB_2U(SCH_1):PAGE108_I178@PURE_QUANTA.SCONN288_ADR50017P130CC(CHIPS)':
 'VSS114': CDS_PINID='VSS114';
NODE_NAME     J27 264
 '@S9S_MB_2U_LIB.S9S_MB_2U(SCH_1):PAGE108_I178@PURE_QUANTA.SCONN288_ADR50017P130CC(CHIPS)':
 'VSS115': CDS_PINID='VSS115';
NODE_NAME     J27 266
 '@S9S_MB_2U_LIB.S9S_MB_2U(SCH_1):PAGE108_I178@PURE_QUANTA.SCONN288_ADR50017P130CC(CHIPS)':
 'VSS116': CDS_PINID='VSS116';
NODE_NAME     J27 268
 '@S9S_MB_2U_LIB.S9S_MB_2U(SCH_1):PAGE108_I178@PURE_QUANTA.SCONN288_ADR50017P130CC(CHIPS)':
 'VSS117': CDS_PINID='VSS117';
NODE_NAME     J27 270
 '@S9S_MB_2U_LIB.S9S_MB_2U(SCH_1):PAGE108_I178@PURE_QUANTA.SCONN288_ADR50017P130CC(CHIPS)':
 'VSS118': CDS_PINID='VSS118';
NODE_NAME     J27 273
 '@S9S_MB_2U_LIB.S9S_MB_2U(SCH_1):PAGE108_I178@PURE_QUANTA.SCONN288_ADR50017P130CC(CHIPS)':
 'VSS119': CDS_PINID='VSS119';
NODE_NAME     J27 275
 '@S9S_MB_2U_LIB.S9S_MB_2U(SCH_1):PAGE108_I178@PURE_QUANTA.SCONN288_ADR50017P130CC(CHIPS)':
 'VSS120': CDS_PINID='VSS120';
NODE_NAME     J27 277
 '@S9S_MB_2U_LIB.S9S_MB_2U(SCH_1):PAGE108_I178@PURE_QUANTA.SCONN288_ADR50017P130CC(CHIPS)':
 'VSS121': CDS_PINID='VSS121';
NODE_NAME     J27 279
 '@S9S_MB_2U_LIB.S9S_MB_2U(SCH_1):PAGE108_I178@PURE_QUANTA.SCONN288_ADR50017P130CC(CHIPS)':
 'VSS122': CDS_PINID='VSS122';
NODE_NAME     J27 281
 '@S9S_MB_2U_LIB.S9S_MB_2U(SCH_1):PAGE108_I178@PURE_QUANTA.SCONN288_ADR50017P130CC(CHIPS)':
 'VSS123': CDS_PINID='VSS123';
NODE_NAME     J27 284
 '@S9S_MB_2U_LIB.S9S_MB_2U(SCH_1):PAGE108_I178@PURE_QUANTA.SCONN288_ADR50017P130CC(CHIPS)':
 'VSS124': CDS_PINID='VSS124';
NODE_NAME     J27 286
 '@S9S_MB_2U_LIB.S9S_MB_2U(SCH_1):PAGE108_I178@PURE_QUANTA.SCONN288_ADR50017P130CC(CHIPS)':
 'VSS125': CDS_PINID='VSS125';
NODE_NAME     J27 288
 '@S9S_MB_2U_LIB.S9S_MB_2U(SCH_1):PAGE108_I178@PURE_QUANTA.SCONN288_ADR50017P130CC(CHIPS)':
 'VSS126': CDS_PINID='VSS126';
NODE_NAME     R76 2
 '@S9S_MB_2U_LIB.S9S_MB_2U(SCH_1):PAGE109_I46@PURE_QUANTA.Q_RES(CHIPS)':
 'B': CDS_PINID='B';
NODE_NAME     C84 2
 '@S9S_MB_2U_LIB.S9S_MB_2U(SCH_1):PAGE109_I121@PURE_QUANTA.Q_CAP(CHIPS)':
 'B': CDS_PINID='B';
NODE_NAME     C85 2
 '@S9S_MB_2U_LIB.S9S_MB_2U(SCH_1):PAGE109_I125@PURE_QUANTA.Q_CAP(CHIPS)':
 'B': CDS_PINID='B';
NODE_NAME     C86 2
 '@S9S_MB_2U_LIB.S9S_MB_2U(SCH_1):PAGE109_I128@PURE_QUANTA.Q_CAP(CHIPS)':
 'B': CDS_PINID='B';
NODE_NAME     J28 G1
 '@S9S_MB_2U_LIB.S9S_MB_2U(SCH_1):PAGE109_I176@PURE_QUANTA.SCONN288_ADR50017P087CC(CHIPS)':
 'G1': CDS_PINID='G1';
NODE_NAME     J28 G2
 '@S9S_MB_2U_LIB.S9S_MB_2U(SCH_1):PAGE109_I176@PURE_QUANTA.SCONN288_ADR50017P087CC(CHIPS)':
 'G2': CDS_PINID='G2';
NODE_NAME     J28 G3
 '@S9S_MB_2U_LIB.S9S_MB_2U(SCH_1):PAGE109_I176@PURE_QUANTA.SCONN288_ADR50017P087CC(CHIPS)':
 'G3': CDS_PINID='G3';
NODE_NAME     J28 6
 '@S9S_MB_2U_LIB.S9S_MB_2U(SCH_1):PAGE109_I176@PURE_QUANTA.SCONN288_ADR50017P087CC(CHIPS)':
 'VSS0': CDS_PINID='VSS0';
NODE_NAME     J28 8
 '@S9S_MB_2U_LIB.S9S_MB_2U(SCH_1):PAGE109_I176@PURE_QUANTA.SCONN288_ADR50017P087CC(CHIPS)':
 'VSS1': CDS_PINID='VSS1';
NODE_NAME     J28 10
 '@S9S_MB_2U_LIB.S9S_MB_2U(SCH_1):PAGE109_I176@PURE_QUANTA.SCONN288_ADR50017P087CC(CHIPS)':
 'VSS2': CDS_PINID='VSS2';
NODE_NAME     J28 13
 '@S9S_MB_2U_LIB.S9S_MB_2U(SCH_1):PAGE109_I176@PURE_QUANTA.SCONN288_ADR50017P087CC(CHIPS)':
 'VSS3': CDS_PINID='VSS3';
NODE_NAME     J28 15
 '@S9S_MB_2U_LIB.S9S_MB_2U(SCH_1):PAGE109_I176@PURE_QUANTA.SCONN288_ADR50017P087CC(CHIPS)':
 'VSS4': CDS_PINID='VSS4';
NODE_NAME     J28 17
 '@S9S_MB_2U_LIB.S9S_MB_2U(SCH_1):PAGE109_I176@PURE_QUANTA.SCONN288_ADR50017P087CC(CHIPS)':
 'VSS5': CDS_PINID='VSS5';
NODE_NAME     J28 19
 '@S9S_MB_2U_LIB.S9S_MB_2U(SCH_1):PAGE109_I176@PURE_QUANTA.SCONN288_ADR50017P087CC(CHIPS)':
 'VSS6': CDS_PINID='VSS6';
NODE_NAME     J28 21
 '@S9S_MB_2U_LIB.S9S_MB_2U(SCH_1):PAGE109_I176@PURE_QUANTA.SCONN288_ADR50017P087CC(CHIPS)':
 'VSS7': CDS_PINID='VSS7';
NODE_NAME     J28 24
 '@S9S_MB_2U_LIB.S9S_MB_2U(SCH_1):PAGE109_I176@PURE_QUANTA.SCONN288_ADR50017P087CC(CHIPS)':
 'VSS8': CDS_PINID='VSS8';
NODE_NAME     J28 26
 '@S9S_MB_2U_LIB.S9S_MB_2U(SCH_1):PAGE109_I176@PURE_QUANTA.SCONN288_ADR50017P087CC(CHIPS)':
 'VSS9': CDS_PINID='VSS9';
NODE_NAME     J28 28
 '@S9S_MB_2U_LIB.S9S_MB_2U(SCH_1):PAGE109_I176@PURE_QUANTA.SCONN288_ADR50017P087CC(CHIPS)':
 'VSS10': CDS_PINID='VSS10';
NODE_NAME     J28 30
 '@S9S_MB_2U_LIB.S9S_MB_2U(SCH_1):PAGE109_I176@PURE_QUANTA.SCONN288_ADR50017P087CC(CHIPS)':
 'VSS11': CDS_PINID='VSS11';
NODE_NAME     J28 32
 '@S9S_MB_2U_LIB.S9S_MB_2U(SCH_1):PAGE109_I176@PURE_QUANTA.SCONN288_ADR50017P087CC(CHIPS)':
 'VSS12': CDS_PINID='VSS12';
NODE_NAME     J28 35
 '@S9S_MB_2U_LIB.S9S_MB_2U(SCH_1):PAGE109_I176@PURE_QUANTA.SCONN288_ADR50017P087CC(CHIPS)':
 'VSS13': CDS_PINID='VSS13';
NODE_NAME     J28 37
 '@S9S_MB_2U_LIB.S9S_MB_2U(SCH_1):PAGE109_I176@PURE_QUANTA.SCONN288_ADR50017P087CC(CHIPS)':
 'VSS14': CDS_PINID='VSS14';
NODE_NAME     J28 39
 '@S9S_MB_2U_LIB.S9S_MB_2U(SCH_1):PAGE109_I176@PURE_QUANTA.SCONN288_ADR50017P087CC(CHIPS)':
 'VSS15': CDS_PINID='VSS15';
NODE_NAME     J28 41
 '@S9S_MB_2U_LIB.S9S_MB_2U(SCH_1):PAGE109_I176@PURE_QUANTA.SCONN288_ADR50017P087CC(CHIPS)':
 'VSS16': CDS_PINID='VSS16';
NODE_NAME     J28 43
 '@S9S_MB_2U_LIB.S9S_MB_2U(SCH_1):PAGE109_I176@PURE_QUANTA.SCONN288_ADR50017P087CC(CHIPS)':
 'VSS17': CDS_PINID='VSS17';
NODE_NAME     J28 46
 '@S9S_MB_2U_LIB.S9S_MB_2U(SCH_1):PAGE109_I176@PURE_QUANTA.SCONN288_ADR50017P087CC(CHIPS)':
 'VSS18': CDS_PINID='VSS18';
NODE_NAME     J28 48
 '@S9S_MB_2U_LIB.S9S_MB_2U(SCH_1):PAGE109_I176@PURE_QUANTA.SCONN288_ADR50017P087CC(CHIPS)':
 'VSS19': CDS_PINID='VSS19';
NODE_NAME     J28 50
 '@S9S_MB_2U_LIB.S9S_MB_2U(SCH_1):PAGE109_I176@PURE_QUANTA.SCONN288_ADR50017P087CC(CHIPS)':
 'VSS20': CDS_PINID='VSS20';
NODE_NAME     J28 52
 '@S9S_MB_2U_LIB.S9S_MB_2U(SCH_1):PAGE109_I176@PURE_QUANTA.SCONN288_ADR50017P087CC(CHIPS)':
 'VSS21': CDS_PINID='VSS21';
NODE_NAME     J28 54
 '@S9S_MB_2U_LIB.S9S_MB_2U(SCH_1):PAGE109_I176@PURE_QUANTA.SCONN288_ADR50017P087CC(CHIPS)':
 'VSS22': CDS_PINID='VSS22';
NODE_NAME     J28 57
 '@S9S_MB_2U_LIB.S9S_MB_2U(SCH_1):PAGE109_I176@PURE_QUANTA.SCONN288_ADR50017P087CC(CHIPS)':
 'VSS23': CDS_PINID='VSS23';
NODE_NAME     J28 59
 '@S9S_MB_2U_LIB.S9S_MB_2U(SCH_1):PAGE109_I176@PURE_QUANTA.SCONN288_ADR50017P087CC(CHIPS)':
 'VSS24': CDS_PINID='VSS24';
NODE_NAME     J28 61
 '@S9S_MB_2U_LIB.S9S_MB_2U(SCH_1):PAGE109_I176@PURE_QUANTA.SCONN288_ADR50017P087CC(CHIPS)':
 'VSS25': CDS_PINID='VSS25';
NODE_NAME     J28 63
 '@S9S_MB_2U_LIB.S9S_MB_2U(SCH_1):PAGE109_I176@PURE_QUANTA.SCONN288_ADR50017P087CC(CHIPS)':
 'VSS26': CDS_PINID='VSS26';
NODE_NAME     J28 65
 '@S9S_MB_2U_LIB.S9S_MB_2U(SCH_1):PAGE109_I176@PURE_QUANTA.SCONN288_ADR50017P087CC(CHIPS)':
 'VSS27': CDS_PINID='VSS27';
NODE_NAME     J28 67
 '@S9S_MB_2U_LIB.S9S_MB_2U(SCH_1):PAGE109_I176@PURE_QUANTA.SCONN288_ADR50017P087CC(CHIPS)':
 'VSS28': CDS_PINID='VSS28';
NODE_NAME     J28 69
 '@S9S_MB_2U_LIB.S9S_MB_2U(SCH_1):PAGE109_I176@PURE_QUANTA.SCONN288_ADR50017P087CC(CHIPS)':
 'VSS29': CDS_PINID='VSS29';
NODE_NAME     J28 71
 '@S9S_MB_2U_LIB.S9S_MB_2U(SCH_1):PAGE109_I176@PURE_QUANTA.SCONN288_ADR50017P087CC(CHIPS)':
 'VSS30': CDS_PINID='VSS30';
NODE_NAME     J28 73
 '@S9S_MB_2U_LIB.S9S_MB_2U(SCH_1):PAGE109_I176@PURE_QUANTA.SCONN288_ADR50017P087CC(CHIPS)':
 'VSS31': CDS_PINID='VSS31';
NODE_NAME     J28 75
 '@S9S_MB_2U_LIB.S9S_MB_2U(SCH_1):PAGE109_I176@PURE_QUANTA.SCONN288_ADR50017P087CC(CHIPS)':
 'VSS32': CDS_PINID='VSS32';
NODE_NAME     J28 77
 '@S9S_MB_2U_LIB.S9S_MB_2U(SCH_1):PAGE109_I176@PURE_QUANTA.SCONN288_ADR50017P087CC(CHIPS)':
 'VSS33': CDS_PINID='VSS33';
NODE_NAME     J28 79
 '@S9S_MB_2U_LIB.S9S_MB_2U(SCH_1):PAGE109_I176@PURE_QUANTA.SCONN288_ADR50017P087CC(CHIPS)':
 'VSS34': CDS_PINID='VSS34';
NODE_NAME     J28 81
 '@S9S_MB_2U_LIB.S9S_MB_2U(SCH_1):PAGE109_I176@PURE_QUANTA.SCONN288_ADR50017P087CC(CHIPS)':
 'VSS35': CDS_PINID='VSS35';
NODE_NAME     J28 83
 '@S9S_MB_2U_LIB.S9S_MB_2U(SCH_1):PAGE109_I176@PURE_QUANTA.SCONN288_ADR50017P087CC(CHIPS)':
 'VSS36': CDS_PINID='VSS36';
NODE_NAME     J28 85
 '@S9S_MB_2U_LIB.S9S_MB_2U(SCH_1):PAGE109_I176@PURE_QUANTA.SCONN288_ADR50017P087CC(CHIPS)':
 'VSS37': CDS_PINID='VSS37';
NODE_NAME     J28 88
 '@S9S_MB_2U_LIB.S9S_MB_2U(SCH_1):PAGE109_I176@PURE_QUANTA.SCONN288_ADR50017P087CC(CHIPS)':
 'VSS38': CDS_PINID='VSS38';
NODE_NAME     J28 90
 '@S9S_MB_2U_LIB.S9S_MB_2U(SCH_1):PAGE109_I176@PURE_QUANTA.SCONN288_ADR50017P087CC(CHIPS)':
 'VSS39': CDS_PINID='VSS39';
NODE_NAME     J28 92
 '@S9S_MB_2U_LIB.S9S_MB_2U(SCH_1):PAGE109_I176@PURE_QUANTA.SCONN288_ADR50017P087CC(CHIPS)':
 'VSS40': CDS_PINID='VSS40';
NODE_NAME     J28 95
 '@S9S_MB_2U_LIB.S9S_MB_2U(SCH_1):PAGE109_I176@PURE_QUANTA.SCONN288_ADR50017P087CC(CHIPS)':
 'VSS41': CDS_PINID='VSS41';
NODE_NAME     J28 97
 '@S9S_MB_2U_LIB.S9S_MB_2U(SCH_1):PAGE109_I176@PURE_QUANTA.SCONN288_ADR50017P087CC(CHIPS)':
 'VSS42': CDS_PINID='VSS42';
NODE_NAME     J28 99
 '@S9S_MB_2U_LIB.S9S_MB_2U(SCH_1):PAGE109_I176@PURE_QUANTA.SCONN288_ADR50017P087CC(CHIPS)':
 'VSS43': CDS_PINID='VSS43';
NODE_NAME     J28 101
 '@S9S_MB_2U_LIB.S9S_MB_2U(SCH_1):PAGE109_I176@PURE_QUANTA.SCONN288_ADR50017P087CC(CHIPS)':
 'VSS44': CDS_PINID='VSS44';
NODE_NAME     J28 103
 '@S9S_MB_2U_LIB.S9S_MB_2U(SCH_1):PAGE109_I176@PURE_QUANTA.SCONN288_ADR50017P087CC(CHIPS)':
 'VSS45': CDS_PINID='VSS45';
NODE_NAME     J28 106
 '@S9S_MB_2U_LIB.S9S_MB_2U(SCH_1):PAGE109_I176@PURE_QUANTA.SCONN288_ADR50017P087CC(CHIPS)':
 'VSS46': CDS_PINID='VSS46';
NODE_NAME     J28 108
 '@S9S_MB_2U_LIB.S9S_MB_2U(SCH_1):PAGE109_I176@PURE_QUANTA.SCONN288_ADR50017P087CC(CHIPS)':
 'VSS47': CDS_PINID='VSS47';
NODE_NAME     J28 110
 '@S9S_MB_2U_LIB.S9S_MB_2U(SCH_1):PAGE109_I176@PURE_QUANTA.SCONN288_ADR50017P087CC(CHIPS)':
 'VSS48': CDS_PINID='VSS48';
NODE_NAME     J28 112
 '@S9S_MB_2U_LIB.S9S_MB_2U(SCH_1):PAGE109_I176@PURE_QUANTA.SCONN288_ADR50017P087CC(CHIPS)':
 'VSS49': CDS_PINID='VSS49';
NODE_NAME     J28 114
 '@S9S_MB_2U_LIB.S9S_MB_2U(SCH_1):PAGE109_I176@PURE_QUANTA.SCONN288_ADR50017P087CC(CHIPS)':
 'VSS50': CDS_PINID='VSS50';
NODE_NAME     J28 117
 '@S9S_MB_2U_LIB.S9S_MB_2U(SCH_1):PAGE109_I176@PURE_QUANTA.SCONN288_ADR50017P087CC(CHIPS)':
 'VSS51': CDS_PINID='VSS51';
NODE_NAME     J28 119
 '@S9S_MB_2U_LIB.S9S_MB_2U(SCH_1):PAGE109_I176@PURE_QUANTA.SCONN288_ADR50017P087CC(CHIPS)':
 'VSS52': CDS_PINID='VSS52';
NODE_NAME     J28 121
 '@S9S_MB_2U_LIB.S9S_MB_2U(SCH_1):PAGE109_I176@PURE_QUANTA.SCONN288_ADR50017P087CC(CHIPS)':
 'VSS53': CDS_PINID='VSS53';
NODE_NAME     J28 123
 '@S9S_MB_2U_LIB.S9S_MB_2U(SCH_1):PAGE109_I176@PURE_QUANTA.SCONN288_ADR50017P087CC(CHIPS)':
 'VSS54': CDS_PINID='VSS54';
NODE_NAME     J28 125
 '@S9S_MB_2U_LIB.S9S_MB_2U(SCH_1):PAGE109_I176@PURE_QUANTA.SCONN288_ADR50017P087CC(CHIPS)':
 'VSS55': CDS_PINID='VSS55';
NODE_NAME     J28 128
 '@S9S_MB_2U_LIB.S9S_MB_2U(SCH_1):PAGE109_I176@PURE_QUANTA.SCONN288_ADR50017P087CC(CHIPS)':
 'VSS56': CDS_PINID='VSS56';
NODE_NAME     J28 130
 '@S9S_MB_2U_LIB.S9S_MB_2U(SCH_1):PAGE109_I176@PURE_QUANTA.SCONN288_ADR50017P087CC(CHIPS)':
 'VSS57': CDS_PINID='VSS57';
NODE_NAME     J28 132
 '@S9S_MB_2U_LIB.S9S_MB_2U(SCH_1):PAGE109_I176@PURE_QUANTA.SCONN288_ADR50017P087CC(CHIPS)':
 'VSS58': CDS_PINID='VSS58';
NODE_NAME     J28 134
 '@S9S_MB_2U_LIB.S9S_MB_2U(SCH_1):PAGE109_I176@PURE_QUANTA.SCONN288_ADR50017P087CC(CHIPS)':
 'VSS59': CDS_PINID='VSS59';
NODE_NAME     J28 136
 '@S9S_MB_2U_LIB.S9S_MB_2U(SCH_1):PAGE109_I176@PURE_QUANTA.SCONN288_ADR50017P087CC(CHIPS)':
 'VSS60': CDS_PINID='VSS60';
NODE_NAME     J28 139
 '@S9S_MB_2U_LIB.S9S_MB_2U(SCH_1):PAGE109_I176@PURE_QUANTA.SCONN288_ADR50017P087CC(CHIPS)':
 'VSS61': CDS_PINID='VSS61';
NODE_NAME     J28 141
 '@S9S_MB_2U_LIB.S9S_MB_2U(SCH_1):PAGE109_I176@PURE_QUANTA.SCONN288_ADR50017P087CC(CHIPS)':
 'VSS62': CDS_PINID='VSS62';
NODE_NAME     J28 143
 '@S9S_MB_2U_LIB.S9S_MB_2U(SCH_1):PAGE109_I176@PURE_QUANTA.SCONN288_ADR50017P087CC(CHIPS)':
 'VSS63': CDS_PINID='VSS63';
NODE_NAME     J28 151
 '@S9S_MB_2U_LIB.S9S_MB_2U(SCH_1):PAGE109_I176@PURE_QUANTA.SCONN288_ADR50017P087CC(CHIPS)':
 'VSS64': CDS_PINID='VSS64';
NODE_NAME     J28 153
 '@S9S_MB_2U_LIB.S9S_MB_2U(SCH_1):PAGE109_I176@PURE_QUANTA.SCONN288_ADR50017P087CC(CHIPS)':
 'VSS65': CDS_PINID='VSS65';
NODE_NAME     J28 155
 '@S9S_MB_2U_LIB.S9S_MB_2U(SCH_1):PAGE109_I176@PURE_QUANTA.SCONN288_ADR50017P087CC(CHIPS)':
 'VSS66': CDS_PINID='VSS66';
NODE_NAME     J28 158
 '@S9S_MB_2U_LIB.S9S_MB_2U(SCH_1):PAGE109_I176@PURE_QUANTA.SCONN288_ADR50017P087CC(CHIPS)':
 'VSS67': CDS_PINID='VSS67';
NODE_NAME     J28 160
 '@S9S_MB_2U_LIB.S9S_MB_2U(SCH_1):PAGE109_I176@PURE_QUANTA.SCONN288_ADR50017P087CC(CHIPS)':
 'VSS68': CDS_PINID='VSS68';
NODE_NAME     J28 162
 '@S9S_MB_2U_LIB.S9S_MB_2U(SCH_1):PAGE109_I176@PURE_QUANTA.SCONN288_ADR50017P087CC(CHIPS)':
 'VSS69': CDS_PINID='VSS69';
NODE_NAME     J28 164
 '@S9S_MB_2U_LIB.S9S_MB_2U(SCH_1):PAGE109_I176@PURE_QUANTA.SCONN288_ADR50017P087CC(CHIPS)':
 'VSS70': CDS_PINID='VSS70';
NODE_NAME     J28 166
 '@S9S_MB_2U_LIB.S9S_MB_2U(SCH_1):PAGE109_I176@PURE_QUANTA.SCONN288_ADR50017P087CC(CHIPS)':
 'VSS71': CDS_PINID='VSS71';
NODE_NAME     J28 169
 '@S9S_MB_2U_LIB.S9S_MB_2U(SCH_1):PAGE109_I176@PURE_QUANTA.SCONN288_ADR50017P087CC(CHIPS)':
 'VSS72': CDS_PINID='VSS72';
NODE_NAME     J28 171
 '@S9S_MB_2U_LIB.S9S_MB_2U(SCH_1):PAGE109_I176@PURE_QUANTA.SCONN288_ADR50017P087CC(CHIPS)':
 'VSS73': CDS_PINID='VSS73';
NODE_NAME     J28 173
 '@S9S_MB_2U_LIB.S9S_MB_2U(SCH_1):PAGE109_I176@PURE_QUANTA.SCONN288_ADR50017P087CC(CHIPS)':
 'VSS74': CDS_PINID='VSS74';
NODE_NAME     J28 175
 '@S9S_MB_2U_LIB.S9S_MB_2U(SCH_1):PAGE109_I176@PURE_QUANTA.SCONN288_ADR50017P087CC(CHIPS)':
 'VSS75': CDS_PINID='VSS75';
NODE_NAME     J28 177
 '@S9S_MB_2U_LIB.S9S_MB_2U(SCH_1):PAGE109_I176@PURE_QUANTA.SCONN288_ADR50017P087CC(CHIPS)':
 'VSS76': CDS_PINID='VSS76';
NODE_NAME     J28 180
 '@S9S_MB_2U_LIB.S9S_MB_2U(SCH_1):PAGE109_I176@PURE_QUANTA.SCONN288_ADR50017P087CC(CHIPS)':
 'VSS77': CDS_PINID='VSS77';
NODE_NAME     J28 182
 '@S9S_MB_2U_LIB.S9S_MB_2U(SCH_1):PAGE109_I176@PURE_QUANTA.SCONN288_ADR50017P087CC(CHIPS)':
 'VSS78': CDS_PINID='VSS78';
NODE_NAME     J28 184
 '@S9S_MB_2U_LIB.S9S_MB_2U(SCH_1):PAGE109_I176@PURE_QUANTA.SCONN288_ADR50017P087CC(CHIPS)':
 'VSS79': CDS_PINID='VSS79';
NODE_NAME     J28 186
 '@S9S_MB_2U_LIB.S9S_MB_2U(SCH_1):PAGE109_I176@PURE_QUANTA.SCONN288_ADR50017P087CC(CHIPS)':
 'VSS80': CDS_PINID='VSS80';
NODE_NAME     J28 188
 '@S9S_MB_2U_LIB.S9S_MB_2U(SCH_1):PAGE109_I176@PURE_QUANTA.SCONN288_ADR50017P087CC(CHIPS)':
 'VSS81': CDS_PINID='VSS81';
NODE_NAME     J28 191
 '@S9S_MB_2U_LIB.S9S_MB_2U(SCH_1):PAGE109_I176@PURE_QUANTA.SCONN288_ADR50017P087CC(CHIPS)':
 'VSS82': CDS_PINID='VSS82';
NODE_NAME     J28 193
 '@S9S_MB_2U_LIB.S9S_MB_2U(SCH_1):PAGE109_I176@PURE_QUANTA.SCONN288_ADR50017P087CC(CHIPS)':
 'VSS83': CDS_PINID='VSS83';
NODE_NAME     J28 195
 '@S9S_MB_2U_LIB.S9S_MB_2U(SCH_1):PAGE109_I176@PURE_QUANTA.SCONN288_ADR50017P087CC(CHIPS)':
 'VSS84': CDS_PINID='VSS84';
NODE_NAME     J28 197
 '@S9S_MB_2U_LIB.S9S_MB_2U(SCH_1):PAGE109_I176@PURE_QUANTA.SCONN288_ADR50017P087CC(CHIPS)':
 'VSS85': CDS_PINID='VSS85';
NODE_NAME     J28 199
 '@S9S_MB_2U_LIB.S9S_MB_2U(SCH_1):PAGE109_I176@PURE_QUANTA.SCONN288_ADR50017P087CC(CHIPS)':
 'VSS86': CDS_PINID='VSS86';
NODE_NAME     J28 202
 '@S9S_MB_2U_LIB.S9S_MB_2U(SCH_1):PAGE109_I176@PURE_QUANTA.SCONN288_ADR50017P087CC(CHIPS)':
 'VSS87': CDS_PINID='VSS87';
NODE_NAME     J28 204
 '@S9S_MB_2U_LIB.S9S_MB_2U(SCH_1):PAGE109_I176@PURE_QUANTA.SCONN288_ADR50017P087CC(CHIPS)':
 'VSS88': CDS_PINID='VSS88';
NODE_NAME     J28 206
 '@S9S_MB_2U_LIB.S9S_MB_2U(SCH_1):PAGE109_I176@PURE_QUANTA.SCONN288_ADR50017P087CC(CHIPS)':
 'VSS89': CDS_PINID='VSS89';
NODE_NAME     J28 208
 '@S9S_MB_2U_LIB.S9S_MB_2U(SCH_1):PAGE109_I176@PURE_QUANTA.SCONN288_ADR50017P087CC(CHIPS)':
 'VSS90': CDS_PINID='VSS90';
NODE_NAME     J28 210
 '@S9S_MB_2U_LIB.S9S_MB_2U(SCH_1):PAGE109_I176@PURE_QUANTA.SCONN288_ADR50017P087CC(CHIPS)':
 'VSS91': CDS_PINID='VSS91';
NODE_NAME     J28 212
 '@S9S_MB_2U_LIB.S9S_MB_2U(SCH_1):PAGE109_I176@PURE_QUANTA.SCONN288_ADR50017P087CC(CHIPS)':
 'VSS92': CDS_PINID='VSS92';
NODE_NAME     J28 214
 '@S9S_MB_2U_LIB.S9S_MB_2U(SCH_1):PAGE109_I176@PURE_QUANTA.SCONN288_ADR50017P087CC(CHIPS)':
 'VSS93': CDS_PINID='VSS93';
NODE_NAME     J28 216
 '@S9S_MB_2U_LIB.S9S_MB_2U(SCH_1):PAGE109_I176@PURE_QUANTA.SCONN288_ADR50017P087CC(CHIPS)':
 'VSS94': CDS_PINID='VSS94';
NODE_NAME     J28 219
 '@S9S_MB_2U_LIB.S9S_MB_2U(SCH_1):PAGE109_I176@PURE_QUANTA.SCONN288_ADR50017P087CC(CHIPS)':
 'VSS95': CDS_PINID='VSS95';
NODE_NAME     J28 222
 '@S9S_MB_2U_LIB.S9S_MB_2U(SCH_1):PAGE109_I176@PURE_QUANTA.SCONN288_ADR50017P087CC(CHIPS)':
 'VSS96': CDS_PINID='VSS96';
NODE_NAME     J28 224
 '@S9S_MB_2U_LIB.S9S_MB_2U(SCH_1):PAGE109_I176@PURE_QUANTA.SCONN288_ADR50017P087CC(CHIPS)':
 'VSS97': CDS_PINID='VSS97';
NODE_NAME     J28 226
 '@S9S_MB_2U_LIB.S9S_MB_2U(SCH_1):PAGE109_I176@PURE_QUANTA.SCONN288_ADR50017P087CC(CHIPS)':
 'VSS98': CDS_PINID='VSS98';
NODE_NAME     J28 228
 '@S9S_MB_2U_LIB.S9S_MB_2U(SCH_1):PAGE109_I176@PURE_QUANTA.SCONN288_ADR50017P087CC(CHIPS)':
 'VSS99': CDS_PINID='VSS99';
NODE_NAME     J28 230
 '@S9S_MB_2U_LIB.S9S_MB_2U(SCH_1):PAGE109_I176@PURE_QUANTA.SCONN288_ADR50017P087CC(CHIPS)':
 'VSS100': CDS_PINID='VSS100';
NODE_NAME     J28 233
 '@S9S_MB_2U_LIB.S9S_MB_2U(SCH_1):PAGE109_I176@PURE_QUANTA.SCONN288_ADR50017P087CC(CHIPS)':
 'VSS101': CDS_PINID='VSS101';
NODE_NAME     J28 235
 '@S9S_MB_2U_LIB.S9S_MB_2U(SCH_1):PAGE109_I176@PURE_QUANTA.SCONN288_ADR50017P087CC(CHIPS)':
 'VSS102': CDS_PINID='VSS102';
NODE_NAME     J28 237
 '@S9S_MB_2U_LIB.S9S_MB_2U(SCH_1):PAGE109_I176@PURE_QUANTA.SCONN288_ADR50017P087CC(CHIPS)':
 'VSS103': CDS_PINID='VSS103';
NODE_NAME     J28 240
 '@S9S_MB_2U_LIB.S9S_MB_2U(SCH_1):PAGE109_I176@PURE_QUANTA.SCONN288_ADR50017P087CC(CHIPS)':
 'VSS104': CDS_PINID='VSS104';
NODE_NAME     J28 242
 '@S9S_MB_2U_LIB.S9S_MB_2U(SCH_1):PAGE109_I176@PURE_QUANTA.SCONN288_ADR50017P087CC(CHIPS)':
 'VSS105': CDS_PINID='VSS105';
NODE_NAME     J28 244
 '@S9S_MB_2U_LIB.S9S_MB_2U(SCH_1):PAGE109_I176@PURE_QUANTA.SCONN288_ADR50017P087CC(CHIPS)':
 'VSS106': CDS_PINID='VSS106';
NODE_NAME     J28 246
 '@S9S_MB_2U_LIB.S9S_MB_2U(SCH_1):PAGE109_I176@PURE_QUANTA.SCONN288_ADR50017P087CC(CHIPS)':
 'VSS107': CDS_PINID='VSS107';
NODE_NAME     J28 248
 '@S9S_MB_2U_LIB.S9S_MB_2U(SCH_1):PAGE109_I176@PURE_QUANTA.SCONN288_ADR50017P087CC(CHIPS)':
 'VSS108': CDS_PINID='VSS108';
NODE_NAME     J28 251
 '@S9S_MB_2U_LIB.S9S_MB_2U(SCH_1):PAGE109_I176@PURE_QUANTA.SCONN288_ADR50017P087CC(CHIPS)':
 'VSS109': CDS_PINID='VSS109';
NODE_NAME     J28 253
 '@S9S_MB_2U_LIB.S9S_MB_2U(SCH_1):PAGE109_I176@PURE_QUANTA.SCONN288_ADR50017P087CC(CHIPS)':
 'VSS110': CDS_PINID='VSS110';
NODE_NAME     J28 255
 '@S9S_MB_2U_LIB.S9S_MB_2U(SCH_1):PAGE109_I176@PURE_QUANTA.SCONN288_ADR50017P087CC(CHIPS)':
 'VSS111': CDS_PINID='VSS111';
NODE_NAME     J28 257
 '@S9S_MB_2U_LIB.S9S_MB_2U(SCH_1):PAGE109_I176@PURE_QUANTA.SCONN288_ADR50017P087CC(CHIPS)':
 'VSS112': CDS_PINID='VSS112';
NODE_NAME     J28 259
 '@S9S_MB_2U_LIB.S9S_MB_2U(SCH_1):PAGE109_I176@PURE_QUANTA.SCONN288_ADR50017P087CC(CHIPS)':
 'VSS113': CDS_PINID='VSS113';
NODE_NAME     J28 262
 '@S9S_MB_2U_LIB.S9S_MB_2U(SCH_1):PAGE109_I176@PURE_QUANTA.SCONN288_ADR50017P087CC(CHIPS)':
 'VSS114': CDS_PINID='VSS114';
NODE_NAME     J28 264
 '@S9S_MB_2U_LIB.S9S_MB_2U(SCH_1):PAGE109_I176@PURE_QUANTA.SCONN288_ADR50017P087CC(CHIPS)':
 'VSS115': CDS_PINID='VSS115';
NODE_NAME     J28 266
 '@S9S_MB_2U_LIB.S9S_MB_2U(SCH_1):PAGE109_I176@PURE_QUANTA.SCONN288_ADR50017P087CC(CHIPS)':
 'VSS116': CDS_PINID='VSS116';
NODE_NAME     J28 268
 '@S9S_MB_2U_LIB.S9S_MB_2U(SCH_1):PAGE109_I176@PURE_QUANTA.SCONN288_ADR50017P087CC(CHIPS)':
 'VSS117': CDS_PINID='VSS117';
NODE_NAME     J28 270
 '@S9S_MB_2U_LIB.S9S_MB_2U(SCH_1):PAGE109_I176@PURE_QUANTA.SCONN288_ADR50017P087CC(CHIPS)':
 'VSS118': CDS_PINID='VSS118';
NODE_NAME     J28 273
 '@S9S_MB_2U_LIB.S9S_MB_2U(SCH_1):PAGE109_I176@PURE_QUANTA.SCONN288_ADR50017P087CC(CHIPS)':
 'VSS119': CDS_PINID='VSS119';
NODE_NAME     J28 275
 '@S9S_MB_2U_LIB.S9S_MB_2U(SCH_1):PAGE109_I176@PURE_QUANTA.SCONN288_ADR50017P087CC(CHIPS)':
 'VSS120': CDS_PINID='VSS120';
NODE_NAME     J28 277
 '@S9S_MB_2U_LIB.S9S_MB_2U(SCH_1):PAGE109_I176@PURE_QUANTA.SCONN288_ADR50017P087CC(CHIPS)':
 'VSS121': CDS_PINID='VSS121';
NODE_NAME     J28 279
 '@S9S_MB_2U_LIB.S9S_MB_2U(SCH_1):PAGE109_I176@PURE_QUANTA.SCONN288_ADR50017P087CC(CHIPS)':
 'VSS122': CDS_PINID='VSS122';
NODE_NAME     J28 281
 '@S9S_MB_2U_LIB.S9S_MB_2U(SCH_1):PAGE109_I176@PURE_QUANTA.SCONN288_ADR50017P087CC(CHIPS)':
 'VSS123': CDS_PINID='VSS123';
NODE_NAME     J28 284
 '@S9S_MB_2U_LIB.S9S_MB_2U(SCH_1):PAGE109_I176@PURE_QUANTA.SCONN288_ADR50017P087CC(CHIPS)':
 'VSS124': CDS_PINID='VSS124';
NODE_NAME     J28 286
 '@S9S_MB_2U_LIB.S9S_MB_2U(SCH_1):PAGE109_I176@PURE_QUANTA.SCONN288_ADR50017P087CC(CHIPS)':
 'VSS125': CDS_PINID='VSS125';
NODE_NAME     J28 288
 '@S9S_MB_2U_LIB.S9S_MB_2U(SCH_1):PAGE109_I176@PURE_QUANTA.SCONN288_ADR50017P087CC(CHIPS)':
 'VSS126': CDS_PINID='VSS126';
NODE_NAME     R75 2
 '@S9S_MB_2U_LIB.S9S_MB_2U(SCH_1):PAGE110_I47@PURE_QUANTA.Q_RES(CHIPS)':
 'B': CDS_PINID='B';
NODE_NAME     C81 2
 '@S9S_MB_2U_LIB.S9S_MB_2U(SCH_1):PAGE110_I120@PURE_QUANTA.Q_CAP(CHIPS)':
 'B': CDS_PINID='B';
NODE_NAME     C82 2
 '@S9S_MB_2U_LIB.S9S_MB_2U(SCH_1):PAGE110_I124@PURE_QUANTA.Q_CAP(CHIPS)':
 'B': CDS_PINID='B';
NODE_NAME     C83 2
 '@S9S_MB_2U_LIB.S9S_MB_2U(SCH_1):PAGE110_I126@PURE_QUANTA.Q_CAP(CHIPS)':
 'B': CDS_PINID='B';
NODE_NAME     J29 G1
 '@S9S_MB_2U_LIB.S9S_MB_2U(SCH_1):PAGE110_I178@PURE_QUANTA.SCONN288_ADR50017P130CC(CHIPS)':
 'G1': CDS_PINID='G1';
NODE_NAME     J29 G2
 '@S9S_MB_2U_LIB.S9S_MB_2U(SCH_1):PAGE110_I178@PURE_QUANTA.SCONN288_ADR50017P130CC(CHIPS)':
 'G2': CDS_PINID='G2';
NODE_NAME     J29 G3
 '@S9S_MB_2U_LIB.S9S_MB_2U(SCH_1):PAGE110_I178@PURE_QUANTA.SCONN288_ADR50017P130CC(CHIPS)':
 'G3': CDS_PINID='G3';
NODE_NAME     J29 6
 '@S9S_MB_2U_LIB.S9S_MB_2U(SCH_1):PAGE110_I178@PURE_QUANTA.SCONN288_ADR50017P130CC(CHIPS)':
 'VSS0': CDS_PINID='VSS0';
NODE_NAME     J29 8
 '@S9S_MB_2U_LIB.S9S_MB_2U(SCH_1):PAGE110_I178@PURE_QUANTA.SCONN288_ADR50017P130CC(CHIPS)':
 'VSS1': CDS_PINID='VSS1';
NODE_NAME     J29 10
 '@S9S_MB_2U_LIB.S9S_MB_2U(SCH_1):PAGE110_I178@PURE_QUANTA.SCONN288_ADR50017P130CC(CHIPS)':
 'VSS2': CDS_PINID='VSS2';
NODE_NAME     J29 13
 '@S9S_MB_2U_LIB.S9S_MB_2U(SCH_1):PAGE110_I178@PURE_QUANTA.SCONN288_ADR50017P130CC(CHIPS)':
 'VSS3': CDS_PINID='VSS3';
NODE_NAME     J29 15
 '@S9S_MB_2U_LIB.S9S_MB_2U(SCH_1):PAGE110_I178@PURE_QUANTA.SCONN288_ADR50017P130CC(CHIPS)':
 'VSS4': CDS_PINID='VSS4';
NODE_NAME     J29 17
 '@S9S_MB_2U_LIB.S9S_MB_2U(SCH_1):PAGE110_I178@PURE_QUANTA.SCONN288_ADR50017P130CC(CHIPS)':
 'VSS5': CDS_PINID='VSS5';
NODE_NAME     J29 19
 '@S9S_MB_2U_LIB.S9S_MB_2U(SCH_1):PAGE110_I178@PURE_QUANTA.SCONN288_ADR50017P130CC(CHIPS)':
 'VSS6': CDS_PINID='VSS6';
NODE_NAME     J29 21
 '@S9S_MB_2U_LIB.S9S_MB_2U(SCH_1):PAGE110_I178@PURE_QUANTA.SCONN288_ADR50017P130CC(CHIPS)':
 'VSS7': CDS_PINID='VSS7';
NODE_NAME     J29 24
 '@S9S_MB_2U_LIB.S9S_MB_2U(SCH_1):PAGE110_I178@PURE_QUANTA.SCONN288_ADR50017P130CC(CHIPS)':
 'VSS8': CDS_PINID='VSS8';
NODE_NAME     J29 26
 '@S9S_MB_2U_LIB.S9S_MB_2U(SCH_1):PAGE110_I178@PURE_QUANTA.SCONN288_ADR50017P130CC(CHIPS)':
 'VSS9': CDS_PINID='VSS9';
NODE_NAME     J29 28
 '@S9S_MB_2U_LIB.S9S_MB_2U(SCH_1):PAGE110_I178@PURE_QUANTA.SCONN288_ADR50017P130CC(CHIPS)':
 'VSS10': CDS_PINID='VSS10';
NODE_NAME     J29 30
 '@S9S_MB_2U_LIB.S9S_MB_2U(SCH_1):PAGE110_I178@PURE_QUANTA.SCONN288_ADR50017P130CC(CHIPS)':
 'VSS11': CDS_PINID='VSS11';
NODE_NAME     J29 32
 '@S9S_MB_2U_LIB.S9S_MB_2U(SCH_1):PAGE110_I178@PURE_QUANTA.SCONN288_ADR50017P130CC(CHIPS)':
 'VSS12': CDS_PINID='VSS12';
NODE_NAME     J29 35
 '@S9S_MB_2U_LIB.S9S_MB_2U(SCH_1):PAGE110_I178@PURE_QUANTA.SCONN288_ADR50017P130CC(CHIPS)':
 'VSS13': CDS_PINID='VSS13';
NODE_NAME     J29 37
 '@S9S_MB_2U_LIB.S9S_MB_2U(SCH_1):PAGE110_I178@PURE_QUANTA.SCONN288_ADR50017P130CC(CHIPS)':
 'VSS14': CDS_PINID='VSS14';
NODE_NAME     J29 39
 '@S9S_MB_2U_LIB.S9S_MB_2U(SCH_1):PAGE110_I178@PURE_QUANTA.SCONN288_ADR50017P130CC(CHIPS)':
 'VSS15': CDS_PINID='VSS15';
NODE_NAME     J29 41
 '@S9S_MB_2U_LIB.S9S_MB_2U(SCH_1):PAGE110_I178@PURE_QUANTA.SCONN288_ADR50017P130CC(CHIPS)':
 'VSS16': CDS_PINID='VSS16';
NODE_NAME     J29 43
 '@S9S_MB_2U_LIB.S9S_MB_2U(SCH_1):PAGE110_I178@PURE_QUANTA.SCONN288_ADR50017P130CC(CHIPS)':
 'VSS17': CDS_PINID='VSS17';
NODE_NAME     J29 46
 '@S9S_MB_2U_LIB.S9S_MB_2U(SCH_1):PAGE110_I178@PURE_QUANTA.SCONN288_ADR50017P130CC(CHIPS)':
 'VSS18': CDS_PINID='VSS18';
NODE_NAME     J29 48
 '@S9S_MB_2U_LIB.S9S_MB_2U(SCH_1):PAGE110_I178@PURE_QUANTA.SCONN288_ADR50017P130CC(CHIPS)':
 'VSS19': CDS_PINID='VSS19';
NODE_NAME     J29 50
 '@S9S_MB_2U_LIB.S9S_MB_2U(SCH_1):PAGE110_I178@PURE_QUANTA.SCONN288_ADR50017P130CC(CHIPS)':
 'VSS20': CDS_PINID='VSS20';
NODE_NAME     J29 52
 '@S9S_MB_2U_LIB.S9S_MB_2U(SCH_1):PAGE110_I178@PURE_QUANTA.SCONN288_ADR50017P130CC(CHIPS)':
 'VSS21': CDS_PINID='VSS21';
NODE_NAME     J29 54
 '@S9S_MB_2U_LIB.S9S_MB_2U(SCH_1):PAGE110_I178@PURE_QUANTA.SCONN288_ADR50017P130CC(CHIPS)':
 'VSS22': CDS_PINID='VSS22';
NODE_NAME     J29 57
 '@S9S_MB_2U_LIB.S9S_MB_2U(SCH_1):PAGE110_I178@PURE_QUANTA.SCONN288_ADR50017P130CC(CHIPS)':
 'VSS23': CDS_PINID='VSS23';
NODE_NAME     J29 59
 '@S9S_MB_2U_LIB.S9S_MB_2U(SCH_1):PAGE110_I178@PURE_QUANTA.SCONN288_ADR50017P130CC(CHIPS)':
 'VSS24': CDS_PINID='VSS24';
NODE_NAME     J29 61
 '@S9S_MB_2U_LIB.S9S_MB_2U(SCH_1):PAGE110_I178@PURE_QUANTA.SCONN288_ADR50017P130CC(CHIPS)':
 'VSS25': CDS_PINID='VSS25';
NODE_NAME     J29 63
 '@S9S_MB_2U_LIB.S9S_MB_2U(SCH_1):PAGE110_I178@PURE_QUANTA.SCONN288_ADR50017P130CC(CHIPS)':
 'VSS26': CDS_PINID='VSS26';
NODE_NAME     J29 65
 '@S9S_MB_2U_LIB.S9S_MB_2U(SCH_1):PAGE110_I178@PURE_QUANTA.SCONN288_ADR50017P130CC(CHIPS)':
 'VSS27': CDS_PINID='VSS27';
NODE_NAME     J29 67
 '@S9S_MB_2U_LIB.S9S_MB_2U(SCH_1):PAGE110_I178@PURE_QUANTA.SCONN288_ADR50017P130CC(CHIPS)':
 'VSS28': CDS_PINID='VSS28';
NODE_NAME     J29 69
 '@S9S_MB_2U_LIB.S9S_MB_2U(SCH_1):PAGE110_I178@PURE_QUANTA.SCONN288_ADR50017P130CC(CHIPS)':
 'VSS29': CDS_PINID='VSS29';
NODE_NAME     J29 71
 '@S9S_MB_2U_LIB.S9S_MB_2U(SCH_1):PAGE110_I178@PURE_QUANTA.SCONN288_ADR50017P130CC(CHIPS)':
 'VSS30': CDS_PINID='VSS30';
NODE_NAME     J29 73
 '@S9S_MB_2U_LIB.S9S_MB_2U(SCH_1):PAGE110_I178@PURE_QUANTA.SCONN288_ADR50017P130CC(CHIPS)':
 'VSS31': CDS_PINID='VSS31';
NODE_NAME     J29 75
 '@S9S_MB_2U_LIB.S9S_MB_2U(SCH_1):PAGE110_I178@PURE_QUANTA.SCONN288_ADR50017P130CC(CHIPS)':
 'VSS32': CDS_PINID='VSS32';
NODE_NAME     J29 77
 '@S9S_MB_2U_LIB.S9S_MB_2U(SCH_1):PAGE110_I178@PURE_QUANTA.SCONN288_ADR50017P130CC(CHIPS)':
 'VSS33': CDS_PINID='VSS33';
NODE_NAME     J29 79
 '@S9S_MB_2U_LIB.S9S_MB_2U(SCH_1):PAGE110_I178@PURE_QUANTA.SCONN288_ADR50017P130CC(CHIPS)':
 'VSS34': CDS_PINID='VSS34';
NODE_NAME     J29 81
 '@S9S_MB_2U_LIB.S9S_MB_2U(SCH_1):PAGE110_I178@PURE_QUANTA.SCONN288_ADR50017P130CC(CHIPS)':
 'VSS35': CDS_PINID='VSS35';
NODE_NAME     J29 83
 '@S9S_MB_2U_LIB.S9S_MB_2U(SCH_1):PAGE110_I178@PURE_QUANTA.SCONN288_ADR50017P130CC(CHIPS)':
 'VSS36': CDS_PINID='VSS36';
NODE_NAME     J29 85
 '@S9S_MB_2U_LIB.S9S_MB_2U(SCH_1):PAGE110_I178@PURE_QUANTA.SCONN288_ADR50017P130CC(CHIPS)':
 'VSS37': CDS_PINID='VSS37';
NODE_NAME     J29 88
 '@S9S_MB_2U_LIB.S9S_MB_2U(SCH_1):PAGE110_I178@PURE_QUANTA.SCONN288_ADR50017P130CC(CHIPS)':
 'VSS38': CDS_PINID='VSS38';
NODE_NAME     J29 90
 '@S9S_MB_2U_LIB.S9S_MB_2U(SCH_1):PAGE110_I178@PURE_QUANTA.SCONN288_ADR50017P130CC(CHIPS)':
 'VSS39': CDS_PINID='VSS39';
NODE_NAME     J29 92
 '@S9S_MB_2U_LIB.S9S_MB_2U(SCH_1):PAGE110_I178@PURE_QUANTA.SCONN288_ADR50017P130CC(CHIPS)':
 'VSS40': CDS_PINID='VSS40';
NODE_NAME     J29 95
 '@S9S_MB_2U_LIB.S9S_MB_2U(SCH_1):PAGE110_I178@PURE_QUANTA.SCONN288_ADR50017P130CC(CHIPS)':
 'VSS41': CDS_PINID='VSS41';
NODE_NAME     J29 97
 '@S9S_MB_2U_LIB.S9S_MB_2U(SCH_1):PAGE110_I178@PURE_QUANTA.SCONN288_ADR50017P130CC(CHIPS)':
 'VSS42': CDS_PINID='VSS42';
NODE_NAME     J29 99
 '@S9S_MB_2U_LIB.S9S_MB_2U(SCH_1):PAGE110_I178@PURE_QUANTA.SCONN288_ADR50017P130CC(CHIPS)':
 'VSS43': CDS_PINID='VSS43';
NODE_NAME     J29 101
 '@S9S_MB_2U_LIB.S9S_MB_2U(SCH_1):PAGE110_I178@PURE_QUANTA.SCONN288_ADR50017P130CC(CHIPS)':
 'VSS44': CDS_PINID='VSS44';
NODE_NAME     J29 103
 '@S9S_MB_2U_LIB.S9S_MB_2U(SCH_1):PAGE110_I178@PURE_QUANTA.SCONN288_ADR50017P130CC(CHIPS)':
 'VSS45': CDS_PINID='VSS45';
NODE_NAME     J29 106
 '@S9S_MB_2U_LIB.S9S_MB_2U(SCH_1):PAGE110_I178@PURE_QUANTA.SCONN288_ADR50017P130CC(CHIPS)':
 'VSS46': CDS_PINID='VSS46';
NODE_NAME     J29 108
 '@S9S_MB_2U_LIB.S9S_MB_2U(SCH_1):PAGE110_I178@PURE_QUANTA.SCONN288_ADR50017P130CC(CHIPS)':
 'VSS47': CDS_PINID='VSS47';
NODE_NAME     J29 110
 '@S9S_MB_2U_LIB.S9S_MB_2U(SCH_1):PAGE110_I178@PURE_QUANTA.SCONN288_ADR50017P130CC(CHIPS)':
 'VSS48': CDS_PINID='VSS48';
NODE_NAME     J29 112
 '@S9S_MB_2U_LIB.S9S_MB_2U(SCH_1):PAGE110_I178@PURE_QUANTA.SCONN288_ADR50017P130CC(CHIPS)':
 'VSS49': CDS_PINID='VSS49';
NODE_NAME     J29 114
 '@S9S_MB_2U_LIB.S9S_MB_2U(SCH_1):PAGE110_I178@PURE_QUANTA.SCONN288_ADR50017P130CC(CHIPS)':
 'VSS50': CDS_PINID='VSS50';
NODE_NAME     J29 117
 '@S9S_MB_2U_LIB.S9S_MB_2U(SCH_1):PAGE110_I178@PURE_QUANTA.SCONN288_ADR50017P130CC(CHIPS)':
 'VSS51': CDS_PINID='VSS51';
NODE_NAME     J29 119
 '@S9S_MB_2U_LIB.S9S_MB_2U(SCH_1):PAGE110_I178@PURE_QUANTA.SCONN288_ADR50017P130CC(CHIPS)':
 'VSS52': CDS_PINID='VSS52';
NODE_NAME     J29 121
 '@S9S_MB_2U_LIB.S9S_MB_2U(SCH_1):PAGE110_I178@PURE_QUANTA.SCONN288_ADR50017P130CC(CHIPS)':
 'VSS53': CDS_PINID='VSS53';
NODE_NAME     J29 123
 '@S9S_MB_2U_LIB.S9S_MB_2U(SCH_1):PAGE110_I178@PURE_QUANTA.SCONN288_ADR50017P130CC(CHIPS)':
 'VSS54': CDS_PINID='VSS54';
NODE_NAME     J29 125
 '@S9S_MB_2U_LIB.S9S_MB_2U(SCH_1):PAGE110_I178@PURE_QUANTA.SCONN288_ADR50017P130CC(CHIPS)':
 'VSS55': CDS_PINID='VSS55';
NODE_NAME     J29 128
 '@S9S_MB_2U_LIB.S9S_MB_2U(SCH_1):PAGE110_I178@PURE_QUANTA.SCONN288_ADR50017P130CC(CHIPS)':
 'VSS56': CDS_PINID='VSS56';
NODE_NAME     J29 130
 '@S9S_MB_2U_LIB.S9S_MB_2U(SCH_1):PAGE110_I178@PURE_QUANTA.SCONN288_ADR50017P130CC(CHIPS)':
 'VSS57': CDS_PINID='VSS57';
NODE_NAME     J29 132
 '@S9S_MB_2U_LIB.S9S_MB_2U(SCH_1):PAGE110_I178@PURE_QUANTA.SCONN288_ADR50017P130CC(CHIPS)':
 'VSS58': CDS_PINID='VSS58';
NODE_NAME     J29 134
 '@S9S_MB_2U_LIB.S9S_MB_2U(SCH_1):PAGE110_I178@PURE_QUANTA.SCONN288_ADR50017P130CC(CHIPS)':
 'VSS59': CDS_PINID='VSS59';
NODE_NAME     J29 136
 '@S9S_MB_2U_LIB.S9S_MB_2U(SCH_1):PAGE110_I178@PURE_QUANTA.SCONN288_ADR50017P130CC(CHIPS)':
 'VSS60': CDS_PINID='VSS60';
NODE_NAME     J29 139
 '@S9S_MB_2U_LIB.S9S_MB_2U(SCH_1):PAGE110_I178@PURE_QUANTA.SCONN288_ADR50017P130CC(CHIPS)':
 'VSS61': CDS_PINID='VSS61';
NODE_NAME     J29 141
 '@S9S_MB_2U_LIB.S9S_MB_2U(SCH_1):PAGE110_I178@PURE_QUANTA.SCONN288_ADR50017P130CC(CHIPS)':
 'VSS62': CDS_PINID='VSS62';
NODE_NAME     J29 143
 '@S9S_MB_2U_LIB.S9S_MB_2U(SCH_1):PAGE110_I178@PURE_QUANTA.SCONN288_ADR50017P130CC(CHIPS)':
 'VSS63': CDS_PINID='VSS63';
NODE_NAME     J29 151
 '@S9S_MB_2U_LIB.S9S_MB_2U(SCH_1):PAGE110_I178@PURE_QUANTA.SCONN288_ADR50017P130CC(CHIPS)':
 'VSS64': CDS_PINID='VSS64';
NODE_NAME     J29 153
 '@S9S_MB_2U_LIB.S9S_MB_2U(SCH_1):PAGE110_I178@PURE_QUANTA.SCONN288_ADR50017P130CC(CHIPS)':
 'VSS65': CDS_PINID='VSS65';
NODE_NAME     J29 155
 '@S9S_MB_2U_LIB.S9S_MB_2U(SCH_1):PAGE110_I178@PURE_QUANTA.SCONN288_ADR50017P130CC(CHIPS)':
 'VSS66': CDS_PINID='VSS66';
NODE_NAME     J29 158
 '@S9S_MB_2U_LIB.S9S_MB_2U(SCH_1):PAGE110_I178@PURE_QUANTA.SCONN288_ADR50017P130CC(CHIPS)':
 'VSS67': CDS_PINID='VSS67';
NODE_NAME     J29 160
 '@S9S_MB_2U_LIB.S9S_MB_2U(SCH_1):PAGE110_I178@PURE_QUANTA.SCONN288_ADR50017P130CC(CHIPS)':
 'VSS68': CDS_PINID='VSS68';
NODE_NAME     J29 162
 '@S9S_MB_2U_LIB.S9S_MB_2U(SCH_1):PAGE110_I178@PURE_QUANTA.SCONN288_ADR50017P130CC(CHIPS)':
 'VSS69': CDS_PINID='VSS69';
NODE_NAME     J29 164
 '@S9S_MB_2U_LIB.S9S_MB_2U(SCH_1):PAGE110_I178@PURE_QUANTA.SCONN288_ADR50017P130CC(CHIPS)':
 'VSS70': CDS_PINID='VSS70';
NODE_NAME     J29 166
 '@S9S_MB_2U_LIB.S9S_MB_2U(SCH_1):PAGE110_I178@PURE_QUANTA.SCONN288_ADR50017P130CC(CHIPS)':
 'VSS71': CDS_PINID='VSS71';
NODE_NAME     J29 169
 '@S9S_MB_2U_LIB.S9S_MB_2U(SCH_1):PAGE110_I178@PURE_QUANTA.SCONN288_ADR50017P130CC(CHIPS)':
 'VSS72': CDS_PINID='VSS72';
NODE_NAME     J29 171
 '@S9S_MB_2U_LIB.S9S_MB_2U(SCH_1):PAGE110_I178@PURE_QUANTA.SCONN288_ADR50017P130CC(CHIPS)':
 'VSS73': CDS_PINID='VSS73';
NODE_NAME     J29 173
 '@S9S_MB_2U_LIB.S9S_MB_2U(SCH_1):PAGE110_I178@PURE_QUANTA.SCONN288_ADR50017P130CC(CHIPS)':
 'VSS74': CDS_PINID='VSS74';
NODE_NAME     J29 175
 '@S9S_MB_2U_LIB.S9S_MB_2U(SCH_1):PAGE110_I178@PURE_QUANTA.SCONN288_ADR50017P130CC(CHIPS)':
 'VSS75': CDS_PINID='VSS75';
NODE_NAME     J29 177
 '@S9S_MB_2U_LIB.S9S_MB_2U(SCH_1):PAGE110_I178@PURE_QUANTA.SCONN288_ADR50017P130CC(CHIPS)':
 'VSS76': CDS_PINID='VSS76';
NODE_NAME     J29 180
 '@S9S_MB_2U_LIB.S9S_MB_2U(SCH_1):PAGE110_I178@PURE_QUANTA.SCONN288_ADR50017P130CC(CHIPS)':
 'VSS77': CDS_PINID='VSS77';
NODE_NAME     J29 182
 '@S9S_MB_2U_LIB.S9S_MB_2U(SCH_1):PAGE110_I178@PURE_QUANTA.SCONN288_ADR50017P130CC(CHIPS)':
 'VSS78': CDS_PINID='VSS78';
NODE_NAME     J29 184
 '@S9S_MB_2U_LIB.S9S_MB_2U(SCH_1):PAGE110_I178@PURE_QUANTA.SCONN288_ADR50017P130CC(CHIPS)':
 'VSS79': CDS_PINID='VSS79';
NODE_NAME     J29 186
 '@S9S_MB_2U_LIB.S9S_MB_2U(SCH_1):PAGE110_I178@PURE_QUANTA.SCONN288_ADR50017P130CC(CHIPS)':
 'VSS80': CDS_PINID='VSS80';
NODE_NAME     J29 188
 '@S9S_MB_2U_LIB.S9S_MB_2U(SCH_1):PAGE110_I178@PURE_QUANTA.SCONN288_ADR50017P130CC(CHIPS)':
 'VSS81': CDS_PINID='VSS81';
NODE_NAME     J29 191
 '@S9S_MB_2U_LIB.S9S_MB_2U(SCH_1):PAGE110_I178@PURE_QUANTA.SCONN288_ADR50017P130CC(CHIPS)':
 'VSS82': CDS_PINID='VSS82';
NODE_NAME     J29 193
 '@S9S_MB_2U_LIB.S9S_MB_2U(SCH_1):PAGE110_I178@PURE_QUANTA.SCONN288_ADR50017P130CC(CHIPS)':
 'VSS83': CDS_PINID='VSS83';
NODE_NAME     J29 195
 '@S9S_MB_2U_LIB.S9S_MB_2U(SCH_1):PAGE110_I178@PURE_QUANTA.SCONN288_ADR50017P130CC(CHIPS)':
 'VSS84': CDS_PINID='VSS84';
NODE_NAME     J29 197
 '@S9S_MB_2U_LIB.S9S_MB_2U(SCH_1):PAGE110_I178@PURE_QUANTA.SCONN288_ADR50017P130CC(CHIPS)':
 'VSS85': CDS_PINID='VSS85';
NODE_NAME     J29 199
 '@S9S_MB_2U_LIB.S9S_MB_2U(SCH_1):PAGE110_I178@PURE_QUANTA.SCONN288_ADR50017P130CC(CHIPS)':
 'VSS86': CDS_PINID='VSS86';
NODE_NAME     J29 202
 '@S9S_MB_2U_LIB.S9S_MB_2U(SCH_1):PAGE110_I178@PURE_QUANTA.SCONN288_ADR50017P130CC(CHIPS)':
 'VSS87': CDS_PINID='VSS87';
NODE_NAME     J29 204
 '@S9S_MB_2U_LIB.S9S_MB_2U(SCH_1):PAGE110_I178@PURE_QUANTA.SCONN288_ADR50017P130CC(CHIPS)':
 'VSS88': CDS_PINID='VSS88';
NODE_NAME     J29 206
 '@S9S_MB_2U_LIB.S9S_MB_2U(SCH_1):PAGE110_I178@PURE_QUANTA.SCONN288_ADR50017P130CC(CHIPS)':
 'VSS89': CDS_PINID='VSS89';
NODE_NAME     J29 208
 '@S9S_MB_2U_LIB.S9S_MB_2U(SCH_1):PAGE110_I178@PURE_QUANTA.SCONN288_ADR50017P130CC(CHIPS)':
 'VSS90': CDS_PINID='VSS90';
NODE_NAME     J29 210
 '@S9S_MB_2U_LIB.S9S_MB_2U(SCH_1):PAGE110_I178@PURE_QUANTA.SCONN288_ADR50017P130CC(CHIPS)':
 'VSS91': CDS_PINID='VSS91';
NODE_NAME     J29 212
 '@S9S_MB_2U_LIB.S9S_MB_2U(SCH_1):PAGE110_I178@PURE_QUANTA.SCONN288_ADR50017P130CC(CHIPS)':
 'VSS92': CDS_PINID='VSS92';
NODE_NAME     J29 214
 '@S9S_MB_2U_LIB.S9S_MB_2U(SCH_1):PAGE110_I178@PURE_QUANTA.SCONN288_ADR50017P130CC(CHIPS)':
 'VSS93': CDS_PINID='VSS93';
NODE_NAME     J29 216
 '@S9S_MB_2U_LIB.S9S_MB_2U(SCH_1):PAGE110_I178@PURE_QUANTA.SCONN288_ADR50017P130CC(CHIPS)':
 'VSS94': CDS_PINID='VSS94';
NODE_NAME     J29 219
 '@S9S_MB_2U_LIB.S9S_MB_2U(SCH_1):PAGE110_I178@PURE_QUANTA.SCONN288_ADR50017P130CC(CHIPS)':
 'VSS95': CDS_PINID='VSS95';
NODE_NAME     J29 222
 '@S9S_MB_2U_LIB.S9S_MB_2U(SCH_1):PAGE110_I178@PURE_QUANTA.SCONN288_ADR50017P130CC(CHIPS)':
 'VSS96': CDS_PINID='VSS96';
NODE_NAME     J29 224
 '@S9S_MB_2U_LIB.S9S_MB_2U(SCH_1):PAGE110_I178@PURE_QUANTA.SCONN288_ADR50017P130CC(CHIPS)':
 'VSS97': CDS_PINID='VSS97';
NODE_NAME     J29 226
 '@S9S_MB_2U_LIB.S9S_MB_2U(SCH_1):PAGE110_I178@PURE_QUANTA.SCONN288_ADR50017P130CC(CHIPS)':
 'VSS98': CDS_PINID='VSS98';
NODE_NAME     J29 228
 '@S9S_MB_2U_LIB.S9S_MB_2U(SCH_1):PAGE110_I178@PURE_QUANTA.SCONN288_ADR50017P130CC(CHIPS)':
 'VSS99': CDS_PINID='VSS99';
NODE_NAME     J29 230
 '@S9S_MB_2U_LIB.S9S_MB_2U(SCH_1):PAGE110_I178@PURE_QUANTA.SCONN288_ADR50017P130CC(CHIPS)':
 'VSS100': CDS_PINID='VSS100';
NODE_NAME     J29 233
 '@S9S_MB_2U_LIB.S9S_MB_2U(SCH_1):PAGE110_I178@PURE_QUANTA.SCONN288_ADR50017P130CC(CHIPS)':
 'VSS101': CDS_PINID='VSS101';
NODE_NAME     J29 235
 '@S9S_MB_2U_LIB.S9S_MB_2U(SCH_1):PAGE110_I178@PURE_QUANTA.SCONN288_ADR50017P130CC(CHIPS)':
 'VSS102': CDS_PINID='VSS102';
NODE_NAME     J29 237
 '@S9S_MB_2U_LIB.S9S_MB_2U(SCH_1):PAGE110_I178@PURE_QUANTA.SCONN288_ADR50017P130CC(CHIPS)':
 'VSS103': CDS_PINID='VSS103';
NODE_NAME     J29 240
 '@S9S_MB_2U_LIB.S9S_MB_2U(SCH_1):PAGE110_I178@PURE_QUANTA.SCONN288_ADR50017P130CC(CHIPS)':
 'VSS104': CDS_PINID='VSS104';
NODE_NAME     J29 242
 '@S9S_MB_2U_LIB.S9S_MB_2U(SCH_1):PAGE110_I178@PURE_QUANTA.SCONN288_ADR50017P130CC(CHIPS)':
 'VSS105': CDS_PINID='VSS105';
NODE_NAME     J29 244
 '@S9S_MB_2U_LIB.S9S_MB_2U(SCH_1):PAGE110_I178@PURE_QUANTA.SCONN288_ADR50017P130CC(CHIPS)':
 'VSS106': CDS_PINID='VSS106';
NODE_NAME     J29 246
 '@S9S_MB_2U_LIB.S9S_MB_2U(SCH_1):PAGE110_I178@PURE_QUANTA.SCONN288_ADR50017P130CC(CHIPS)':
 'VSS107': CDS_PINID='VSS107';
NODE_NAME     J29 248
 '@S9S_MB_2U_LIB.S9S_MB_2U(SCH_1):PAGE110_I178@PURE_QUANTA.SCONN288_ADR50017P130CC(CHIPS)':
 'VSS108': CDS_PINID='VSS108';
NODE_NAME     J29 251
 '@S9S_MB_2U_LIB.S9S_MB_2U(SCH_1):PAGE110_I178@PURE_QUANTA.SCONN288_ADR50017P130CC(CHIPS)':
 'VSS109': CDS_PINID='VSS109';
NODE_NAME     J29 253
 '@S9S_MB_2U_LIB.S9S_MB_2U(SCH_1):PAGE110_I178@PURE_QUANTA.SCONN288_ADR50017P130CC(CHIPS)':
 'VSS110': CDS_PINID='VSS110';
NODE_NAME     J29 255
 '@S9S_MB_2U_LIB.S9S_MB_2U(SCH_1):PAGE110_I178@PURE_QUANTA.SCONN288_ADR50017P130CC(CHIPS)':
 'VSS111': CDS_PINID='VSS111';
NODE_NAME     J29 257
 '@S9S_MB_2U_LIB.S9S_MB_2U(SCH_1):PAGE110_I178@PURE_QUANTA.SCONN288_ADR50017P130CC(CHIPS)':
 'VSS112': CDS_PINID='VSS112';
NODE_NAME     J29 259
 '@S9S_MB_2U_LIB.S9S_MB_2U(SCH_1):PAGE110_I178@PURE_QUANTA.SCONN288_ADR50017P130CC(CHIPS)':
 'VSS113': CDS_PINID='VSS113';
NODE_NAME     J29 262
 '@S9S_MB_2U_LIB.S9S_MB_2U(SCH_1):PAGE110_I178@PURE_QUANTA.SCONN288_ADR50017P130CC(CHIPS)':
 'VSS114': CDS_PINID='VSS114';
NODE_NAME     J29 264
 '@S9S_MB_2U_LIB.S9S_MB_2U(SCH_1):PAGE110_I178@PURE_QUANTA.SCONN288_ADR50017P130CC(CHIPS)':
 'VSS115': CDS_PINID='VSS115';
NODE_NAME     J29 266
 '@S9S_MB_2U_LIB.S9S_MB_2U(SCH_1):PAGE110_I178@PURE_QUANTA.SCONN288_ADR50017P130CC(CHIPS)':
 'VSS116': CDS_PINID='VSS116';
NODE_NAME     J29 268
 '@S9S_MB_2U_LIB.S9S_MB_2U(SCH_1):PAGE110_I178@PURE_QUANTA.SCONN288_ADR50017P130CC(CHIPS)':
 'VSS117': CDS_PINID='VSS117';
NODE_NAME     J29 270
 '@S9S_MB_2U_LIB.S9S_MB_2U(SCH_1):PAGE110_I178@PURE_QUANTA.SCONN288_ADR50017P130CC(CHIPS)':
 'VSS118': CDS_PINID='VSS118';
NODE_NAME     J29 273
 '@S9S_MB_2U_LIB.S9S_MB_2U(SCH_1):PAGE110_I178@PURE_QUANTA.SCONN288_ADR50017P130CC(CHIPS)':
 'VSS119': CDS_PINID='VSS119';
NODE_NAME     J29 275
 '@S9S_MB_2U_LIB.S9S_MB_2U(SCH_1):PAGE110_I178@PURE_QUANTA.SCONN288_ADR50017P130CC(CHIPS)':
 'VSS120': CDS_PINID='VSS120';
NODE_NAME     J29 277
 '@S9S_MB_2U_LIB.S9S_MB_2U(SCH_1):PAGE110_I178@PURE_QUANTA.SCONN288_ADR50017P130CC(CHIPS)':
 'VSS121': CDS_PINID='VSS121';
NODE_NAME     J29 279
 '@S9S_MB_2U_LIB.S9S_MB_2U(SCH_1):PAGE110_I178@PURE_QUANTA.SCONN288_ADR50017P130CC(CHIPS)':
 'VSS122': CDS_PINID='VSS122';
NODE_NAME     J29 281
 '@S9S_MB_2U_LIB.S9S_MB_2U(SCH_1):PAGE110_I178@PURE_QUANTA.SCONN288_ADR50017P130CC(CHIPS)':
 'VSS123': CDS_PINID='VSS123';
NODE_NAME     J29 284
 '@S9S_MB_2U_LIB.S9S_MB_2U(SCH_1):PAGE110_I178@PURE_QUANTA.SCONN288_ADR50017P130CC(CHIPS)':
 'VSS124': CDS_PINID='VSS124';
NODE_NAME     J29 286
 '@S9S_MB_2U_LIB.S9S_MB_2U(SCH_1):PAGE110_I178@PURE_QUANTA.SCONN288_ADR50017P130CC(CHIPS)':
 'VSS125': CDS_PINID='VSS125';
NODE_NAME     J29 288
 '@S9S_MB_2U_LIB.S9S_MB_2U(SCH_1):PAGE110_I178@PURE_QUANTA.SCONN288_ADR50017P130CC(CHIPS)':
 'VSS126': CDS_PINID='VSS126';
NODE_NAME     R74 2
 '@S9S_MB_2U_LIB.S9S_MB_2U(SCH_1):PAGE111_I5@PURE_QUANTA.Q_RES(CHIPS)':
 'B': CDS_PINID='B';
NODE_NAME     C78 2
 '@S9S_MB_2U_LIB.S9S_MB_2U(SCH_1):PAGE111_I54@PURE_QUANTA.Q_CAP(CHIPS)':
 'B': CDS_PINID='B';
NODE_NAME     C79 2
 '@S9S_MB_2U_LIB.S9S_MB_2U(SCH_1):PAGE111_I56@PURE_QUANTA.Q_CAP(CHIPS)':
 'B': CDS_PINID='B';
NODE_NAME     C80 2
 '@S9S_MB_2U_LIB.S9S_MB_2U(SCH_1):PAGE111_I59@PURE_QUANTA.Q_CAP(CHIPS)':
 'B': CDS_PINID='B';
NODE_NAME     J30 G1
 '@S9S_MB_2U_LIB.S9S_MB_2U(SCH_1):PAGE111_I178@PURE_QUANTA.SCONN288_ADR50017P087CC(CHIPS)':
 'G1': CDS_PINID='G1';
NODE_NAME     J30 G2
 '@S9S_MB_2U_LIB.S9S_MB_2U(SCH_1):PAGE111_I178@PURE_QUANTA.SCONN288_ADR50017P087CC(CHIPS)':
 'G2': CDS_PINID='G2';
NODE_NAME     J30 G3
 '@S9S_MB_2U_LIB.S9S_MB_2U(SCH_1):PAGE111_I178@PURE_QUANTA.SCONN288_ADR50017P087CC(CHIPS)':
 'G3': CDS_PINID='G3';
NODE_NAME     J30 6
 '@S9S_MB_2U_LIB.S9S_MB_2U(SCH_1):PAGE111_I178@PURE_QUANTA.SCONN288_ADR50017P087CC(CHIPS)':
 'VSS0': CDS_PINID='VSS0';
NODE_NAME     J30 8
 '@S9S_MB_2U_LIB.S9S_MB_2U(SCH_1):PAGE111_I178@PURE_QUANTA.SCONN288_ADR50017P087CC(CHIPS)':
 'VSS1': CDS_PINID='VSS1';
NODE_NAME     J30 10
 '@S9S_MB_2U_LIB.S9S_MB_2U(SCH_1):PAGE111_I178@PURE_QUANTA.SCONN288_ADR50017P087CC(CHIPS)':
 'VSS2': CDS_PINID='VSS2';
NODE_NAME     J30 13
 '@S9S_MB_2U_LIB.S9S_MB_2U(SCH_1):PAGE111_I178@PURE_QUANTA.SCONN288_ADR50017P087CC(CHIPS)':
 'VSS3': CDS_PINID='VSS3';
NODE_NAME     J30 15
 '@S9S_MB_2U_LIB.S9S_MB_2U(SCH_1):PAGE111_I178@PURE_QUANTA.SCONN288_ADR50017P087CC(CHIPS)':
 'VSS4': CDS_PINID='VSS4';
NODE_NAME     J30 17
 '@S9S_MB_2U_LIB.S9S_MB_2U(SCH_1):PAGE111_I178@PURE_QUANTA.SCONN288_ADR50017P087CC(CHIPS)':
 'VSS5': CDS_PINID='VSS5';
NODE_NAME     J30 19
 '@S9S_MB_2U_LIB.S9S_MB_2U(SCH_1):PAGE111_I178@PURE_QUANTA.SCONN288_ADR50017P087CC(CHIPS)':
 'VSS6': CDS_PINID='VSS6';
NODE_NAME     J30 21
 '@S9S_MB_2U_LIB.S9S_MB_2U(SCH_1):PAGE111_I178@PURE_QUANTA.SCONN288_ADR50017P087CC(CHIPS)':
 'VSS7': CDS_PINID='VSS7';
NODE_NAME     J30 24
 '@S9S_MB_2U_LIB.S9S_MB_2U(SCH_1):PAGE111_I178@PURE_QUANTA.SCONN288_ADR50017P087CC(CHIPS)':
 'VSS8': CDS_PINID='VSS8';
NODE_NAME     J30 26
 '@S9S_MB_2U_LIB.S9S_MB_2U(SCH_1):PAGE111_I178@PURE_QUANTA.SCONN288_ADR50017P087CC(CHIPS)':
 'VSS9': CDS_PINID='VSS9';
NODE_NAME     J30 28
 '@S9S_MB_2U_LIB.S9S_MB_2U(SCH_1):PAGE111_I178@PURE_QUANTA.SCONN288_ADR50017P087CC(CHIPS)':
 'VSS10': CDS_PINID='VSS10';
NODE_NAME     J30 30
 '@S9S_MB_2U_LIB.S9S_MB_2U(SCH_1):PAGE111_I178@PURE_QUANTA.SCONN288_ADR50017P087CC(CHIPS)':
 'VSS11': CDS_PINID='VSS11';
NODE_NAME     J30 32
 '@S9S_MB_2U_LIB.S9S_MB_2U(SCH_1):PAGE111_I178@PURE_QUANTA.SCONN288_ADR50017P087CC(CHIPS)':
 'VSS12': CDS_PINID='VSS12';
NODE_NAME     J30 35
 '@S9S_MB_2U_LIB.S9S_MB_2U(SCH_1):PAGE111_I178@PURE_QUANTA.SCONN288_ADR50017P087CC(CHIPS)':
 'VSS13': CDS_PINID='VSS13';
NODE_NAME     J30 37
 '@S9S_MB_2U_LIB.S9S_MB_2U(SCH_1):PAGE111_I178@PURE_QUANTA.SCONN288_ADR50017P087CC(CHIPS)':
 'VSS14': CDS_PINID='VSS14';
NODE_NAME     J30 39
 '@S9S_MB_2U_LIB.S9S_MB_2U(SCH_1):PAGE111_I178@PURE_QUANTA.SCONN288_ADR50017P087CC(CHIPS)':
 'VSS15': CDS_PINID='VSS15';
NODE_NAME     J30 41
 '@S9S_MB_2U_LIB.S9S_MB_2U(SCH_1):PAGE111_I178@PURE_QUANTA.SCONN288_ADR50017P087CC(CHIPS)':
 'VSS16': CDS_PINID='VSS16';
NODE_NAME     J30 43
 '@S9S_MB_2U_LIB.S9S_MB_2U(SCH_1):PAGE111_I178@PURE_QUANTA.SCONN288_ADR50017P087CC(CHIPS)':
 'VSS17': CDS_PINID='VSS17';
NODE_NAME     J30 46
 '@S9S_MB_2U_LIB.S9S_MB_2U(SCH_1):PAGE111_I178@PURE_QUANTA.SCONN288_ADR50017P087CC(CHIPS)':
 'VSS18': CDS_PINID='VSS18';
NODE_NAME     J30 48
 '@S9S_MB_2U_LIB.S9S_MB_2U(SCH_1):PAGE111_I178@PURE_QUANTA.SCONN288_ADR50017P087CC(CHIPS)':
 'VSS19': CDS_PINID='VSS19';
NODE_NAME     J30 50
 '@S9S_MB_2U_LIB.S9S_MB_2U(SCH_1):PAGE111_I178@PURE_QUANTA.SCONN288_ADR50017P087CC(CHIPS)':
 'VSS20': CDS_PINID='VSS20';
NODE_NAME     J30 52
 '@S9S_MB_2U_LIB.S9S_MB_2U(SCH_1):PAGE111_I178@PURE_QUANTA.SCONN288_ADR50017P087CC(CHIPS)':
 'VSS21': CDS_PINID='VSS21';
NODE_NAME     J30 54
 '@S9S_MB_2U_LIB.S9S_MB_2U(SCH_1):PAGE111_I178@PURE_QUANTA.SCONN288_ADR50017P087CC(CHIPS)':
 'VSS22': CDS_PINID='VSS22';
NODE_NAME     J30 57
 '@S9S_MB_2U_LIB.S9S_MB_2U(SCH_1):PAGE111_I178@PURE_QUANTA.SCONN288_ADR50017P087CC(CHIPS)':
 'VSS23': CDS_PINID='VSS23';
NODE_NAME     J30 59
 '@S9S_MB_2U_LIB.S9S_MB_2U(SCH_1):PAGE111_I178@PURE_QUANTA.SCONN288_ADR50017P087CC(CHIPS)':
 'VSS24': CDS_PINID='VSS24';
NODE_NAME     J30 61
 '@S9S_MB_2U_LIB.S9S_MB_2U(SCH_1):PAGE111_I178@PURE_QUANTA.SCONN288_ADR50017P087CC(CHIPS)':
 'VSS25': CDS_PINID='VSS25';
NODE_NAME     J30 63
 '@S9S_MB_2U_LIB.S9S_MB_2U(SCH_1):PAGE111_I178@PURE_QUANTA.SCONN288_ADR50017P087CC(CHIPS)':
 'VSS26': CDS_PINID='VSS26';
NODE_NAME     J30 65
 '@S9S_MB_2U_LIB.S9S_MB_2U(SCH_1):PAGE111_I178@PURE_QUANTA.SCONN288_ADR50017P087CC(CHIPS)':
 'VSS27': CDS_PINID='VSS27';
NODE_NAME     J30 67
 '@S9S_MB_2U_LIB.S9S_MB_2U(SCH_1):PAGE111_I178@PURE_QUANTA.SCONN288_ADR50017P087CC(CHIPS)':
 'VSS28': CDS_PINID='VSS28';
NODE_NAME     J30 69
 '@S9S_MB_2U_LIB.S9S_MB_2U(SCH_1):PAGE111_I178@PURE_QUANTA.SCONN288_ADR50017P087CC(CHIPS)':
 'VSS29': CDS_PINID='VSS29';
NODE_NAME     J30 71
 '@S9S_MB_2U_LIB.S9S_MB_2U(SCH_1):PAGE111_I178@PURE_QUANTA.SCONN288_ADR50017P087CC(CHIPS)':
 'VSS30': CDS_PINID='VSS30';
NODE_NAME     J30 73
 '@S9S_MB_2U_LIB.S9S_MB_2U(SCH_1):PAGE111_I178@PURE_QUANTA.SCONN288_ADR50017P087CC(CHIPS)':
 'VSS31': CDS_PINID='VSS31';
NODE_NAME     J30 75
 '@S9S_MB_2U_LIB.S9S_MB_2U(SCH_1):PAGE111_I178@PURE_QUANTA.SCONN288_ADR50017P087CC(CHIPS)':
 'VSS32': CDS_PINID='VSS32';
NODE_NAME     J30 77
 '@S9S_MB_2U_LIB.S9S_MB_2U(SCH_1):PAGE111_I178@PURE_QUANTA.SCONN288_ADR50017P087CC(CHIPS)':
 'VSS33': CDS_PINID='VSS33';
NODE_NAME     J30 79
 '@S9S_MB_2U_LIB.S9S_MB_2U(SCH_1):PAGE111_I178@PURE_QUANTA.SCONN288_ADR50017P087CC(CHIPS)':
 'VSS34': CDS_PINID='VSS34';
NODE_NAME     J30 81
 '@S9S_MB_2U_LIB.S9S_MB_2U(SCH_1):PAGE111_I178@PURE_QUANTA.SCONN288_ADR50017P087CC(CHIPS)':
 'VSS35': CDS_PINID='VSS35';
NODE_NAME     J30 83
 '@S9S_MB_2U_LIB.S9S_MB_2U(SCH_1):PAGE111_I178@PURE_QUANTA.SCONN288_ADR50017P087CC(CHIPS)':
 'VSS36': CDS_PINID='VSS36';
NODE_NAME     J30 85
 '@S9S_MB_2U_LIB.S9S_MB_2U(SCH_1):PAGE111_I178@PURE_QUANTA.SCONN288_ADR50017P087CC(CHIPS)':
 'VSS37': CDS_PINID='VSS37';
NODE_NAME     J30 88
 '@S9S_MB_2U_LIB.S9S_MB_2U(SCH_1):PAGE111_I178@PURE_QUANTA.SCONN288_ADR50017P087CC(CHIPS)':
 'VSS38': CDS_PINID='VSS38';
NODE_NAME     J30 90
 '@S9S_MB_2U_LIB.S9S_MB_2U(SCH_1):PAGE111_I178@PURE_QUANTA.SCONN288_ADR50017P087CC(CHIPS)':
 'VSS39': CDS_PINID='VSS39';
NODE_NAME     J30 92
 '@S9S_MB_2U_LIB.S9S_MB_2U(SCH_1):PAGE111_I178@PURE_QUANTA.SCONN288_ADR50017P087CC(CHIPS)':
 'VSS40': CDS_PINID='VSS40';
NODE_NAME     J30 95
 '@S9S_MB_2U_LIB.S9S_MB_2U(SCH_1):PAGE111_I178@PURE_QUANTA.SCONN288_ADR50017P087CC(CHIPS)':
 'VSS41': CDS_PINID='VSS41';
NODE_NAME     J30 97
 '@S9S_MB_2U_LIB.S9S_MB_2U(SCH_1):PAGE111_I178@PURE_QUANTA.SCONN288_ADR50017P087CC(CHIPS)':
 'VSS42': CDS_PINID='VSS42';
NODE_NAME     J30 99
 '@S9S_MB_2U_LIB.S9S_MB_2U(SCH_1):PAGE111_I178@PURE_QUANTA.SCONN288_ADR50017P087CC(CHIPS)':
 'VSS43': CDS_PINID='VSS43';
NODE_NAME     J30 101
 '@S9S_MB_2U_LIB.S9S_MB_2U(SCH_1):PAGE111_I178@PURE_QUANTA.SCONN288_ADR50017P087CC(CHIPS)':
 'VSS44': CDS_PINID='VSS44';
NODE_NAME     J30 103
 '@S9S_MB_2U_LIB.S9S_MB_2U(SCH_1):PAGE111_I178@PURE_QUANTA.SCONN288_ADR50017P087CC(CHIPS)':
 'VSS45': CDS_PINID='VSS45';
NODE_NAME     J30 106
 '@S9S_MB_2U_LIB.S9S_MB_2U(SCH_1):PAGE111_I178@PURE_QUANTA.SCONN288_ADR50017P087CC(CHIPS)':
 'VSS46': CDS_PINID='VSS46';
NODE_NAME     J30 108
 '@S9S_MB_2U_LIB.S9S_MB_2U(SCH_1):PAGE111_I178@PURE_QUANTA.SCONN288_ADR50017P087CC(CHIPS)':
 'VSS47': CDS_PINID='VSS47';
NODE_NAME     J30 110
 '@S9S_MB_2U_LIB.S9S_MB_2U(SCH_1):PAGE111_I178@PURE_QUANTA.SCONN288_ADR50017P087CC(CHIPS)':
 'VSS48': CDS_PINID='VSS48';
NODE_NAME     J30 112
 '@S9S_MB_2U_LIB.S9S_MB_2U(SCH_1):PAGE111_I178@PURE_QUANTA.SCONN288_ADR50017P087CC(CHIPS)':
 'VSS49': CDS_PINID='VSS49';
NODE_NAME     J30 114
 '@S9S_MB_2U_LIB.S9S_MB_2U(SCH_1):PAGE111_I178@PURE_QUANTA.SCONN288_ADR50017P087CC(CHIPS)':
 'VSS50': CDS_PINID='VSS50';
NODE_NAME     J30 117
 '@S9S_MB_2U_LIB.S9S_MB_2U(SCH_1):PAGE111_I178@PURE_QUANTA.SCONN288_ADR50017P087CC(CHIPS)':
 'VSS51': CDS_PINID='VSS51';
NODE_NAME     J30 119
 '@S9S_MB_2U_LIB.S9S_MB_2U(SCH_1):PAGE111_I178@PURE_QUANTA.SCONN288_ADR50017P087CC(CHIPS)':
 'VSS52': CDS_PINID='VSS52';
NODE_NAME     J30 121
 '@S9S_MB_2U_LIB.S9S_MB_2U(SCH_1):PAGE111_I178@PURE_QUANTA.SCONN288_ADR50017P087CC(CHIPS)':
 'VSS53': CDS_PINID='VSS53';
NODE_NAME     J30 123
 '@S9S_MB_2U_LIB.S9S_MB_2U(SCH_1):PAGE111_I178@PURE_QUANTA.SCONN288_ADR50017P087CC(CHIPS)':
 'VSS54': CDS_PINID='VSS54';
NODE_NAME     J30 125
 '@S9S_MB_2U_LIB.S9S_MB_2U(SCH_1):PAGE111_I178@PURE_QUANTA.SCONN288_ADR50017P087CC(CHIPS)':
 'VSS55': CDS_PINID='VSS55';
NODE_NAME     J30 128
 '@S9S_MB_2U_LIB.S9S_MB_2U(SCH_1):PAGE111_I178@PURE_QUANTA.SCONN288_ADR50017P087CC(CHIPS)':
 'VSS56': CDS_PINID='VSS56';
NODE_NAME     J30 130
 '@S9S_MB_2U_LIB.S9S_MB_2U(SCH_1):PAGE111_I178@PURE_QUANTA.SCONN288_ADR50017P087CC(CHIPS)':
 'VSS57': CDS_PINID='VSS57';
NODE_NAME     J30 132
 '@S9S_MB_2U_LIB.S9S_MB_2U(SCH_1):PAGE111_I178@PURE_QUANTA.SCONN288_ADR50017P087CC(CHIPS)':
 'VSS58': CDS_PINID='VSS58';
NODE_NAME     J30 134
 '@S9S_MB_2U_LIB.S9S_MB_2U(SCH_1):PAGE111_I178@PURE_QUANTA.SCONN288_ADR50017P087CC(CHIPS)':
 'VSS59': CDS_PINID='VSS59';
NODE_NAME     J30 136
 '@S9S_MB_2U_LIB.S9S_MB_2U(SCH_1):PAGE111_I178@PURE_QUANTA.SCONN288_ADR50017P087CC(CHIPS)':
 'VSS60': CDS_PINID='VSS60';
NODE_NAME     J30 139
 '@S9S_MB_2U_LIB.S9S_MB_2U(SCH_1):PAGE111_I178@PURE_QUANTA.SCONN288_ADR50017P087CC(CHIPS)':
 'VSS61': CDS_PINID='VSS61';
NODE_NAME     J30 141
 '@S9S_MB_2U_LIB.S9S_MB_2U(SCH_1):PAGE111_I178@PURE_QUANTA.SCONN288_ADR50017P087CC(CHIPS)':
 'VSS62': CDS_PINID='VSS62';
NODE_NAME     J30 143
 '@S9S_MB_2U_LIB.S9S_MB_2U(SCH_1):PAGE111_I178@PURE_QUANTA.SCONN288_ADR50017P087CC(CHIPS)':
 'VSS63': CDS_PINID='VSS63';
NODE_NAME     J30 151
 '@S9S_MB_2U_LIB.S9S_MB_2U(SCH_1):PAGE111_I178@PURE_QUANTA.SCONN288_ADR50017P087CC(CHIPS)':
 'VSS64': CDS_PINID='VSS64';
NODE_NAME     J30 153
 '@S9S_MB_2U_LIB.S9S_MB_2U(SCH_1):PAGE111_I178@PURE_QUANTA.SCONN288_ADR50017P087CC(CHIPS)':
 'VSS65': CDS_PINID='VSS65';
NODE_NAME     J30 155
 '@S9S_MB_2U_LIB.S9S_MB_2U(SCH_1):PAGE111_I178@PURE_QUANTA.SCONN288_ADR50017P087CC(CHIPS)':
 'VSS66': CDS_PINID='VSS66';
NODE_NAME     J30 158
 '@S9S_MB_2U_LIB.S9S_MB_2U(SCH_1):PAGE111_I178@PURE_QUANTA.SCONN288_ADR50017P087CC(CHIPS)':
 'VSS67': CDS_PINID='VSS67';
NODE_NAME     J30 160
 '@S9S_MB_2U_LIB.S9S_MB_2U(SCH_1):PAGE111_I178@PURE_QUANTA.SCONN288_ADR50017P087CC(CHIPS)':
 'VSS68': CDS_PINID='VSS68';
NODE_NAME     J30 162
 '@S9S_MB_2U_LIB.S9S_MB_2U(SCH_1):PAGE111_I178@PURE_QUANTA.SCONN288_ADR50017P087CC(CHIPS)':
 'VSS69': CDS_PINID='VSS69';
NODE_NAME     J30 164
 '@S9S_MB_2U_LIB.S9S_MB_2U(SCH_1):PAGE111_I178@PURE_QUANTA.SCONN288_ADR50017P087CC(CHIPS)':
 'VSS70': CDS_PINID='VSS70';
NODE_NAME     J30 166
 '@S9S_MB_2U_LIB.S9S_MB_2U(SCH_1):PAGE111_I178@PURE_QUANTA.SCONN288_ADR50017P087CC(CHIPS)':
 'VSS71': CDS_PINID='VSS71';
NODE_NAME     J30 169
 '@S9S_MB_2U_LIB.S9S_MB_2U(SCH_1):PAGE111_I178@PURE_QUANTA.SCONN288_ADR50017P087CC(CHIPS)':
 'VSS72': CDS_PINID='VSS72';
NODE_NAME     J30 171
 '@S9S_MB_2U_LIB.S9S_MB_2U(SCH_1):PAGE111_I178@PURE_QUANTA.SCONN288_ADR50017P087CC(CHIPS)':
 'VSS73': CDS_PINID='VSS73';
NODE_NAME     J30 173
 '@S9S_MB_2U_LIB.S9S_MB_2U(SCH_1):PAGE111_I178@PURE_QUANTA.SCONN288_ADR50017P087CC(CHIPS)':
 'VSS74': CDS_PINID='VSS74';
NODE_NAME     J30 175
 '@S9S_MB_2U_LIB.S9S_MB_2U(SCH_1):PAGE111_I178@PURE_QUANTA.SCONN288_ADR50017P087CC(CHIPS)':
 'VSS75': CDS_PINID='VSS75';
NODE_NAME     J30 177
 '@S9S_MB_2U_LIB.S9S_MB_2U(SCH_1):PAGE111_I178@PURE_QUANTA.SCONN288_ADR50017P087CC(CHIPS)':
 'VSS76': CDS_PINID='VSS76';
NODE_NAME     J30 180
 '@S9S_MB_2U_LIB.S9S_MB_2U(SCH_1):PAGE111_I178@PURE_QUANTA.SCONN288_ADR50017P087CC(CHIPS)':
 'VSS77': CDS_PINID='VSS77';
NODE_NAME     J30 182
 '@S9S_MB_2U_LIB.S9S_MB_2U(SCH_1):PAGE111_I178@PURE_QUANTA.SCONN288_ADR50017P087CC(CHIPS)':
 'VSS78': CDS_PINID='VSS78';
NODE_NAME     J30 184
 '@S9S_MB_2U_LIB.S9S_MB_2U(SCH_1):PAGE111_I178@PURE_QUANTA.SCONN288_ADR50017P087CC(CHIPS)':
 'VSS79': CDS_PINID='VSS79';
NODE_NAME     J30 186
 '@S9S_MB_2U_LIB.S9S_MB_2U(SCH_1):PAGE111_I178@PURE_QUANTA.SCONN288_ADR50017P087CC(CHIPS)':
 'VSS80': CDS_PINID='VSS80';
NODE_NAME     J30 188
 '@S9S_MB_2U_LIB.S9S_MB_2U(SCH_1):PAGE111_I178@PURE_QUANTA.SCONN288_ADR50017P087CC(CHIPS)':
 'VSS81': CDS_PINID='VSS81';
NODE_NAME     J30 191
 '@S9S_MB_2U_LIB.S9S_MB_2U(SCH_1):PAGE111_I178@PURE_QUANTA.SCONN288_ADR50017P087CC(CHIPS)':
 'VSS82': CDS_PINID='VSS82';
NODE_NAME     J30 193
 '@S9S_MB_2U_LIB.S9S_MB_2U(SCH_1):PAGE111_I178@PURE_QUANTA.SCONN288_ADR50017P087CC(CHIPS)':
 'VSS83': CDS_PINID='VSS83';
NODE_NAME     J30 195
 '@S9S_MB_2U_LIB.S9S_MB_2U(SCH_1):PAGE111_I178@PURE_QUANTA.SCONN288_ADR50017P087CC(CHIPS)':
 'VSS84': CDS_PINID='VSS84';
NODE_NAME     J30 197
 '@S9S_MB_2U_LIB.S9S_MB_2U(SCH_1):PAGE111_I178@PURE_QUANTA.SCONN288_ADR50017P087CC(CHIPS)':
 'VSS85': CDS_PINID='VSS85';
NODE_NAME     J30 199
 '@S9S_MB_2U_LIB.S9S_MB_2U(SCH_1):PAGE111_I178@PURE_QUANTA.SCONN288_ADR50017P087CC(CHIPS)':
 'VSS86': CDS_PINID='VSS86';
NODE_NAME     J30 202
 '@S9S_MB_2U_LIB.S9S_MB_2U(SCH_1):PAGE111_I178@PURE_QUANTA.SCONN288_ADR50017P087CC(CHIPS)':
 'VSS87': CDS_PINID='VSS87';
NODE_NAME     J30 204
 '@S9S_MB_2U_LIB.S9S_MB_2U(SCH_1):PAGE111_I178@PURE_QUANTA.SCONN288_ADR50017P087CC(CHIPS)':
 'VSS88': CDS_PINID='VSS88';
NODE_NAME     J30 206
 '@S9S_MB_2U_LIB.S9S_MB_2U(SCH_1):PAGE111_I178@PURE_QUANTA.SCONN288_ADR50017P087CC(CHIPS)':
 'VSS89': CDS_PINID='VSS89';
NODE_NAME     J30 208
 '@S9S_MB_2U_LIB.S9S_MB_2U(SCH_1):PAGE111_I178@PURE_QUANTA.SCONN288_ADR50017P087CC(CHIPS)':
 'VSS90': CDS_PINID='VSS90';
NODE_NAME     J30 210
 '@S9S_MB_2U_LIB.S9S_MB_2U(SCH_1):PAGE111_I178@PURE_QUANTA.SCONN288_ADR50017P087CC(CHIPS)':
 'VSS91': CDS_PINID='VSS91';
NODE_NAME     J30 212
 '@S9S_MB_2U_LIB.S9S_MB_2U(SCH_1):PAGE111_I178@PURE_QUANTA.SCONN288_ADR50017P087CC(CHIPS)':
 'VSS92': CDS_PINID='VSS92';
NODE_NAME     J30 214
 '@S9S_MB_2U_LIB.S9S_MB_2U(SCH_1):PAGE111_I178@PURE_QUANTA.SCONN288_ADR50017P087CC(CHIPS)':
 'VSS93': CDS_PINID='VSS93';
NODE_NAME     J30 216
 '@S9S_MB_2U_LIB.S9S_MB_2U(SCH_1):PAGE111_I178@PURE_QUANTA.SCONN288_ADR50017P087CC(CHIPS)':
 'VSS94': CDS_PINID='VSS94';
NODE_NAME     J30 219
 '@S9S_MB_2U_LIB.S9S_MB_2U(SCH_1):PAGE111_I178@PURE_QUANTA.SCONN288_ADR50017P087CC(CHIPS)':
 'VSS95': CDS_PINID='VSS95';
NODE_NAME     J30 222
 '@S9S_MB_2U_LIB.S9S_MB_2U(SCH_1):PAGE111_I178@PURE_QUANTA.SCONN288_ADR50017P087CC(CHIPS)':
 'VSS96': CDS_PINID='VSS96';
NODE_NAME     J30 224
 '@S9S_MB_2U_LIB.S9S_MB_2U(SCH_1):PAGE111_I178@PURE_QUANTA.SCONN288_ADR50017P087CC(CHIPS)':
 'VSS97': CDS_PINID='VSS97';
NODE_NAME     J30 226
 '@S9S_MB_2U_LIB.S9S_MB_2U(SCH_1):PAGE111_I178@PURE_QUANTA.SCONN288_ADR50017P087CC(CHIPS)':
 'VSS98': CDS_PINID='VSS98';
NODE_NAME     J30 228
 '@S9S_MB_2U_LIB.S9S_MB_2U(SCH_1):PAGE111_I178@PURE_QUANTA.SCONN288_ADR50017P087CC(CHIPS)':
 'VSS99': CDS_PINID='VSS99';
NODE_NAME     J30 230
 '@S9S_MB_2U_LIB.S9S_MB_2U(SCH_1):PAGE111_I178@PURE_QUANTA.SCONN288_ADR50017P087CC(CHIPS)':
 'VSS100': CDS_PINID='VSS100';
NODE_NAME     J30 233
 '@S9S_MB_2U_LIB.S9S_MB_2U(SCH_1):PAGE111_I178@PURE_QUANTA.SCONN288_ADR50017P087CC(CHIPS)':
 'VSS101': CDS_PINID='VSS101';
NODE_NAME     J30 235
 '@S9S_MB_2U_LIB.S9S_MB_2U(SCH_1):PAGE111_I178@PURE_QUANTA.SCONN288_ADR50017P087CC(CHIPS)':
 'VSS102': CDS_PINID='VSS102';
NODE_NAME     J30 237
 '@S9S_MB_2U_LIB.S9S_MB_2U(SCH_1):PAGE111_I178@PURE_QUANTA.SCONN288_ADR50017P087CC(CHIPS)':
 'VSS103': CDS_PINID='VSS103';
NODE_NAME     J30 240
 '@S9S_MB_2U_LIB.S9S_MB_2U(SCH_1):PAGE111_I178@PURE_QUANTA.SCONN288_ADR50017P087CC(CHIPS)':
 'VSS104': CDS_PINID='VSS104';
NODE_NAME     J30 242
 '@S9S_MB_2U_LIB.S9S_MB_2U(SCH_1):PAGE111_I178@PURE_QUANTA.SCONN288_ADR50017P087CC(CHIPS)':
 'VSS105': CDS_PINID='VSS105';
NODE_NAME     J30 244
 '@S9S_MB_2U_LIB.S9S_MB_2U(SCH_1):PAGE111_I178@PURE_QUANTA.SCONN288_ADR50017P087CC(CHIPS)':
 'VSS106': CDS_PINID='VSS106';
NODE_NAME     J30 246
 '@S9S_MB_2U_LIB.S9S_MB_2U(SCH_1):PAGE111_I178@PURE_QUANTA.SCONN288_ADR50017P087CC(CHIPS)':
 'VSS107': CDS_PINID='VSS107';
NODE_NAME     J30 248
 '@S9S_MB_2U_LIB.S9S_MB_2U(SCH_1):PAGE111_I178@PURE_QUANTA.SCONN288_ADR50017P087CC(CHIPS)':
 'VSS108': CDS_PINID='VSS108';
NODE_NAME     J30 251
 '@S9S_MB_2U_LIB.S9S_MB_2U(SCH_1):PAGE111_I178@PURE_QUANTA.SCONN288_ADR50017P087CC(CHIPS)':
 'VSS109': CDS_PINID='VSS109';
NODE_NAME     J30 253
 '@S9S_MB_2U_LIB.S9S_MB_2U(SCH_1):PAGE111_I178@PURE_QUANTA.SCONN288_ADR50017P087CC(CHIPS)':
 'VSS110': CDS_PINID='VSS110';
NODE_NAME     J30 255
 '@S9S_MB_2U_LIB.S9S_MB_2U(SCH_1):PAGE111_I178@PURE_QUANTA.SCONN288_ADR50017P087CC(CHIPS)':
 'VSS111': CDS_PINID='VSS111';
NODE_NAME     J30 257
 '@S9S_MB_2U_LIB.S9S_MB_2U(SCH_1):PAGE111_I178@PURE_QUANTA.SCONN288_ADR50017P087CC(CHIPS)':
 'VSS112': CDS_PINID='VSS112';
NODE_NAME     J30 259
 '@S9S_MB_2U_LIB.S9S_MB_2U(SCH_1):PAGE111_I178@PURE_QUANTA.SCONN288_ADR50017P087CC(CHIPS)':
 'VSS113': CDS_PINID='VSS113';
NODE_NAME     J30 262
 '@S9S_MB_2U_LIB.S9S_MB_2U(SCH_1):PAGE111_I178@PURE_QUANTA.SCONN288_ADR50017P087CC(CHIPS)':
 'VSS114': CDS_PINID='VSS114';
NODE_NAME     J30 264
 '@S9S_MB_2U_LIB.S9S_MB_2U(SCH_1):PAGE111_I178@PURE_QUANTA.SCONN288_ADR50017P087CC(CHIPS)':
 'VSS115': CDS_PINID='VSS115';
NODE_NAME     J30 266
 '@S9S_MB_2U_LIB.S9S_MB_2U(SCH_1):PAGE111_I178@PURE_QUANTA.SCONN288_ADR50017P087CC(CHIPS)':
 'VSS116': CDS_PINID='VSS116';
NODE_NAME     J30 268
 '@S9S_MB_2U_LIB.S9S_MB_2U(SCH_1):PAGE111_I178@PURE_QUANTA.SCONN288_ADR50017P087CC(CHIPS)':
 'VSS117': CDS_PINID='VSS117';
NODE_NAME     J30 270
 '@S9S_MB_2U_LIB.S9S_MB_2U(SCH_1):PAGE111_I178@PURE_QUANTA.SCONN288_ADR50017P087CC(CHIPS)':
 'VSS118': CDS_PINID='VSS118';
NODE_NAME     J30 273
 '@S9S_MB_2U_LIB.S9S_MB_2U(SCH_1):PAGE111_I178@PURE_QUANTA.SCONN288_ADR50017P087CC(CHIPS)':
 'VSS119': CDS_PINID='VSS119';
NODE_NAME     J30 275
 '@S9S_MB_2U_LIB.S9S_MB_2U(SCH_1):PAGE111_I178@PURE_QUANTA.SCONN288_ADR50017P087CC(CHIPS)':
 'VSS120': CDS_PINID='VSS120';
NODE_NAME     J30 277
 '@S9S_MB_2U_LIB.S9S_MB_2U(SCH_1):PAGE111_I178@PURE_QUANTA.SCONN288_ADR50017P087CC(CHIPS)':
 'VSS121': CDS_PINID='VSS121';
NODE_NAME     J30 279
 '@S9S_MB_2U_LIB.S9S_MB_2U(SCH_1):PAGE111_I178@PURE_QUANTA.SCONN288_ADR50017P087CC(CHIPS)':
 'VSS122': CDS_PINID='VSS122';
NODE_NAME     J30 281
 '@S9S_MB_2U_LIB.S9S_MB_2U(SCH_1):PAGE111_I178@PURE_QUANTA.SCONN288_ADR50017P087CC(CHIPS)':
 'VSS123': CDS_PINID='VSS123';
NODE_NAME     J30 284
 '@S9S_MB_2U_LIB.S9S_MB_2U(SCH_1):PAGE111_I178@PURE_QUANTA.SCONN288_ADR50017P087CC(CHIPS)':
 'VSS124': CDS_PINID='VSS124';
NODE_NAME     J30 286
 '@S9S_MB_2U_LIB.S9S_MB_2U(SCH_1):PAGE111_I178@PURE_QUANTA.SCONN288_ADR50017P087CC(CHIPS)':
 'VSS125': CDS_PINID='VSS125';
NODE_NAME     J30 288
 '@S9S_MB_2U_LIB.S9S_MB_2U(SCH_1):PAGE111_I178@PURE_QUANTA.SCONN288_ADR50017P087CC(CHIPS)':
 'VSS126': CDS_PINID='VSS126';
NODE_NAME     R73 2
 '@S9S_MB_2U_LIB.S9S_MB_2U(SCH_1):PAGE112_I3@PURE_QUANTA.Q_RES(CHIPS)':
 'B': CDS_PINID='B';
NODE_NAME     C75 2
 '@S9S_MB_2U_LIB.S9S_MB_2U(SCH_1):PAGE112_I124@PURE_QUANTA.Q_CAP(CHIPS)':
 'B': CDS_PINID='B';
NODE_NAME     C76 2
 '@S9S_MB_2U_LIB.S9S_MB_2U(SCH_1):PAGE112_I125@PURE_QUANTA.Q_CAP(CHIPS)':
 'B': CDS_PINID='B';
NODE_NAME     C77 2
 '@S9S_MB_2U_LIB.S9S_MB_2U(SCH_1):PAGE112_I126@PURE_QUANTA.Q_CAP(CHIPS)':
 'B': CDS_PINID='B';
NODE_NAME     J31 G1
 '@S9S_MB_2U_LIB.S9S_MB_2U(SCH_1):PAGE112_I178@PURE_QUANTA.SCONN288_ADR50017P130CC(CHIPS)':
 'G1': CDS_PINID='G1';
NODE_NAME     J31 G2
 '@S9S_MB_2U_LIB.S9S_MB_2U(SCH_1):PAGE112_I178@PURE_QUANTA.SCONN288_ADR50017P130CC(CHIPS)':
 'G2': CDS_PINID='G2';
NODE_NAME     J31 G3
 '@S9S_MB_2U_LIB.S9S_MB_2U(SCH_1):PAGE112_I178@PURE_QUANTA.SCONN288_ADR50017P130CC(CHIPS)':
 'G3': CDS_PINID='G3';
NODE_NAME     J31 6
 '@S9S_MB_2U_LIB.S9S_MB_2U(SCH_1):PAGE112_I178@PURE_QUANTA.SCONN288_ADR50017P130CC(CHIPS)':
 'VSS0': CDS_PINID='VSS0';
NODE_NAME     J31 8
 '@S9S_MB_2U_LIB.S9S_MB_2U(SCH_1):PAGE112_I178@PURE_QUANTA.SCONN288_ADR50017P130CC(CHIPS)':
 'VSS1': CDS_PINID='VSS1';
NODE_NAME     J31 10
 '@S9S_MB_2U_LIB.S9S_MB_2U(SCH_1):PAGE112_I178@PURE_QUANTA.SCONN288_ADR50017P130CC(CHIPS)':
 'VSS2': CDS_PINID='VSS2';
NODE_NAME     J31 13
 '@S9S_MB_2U_LIB.S9S_MB_2U(SCH_1):PAGE112_I178@PURE_QUANTA.SCONN288_ADR50017P130CC(CHIPS)':
 'VSS3': CDS_PINID='VSS3';
NODE_NAME     J31 15
 '@S9S_MB_2U_LIB.S9S_MB_2U(SCH_1):PAGE112_I178@PURE_QUANTA.SCONN288_ADR50017P130CC(CHIPS)':
 'VSS4': CDS_PINID='VSS4';
NODE_NAME     J31 17
 '@S9S_MB_2U_LIB.S9S_MB_2U(SCH_1):PAGE112_I178@PURE_QUANTA.SCONN288_ADR50017P130CC(CHIPS)':
 'VSS5': CDS_PINID='VSS5';
NODE_NAME     J31 19
 '@S9S_MB_2U_LIB.S9S_MB_2U(SCH_1):PAGE112_I178@PURE_QUANTA.SCONN288_ADR50017P130CC(CHIPS)':
 'VSS6': CDS_PINID='VSS6';
NODE_NAME     J31 21
 '@S9S_MB_2U_LIB.S9S_MB_2U(SCH_1):PAGE112_I178@PURE_QUANTA.SCONN288_ADR50017P130CC(CHIPS)':
 'VSS7': CDS_PINID='VSS7';
NODE_NAME     J31 24
 '@S9S_MB_2U_LIB.S9S_MB_2U(SCH_1):PAGE112_I178@PURE_QUANTA.SCONN288_ADR50017P130CC(CHIPS)':
 'VSS8': CDS_PINID='VSS8';
NODE_NAME     J31 26
 '@S9S_MB_2U_LIB.S9S_MB_2U(SCH_1):PAGE112_I178@PURE_QUANTA.SCONN288_ADR50017P130CC(CHIPS)':
 'VSS9': CDS_PINID='VSS9';
NODE_NAME     J31 28
 '@S9S_MB_2U_LIB.S9S_MB_2U(SCH_1):PAGE112_I178@PURE_QUANTA.SCONN288_ADR50017P130CC(CHIPS)':
 'VSS10': CDS_PINID='VSS10';
NODE_NAME     J31 30
 '@S9S_MB_2U_LIB.S9S_MB_2U(SCH_1):PAGE112_I178@PURE_QUANTA.SCONN288_ADR50017P130CC(CHIPS)':
 'VSS11': CDS_PINID='VSS11';
NODE_NAME     J31 32
 '@S9S_MB_2U_LIB.S9S_MB_2U(SCH_1):PAGE112_I178@PURE_QUANTA.SCONN288_ADR50017P130CC(CHIPS)':
 'VSS12': CDS_PINID='VSS12';
NODE_NAME     J31 35
 '@S9S_MB_2U_LIB.S9S_MB_2U(SCH_1):PAGE112_I178@PURE_QUANTA.SCONN288_ADR50017P130CC(CHIPS)':
 'VSS13': CDS_PINID='VSS13';
NODE_NAME     J31 37
 '@S9S_MB_2U_LIB.S9S_MB_2U(SCH_1):PAGE112_I178@PURE_QUANTA.SCONN288_ADR50017P130CC(CHIPS)':
 'VSS14': CDS_PINID='VSS14';
NODE_NAME     J31 39
 '@S9S_MB_2U_LIB.S9S_MB_2U(SCH_1):PAGE112_I178@PURE_QUANTA.SCONN288_ADR50017P130CC(CHIPS)':
 'VSS15': CDS_PINID='VSS15';
NODE_NAME     J31 41
 '@S9S_MB_2U_LIB.S9S_MB_2U(SCH_1):PAGE112_I178@PURE_QUANTA.SCONN288_ADR50017P130CC(CHIPS)':
 'VSS16': CDS_PINID='VSS16';
NODE_NAME     J31 43
 '@S9S_MB_2U_LIB.S9S_MB_2U(SCH_1):PAGE112_I178@PURE_QUANTA.SCONN288_ADR50017P130CC(CHIPS)':
 'VSS17': CDS_PINID='VSS17';
NODE_NAME     J31 46
 '@S9S_MB_2U_LIB.S9S_MB_2U(SCH_1):PAGE112_I178@PURE_QUANTA.SCONN288_ADR50017P130CC(CHIPS)':
 'VSS18': CDS_PINID='VSS18';
NODE_NAME     J31 48
 '@S9S_MB_2U_LIB.S9S_MB_2U(SCH_1):PAGE112_I178@PURE_QUANTA.SCONN288_ADR50017P130CC(CHIPS)':
 'VSS19': CDS_PINID='VSS19';
NODE_NAME     J31 50
 '@S9S_MB_2U_LIB.S9S_MB_2U(SCH_1):PAGE112_I178@PURE_QUANTA.SCONN288_ADR50017P130CC(CHIPS)':
 'VSS20': CDS_PINID='VSS20';
NODE_NAME     J31 52
 '@S9S_MB_2U_LIB.S9S_MB_2U(SCH_1):PAGE112_I178@PURE_QUANTA.SCONN288_ADR50017P130CC(CHIPS)':
 'VSS21': CDS_PINID='VSS21';
NODE_NAME     J31 54
 '@S9S_MB_2U_LIB.S9S_MB_2U(SCH_1):PAGE112_I178@PURE_QUANTA.SCONN288_ADR50017P130CC(CHIPS)':
 'VSS22': CDS_PINID='VSS22';
NODE_NAME     J31 57
 '@S9S_MB_2U_LIB.S9S_MB_2U(SCH_1):PAGE112_I178@PURE_QUANTA.SCONN288_ADR50017P130CC(CHIPS)':
 'VSS23': CDS_PINID='VSS23';
NODE_NAME     J31 59
 '@S9S_MB_2U_LIB.S9S_MB_2U(SCH_1):PAGE112_I178@PURE_QUANTA.SCONN288_ADR50017P130CC(CHIPS)':
 'VSS24': CDS_PINID='VSS24';
NODE_NAME     J31 61
 '@S9S_MB_2U_LIB.S9S_MB_2U(SCH_1):PAGE112_I178@PURE_QUANTA.SCONN288_ADR50017P130CC(CHIPS)':
 'VSS25': CDS_PINID='VSS25';
NODE_NAME     J31 63
 '@S9S_MB_2U_LIB.S9S_MB_2U(SCH_1):PAGE112_I178@PURE_QUANTA.SCONN288_ADR50017P130CC(CHIPS)':
 'VSS26': CDS_PINID='VSS26';
NODE_NAME     J31 65
 '@S9S_MB_2U_LIB.S9S_MB_2U(SCH_1):PAGE112_I178@PURE_QUANTA.SCONN288_ADR50017P130CC(CHIPS)':
 'VSS27': CDS_PINID='VSS27';
NODE_NAME     J31 67
 '@S9S_MB_2U_LIB.S9S_MB_2U(SCH_1):PAGE112_I178@PURE_QUANTA.SCONN288_ADR50017P130CC(CHIPS)':
 'VSS28': CDS_PINID='VSS28';
NODE_NAME     J31 69
 '@S9S_MB_2U_LIB.S9S_MB_2U(SCH_1):PAGE112_I178@PURE_QUANTA.SCONN288_ADR50017P130CC(CHIPS)':
 'VSS29': CDS_PINID='VSS29';
NODE_NAME     J31 71
 '@S9S_MB_2U_LIB.S9S_MB_2U(SCH_1):PAGE112_I178@PURE_QUANTA.SCONN288_ADR50017P130CC(CHIPS)':
 'VSS30': CDS_PINID='VSS30';
NODE_NAME     J31 73
 '@S9S_MB_2U_LIB.S9S_MB_2U(SCH_1):PAGE112_I178@PURE_QUANTA.SCONN288_ADR50017P130CC(CHIPS)':
 'VSS31': CDS_PINID='VSS31';
NODE_NAME     J31 75
 '@S9S_MB_2U_LIB.S9S_MB_2U(SCH_1):PAGE112_I178@PURE_QUANTA.SCONN288_ADR50017P130CC(CHIPS)':
 'VSS32': CDS_PINID='VSS32';
NODE_NAME     J31 77
 '@S9S_MB_2U_LIB.S9S_MB_2U(SCH_1):PAGE112_I178@PURE_QUANTA.SCONN288_ADR50017P130CC(CHIPS)':
 'VSS33': CDS_PINID='VSS33';
NODE_NAME     J31 79
 '@S9S_MB_2U_LIB.S9S_MB_2U(SCH_1):PAGE112_I178@PURE_QUANTA.SCONN288_ADR50017P130CC(CHIPS)':
 'VSS34': CDS_PINID='VSS34';
NODE_NAME     J31 81
 '@S9S_MB_2U_LIB.S9S_MB_2U(SCH_1):PAGE112_I178@PURE_QUANTA.SCONN288_ADR50017P130CC(CHIPS)':
 'VSS35': CDS_PINID='VSS35';
NODE_NAME     J31 83
 '@S9S_MB_2U_LIB.S9S_MB_2U(SCH_1):PAGE112_I178@PURE_QUANTA.SCONN288_ADR50017P130CC(CHIPS)':
 'VSS36': CDS_PINID='VSS36';
NODE_NAME     J31 85
 '@S9S_MB_2U_LIB.S9S_MB_2U(SCH_1):PAGE112_I178@PURE_QUANTA.SCONN288_ADR50017P130CC(CHIPS)':
 'VSS37': CDS_PINID='VSS37';
NODE_NAME     J31 88
 '@S9S_MB_2U_LIB.S9S_MB_2U(SCH_1):PAGE112_I178@PURE_QUANTA.SCONN288_ADR50017P130CC(CHIPS)':
 'VSS38': CDS_PINID='VSS38';
NODE_NAME     J31 90
 '@S9S_MB_2U_LIB.S9S_MB_2U(SCH_1):PAGE112_I178@PURE_QUANTA.SCONN288_ADR50017P130CC(CHIPS)':
 'VSS39': CDS_PINID='VSS39';
NODE_NAME     J31 92
 '@S9S_MB_2U_LIB.S9S_MB_2U(SCH_1):PAGE112_I178@PURE_QUANTA.SCONN288_ADR50017P130CC(CHIPS)':
 'VSS40': CDS_PINID='VSS40';
NODE_NAME     J31 95
 '@S9S_MB_2U_LIB.S9S_MB_2U(SCH_1):PAGE112_I178@PURE_QUANTA.SCONN288_ADR50017P130CC(CHIPS)':
 'VSS41': CDS_PINID='VSS41';
NODE_NAME     J31 97
 '@S9S_MB_2U_LIB.S9S_MB_2U(SCH_1):PAGE112_I178@PURE_QUANTA.SCONN288_ADR50017P130CC(CHIPS)':
 'VSS42': CDS_PINID='VSS42';
NODE_NAME     J31 99
 '@S9S_MB_2U_LIB.S9S_MB_2U(SCH_1):PAGE112_I178@PURE_QUANTA.SCONN288_ADR50017P130CC(CHIPS)':
 'VSS43': CDS_PINID='VSS43';
NODE_NAME     J31 101
 '@S9S_MB_2U_LIB.S9S_MB_2U(SCH_1):PAGE112_I178@PURE_QUANTA.SCONN288_ADR50017P130CC(CHIPS)':
 'VSS44': CDS_PINID='VSS44';
NODE_NAME     J31 103
 '@S9S_MB_2U_LIB.S9S_MB_2U(SCH_1):PAGE112_I178@PURE_QUANTA.SCONN288_ADR50017P130CC(CHIPS)':
 'VSS45': CDS_PINID='VSS45';
NODE_NAME     J31 106
 '@S9S_MB_2U_LIB.S9S_MB_2U(SCH_1):PAGE112_I178@PURE_QUANTA.SCONN288_ADR50017P130CC(CHIPS)':
 'VSS46': CDS_PINID='VSS46';
NODE_NAME     J31 108
 '@S9S_MB_2U_LIB.S9S_MB_2U(SCH_1):PAGE112_I178@PURE_QUANTA.SCONN288_ADR50017P130CC(CHIPS)':
 'VSS47': CDS_PINID='VSS47';
NODE_NAME     J31 110
 '@S9S_MB_2U_LIB.S9S_MB_2U(SCH_1):PAGE112_I178@PURE_QUANTA.SCONN288_ADR50017P130CC(CHIPS)':
 'VSS48': CDS_PINID='VSS48';
NODE_NAME     J31 112
 '@S9S_MB_2U_LIB.S9S_MB_2U(SCH_1):PAGE112_I178@PURE_QUANTA.SCONN288_ADR50017P130CC(CHIPS)':
 'VSS49': CDS_PINID='VSS49';
NODE_NAME     J31 114
 '@S9S_MB_2U_LIB.S9S_MB_2U(SCH_1):PAGE112_I178@PURE_QUANTA.SCONN288_ADR50017P130CC(CHIPS)':
 'VSS50': CDS_PINID='VSS50';
NODE_NAME     J31 117
 '@S9S_MB_2U_LIB.S9S_MB_2U(SCH_1):PAGE112_I178@PURE_QUANTA.SCONN288_ADR50017P130CC(CHIPS)':
 'VSS51': CDS_PINID='VSS51';
NODE_NAME     J31 119
 '@S9S_MB_2U_LIB.S9S_MB_2U(SCH_1):PAGE112_I178@PURE_QUANTA.SCONN288_ADR50017P130CC(CHIPS)':
 'VSS52': CDS_PINID='VSS52';
NODE_NAME     J31 121
 '@S9S_MB_2U_LIB.S9S_MB_2U(SCH_1):PAGE112_I178@PURE_QUANTA.SCONN288_ADR50017P130CC(CHIPS)':
 'VSS53': CDS_PINID='VSS53';
NODE_NAME     J31 123
 '@S9S_MB_2U_LIB.S9S_MB_2U(SCH_1):PAGE112_I178@PURE_QUANTA.SCONN288_ADR50017P130CC(CHIPS)':
 'VSS54': CDS_PINID='VSS54';
NODE_NAME     J31 125
 '@S9S_MB_2U_LIB.S9S_MB_2U(SCH_1):PAGE112_I178@PURE_QUANTA.SCONN288_ADR50017P130CC(CHIPS)':
 'VSS55': CDS_PINID='VSS55';
NODE_NAME     J31 128
 '@S9S_MB_2U_LIB.S9S_MB_2U(SCH_1):PAGE112_I178@PURE_QUANTA.SCONN288_ADR50017P130CC(CHIPS)':
 'VSS56': CDS_PINID='VSS56';
NODE_NAME     J31 130
 '@S9S_MB_2U_LIB.S9S_MB_2U(SCH_1):PAGE112_I178@PURE_QUANTA.SCONN288_ADR50017P130CC(CHIPS)':
 'VSS57': CDS_PINID='VSS57';
NODE_NAME     J31 132
 '@S9S_MB_2U_LIB.S9S_MB_2U(SCH_1):PAGE112_I178@PURE_QUANTA.SCONN288_ADR50017P130CC(CHIPS)':
 'VSS58': CDS_PINID='VSS58';
NODE_NAME     J31 134
 '@S9S_MB_2U_LIB.S9S_MB_2U(SCH_1):PAGE112_I178@PURE_QUANTA.SCONN288_ADR50017P130CC(CHIPS)':
 'VSS59': CDS_PINID='VSS59';
NODE_NAME     J31 136
 '@S9S_MB_2U_LIB.S9S_MB_2U(SCH_1):PAGE112_I178@PURE_QUANTA.SCONN288_ADR50017P130CC(CHIPS)':
 'VSS60': CDS_PINID='VSS60';
NODE_NAME     J31 139
 '@S9S_MB_2U_LIB.S9S_MB_2U(SCH_1):PAGE112_I178@PURE_QUANTA.SCONN288_ADR50017P130CC(CHIPS)':
 'VSS61': CDS_PINID='VSS61';
NODE_NAME     J31 141
 '@S9S_MB_2U_LIB.S9S_MB_2U(SCH_1):PAGE112_I178@PURE_QUANTA.SCONN288_ADR50017P130CC(CHIPS)':
 'VSS62': CDS_PINID='VSS62';
NODE_NAME     J31 143
 '@S9S_MB_2U_LIB.S9S_MB_2U(SCH_1):PAGE112_I178@PURE_QUANTA.SCONN288_ADR50017P130CC(CHIPS)':
 'VSS63': CDS_PINID='VSS63';
NODE_NAME     J31 151
 '@S9S_MB_2U_LIB.S9S_MB_2U(SCH_1):PAGE112_I178@PURE_QUANTA.SCONN288_ADR50017P130CC(CHIPS)':
 'VSS64': CDS_PINID='VSS64';
NODE_NAME     J31 153
 '@S9S_MB_2U_LIB.S9S_MB_2U(SCH_1):PAGE112_I178@PURE_QUANTA.SCONN288_ADR50017P130CC(CHIPS)':
 'VSS65': CDS_PINID='VSS65';
NODE_NAME     J31 155
 '@S9S_MB_2U_LIB.S9S_MB_2U(SCH_1):PAGE112_I178@PURE_QUANTA.SCONN288_ADR50017P130CC(CHIPS)':
 'VSS66': CDS_PINID='VSS66';
NODE_NAME     J31 158
 '@S9S_MB_2U_LIB.S9S_MB_2U(SCH_1):PAGE112_I178@PURE_QUANTA.SCONN288_ADR50017P130CC(CHIPS)':
 'VSS67': CDS_PINID='VSS67';
NODE_NAME     J31 160
 '@S9S_MB_2U_LIB.S9S_MB_2U(SCH_1):PAGE112_I178@PURE_QUANTA.SCONN288_ADR50017P130CC(CHIPS)':
 'VSS68': CDS_PINID='VSS68';
NODE_NAME     J31 162
 '@S9S_MB_2U_LIB.S9S_MB_2U(SCH_1):PAGE112_I178@PURE_QUANTA.SCONN288_ADR50017P130CC(CHIPS)':
 'VSS69': CDS_PINID='VSS69';
NODE_NAME     J31 164
 '@S9S_MB_2U_LIB.S9S_MB_2U(SCH_1):PAGE112_I178@PURE_QUANTA.SCONN288_ADR50017P130CC(CHIPS)':
 'VSS70': CDS_PINID='VSS70';
NODE_NAME     J31 166
 '@S9S_MB_2U_LIB.S9S_MB_2U(SCH_1):PAGE112_I178@PURE_QUANTA.SCONN288_ADR50017P130CC(CHIPS)':
 'VSS71': CDS_PINID='VSS71';
NODE_NAME     J31 169
 '@S9S_MB_2U_LIB.S9S_MB_2U(SCH_1):PAGE112_I178@PURE_QUANTA.SCONN288_ADR50017P130CC(CHIPS)':
 'VSS72': CDS_PINID='VSS72';
NODE_NAME     J31 171
 '@S9S_MB_2U_LIB.S9S_MB_2U(SCH_1):PAGE112_I178@PURE_QUANTA.SCONN288_ADR50017P130CC(CHIPS)':
 'VSS73': CDS_PINID='VSS73';
NODE_NAME     J31 173
 '@S9S_MB_2U_LIB.S9S_MB_2U(SCH_1):PAGE112_I178@PURE_QUANTA.SCONN288_ADR50017P130CC(CHIPS)':
 'VSS74': CDS_PINID='VSS74';
NODE_NAME     J31 175
 '@S9S_MB_2U_LIB.S9S_MB_2U(SCH_1):PAGE112_I178@PURE_QUANTA.SCONN288_ADR50017P130CC(CHIPS)':
 'VSS75': CDS_PINID='VSS75';
NODE_NAME     J31 177
 '@S9S_MB_2U_LIB.S9S_MB_2U(SCH_1):PAGE112_I178@PURE_QUANTA.SCONN288_ADR50017P130CC(CHIPS)':
 'VSS76': CDS_PINID='VSS76';
NODE_NAME     J31 180
 '@S9S_MB_2U_LIB.S9S_MB_2U(SCH_1):PAGE112_I178@PURE_QUANTA.SCONN288_ADR50017P130CC(CHIPS)':
 'VSS77': CDS_PINID='VSS77';
NODE_NAME     J31 182
 '@S9S_MB_2U_LIB.S9S_MB_2U(SCH_1):PAGE112_I178@PURE_QUANTA.SCONN288_ADR50017P130CC(CHIPS)':
 'VSS78': CDS_PINID='VSS78';
NODE_NAME     J31 184
 '@S9S_MB_2U_LIB.S9S_MB_2U(SCH_1):PAGE112_I178@PURE_QUANTA.SCONN288_ADR50017P130CC(CHIPS)':
 'VSS79': CDS_PINID='VSS79';
NODE_NAME     J31 186
 '@S9S_MB_2U_LIB.S9S_MB_2U(SCH_1):PAGE112_I178@PURE_QUANTA.SCONN288_ADR50017P130CC(CHIPS)':
 'VSS80': CDS_PINID='VSS80';
NODE_NAME     J31 188
 '@S9S_MB_2U_LIB.S9S_MB_2U(SCH_1):PAGE112_I178@PURE_QUANTA.SCONN288_ADR50017P130CC(CHIPS)':
 'VSS81': CDS_PINID='VSS81';
NODE_NAME     J31 191
 '@S9S_MB_2U_LIB.S9S_MB_2U(SCH_1):PAGE112_I178@PURE_QUANTA.SCONN288_ADR50017P130CC(CHIPS)':
 'VSS82': CDS_PINID='VSS82';
NODE_NAME     J31 193
 '@S9S_MB_2U_LIB.S9S_MB_2U(SCH_1):PAGE112_I178@PURE_QUANTA.SCONN288_ADR50017P130CC(CHIPS)':
 'VSS83': CDS_PINID='VSS83';
NODE_NAME     J31 195
 '@S9S_MB_2U_LIB.S9S_MB_2U(SCH_1):PAGE112_I178@PURE_QUANTA.SCONN288_ADR50017P130CC(CHIPS)':
 'VSS84': CDS_PINID='VSS84';
NODE_NAME     J31 197
 '@S9S_MB_2U_LIB.S9S_MB_2U(SCH_1):PAGE112_I178@PURE_QUANTA.SCONN288_ADR50017P130CC(CHIPS)':
 'VSS85': CDS_PINID='VSS85';
NODE_NAME     J31 199
 '@S9S_MB_2U_LIB.S9S_MB_2U(SCH_1):PAGE112_I178@PURE_QUANTA.SCONN288_ADR50017P130CC(CHIPS)':
 'VSS86': CDS_PINID='VSS86';
NODE_NAME     J31 202
 '@S9S_MB_2U_LIB.S9S_MB_2U(SCH_1):PAGE112_I178@PURE_QUANTA.SCONN288_ADR50017P130CC(CHIPS)':
 'VSS87': CDS_PINID='VSS87';
NODE_NAME     J31 204
 '@S9S_MB_2U_LIB.S9S_MB_2U(SCH_1):PAGE112_I178@PURE_QUANTA.SCONN288_ADR50017P130CC(CHIPS)':
 'VSS88': CDS_PINID='VSS88';
NODE_NAME     J31 206
 '@S9S_MB_2U_LIB.S9S_MB_2U(SCH_1):PAGE112_I178@PURE_QUANTA.SCONN288_ADR50017P130CC(CHIPS)':
 'VSS89': CDS_PINID='VSS89';
NODE_NAME     J31 208
 '@S9S_MB_2U_LIB.S9S_MB_2U(SCH_1):PAGE112_I178@PURE_QUANTA.SCONN288_ADR50017P130CC(CHIPS)':
 'VSS90': CDS_PINID='VSS90';
NODE_NAME     J31 210
 '@S9S_MB_2U_LIB.S9S_MB_2U(SCH_1):PAGE112_I178@PURE_QUANTA.SCONN288_ADR50017P130CC(CHIPS)':
 'VSS91': CDS_PINID='VSS91';
NODE_NAME     J31 212
 '@S9S_MB_2U_LIB.S9S_MB_2U(SCH_1):PAGE112_I178@PURE_QUANTA.SCONN288_ADR50017P130CC(CHIPS)':
 'VSS92': CDS_PINID='VSS92';
NODE_NAME     J31 214
 '@S9S_MB_2U_LIB.S9S_MB_2U(SCH_1):PAGE112_I178@PURE_QUANTA.SCONN288_ADR50017P130CC(CHIPS)':
 'VSS93': CDS_PINID='VSS93';
NODE_NAME     J31 216
 '@S9S_MB_2U_LIB.S9S_MB_2U(SCH_1):PAGE112_I178@PURE_QUANTA.SCONN288_ADR50017P130CC(CHIPS)':
 'VSS94': CDS_PINID='VSS94';
NODE_NAME     J31 219
 '@S9S_MB_2U_LIB.S9S_MB_2U(SCH_1):PAGE112_I178@PURE_QUANTA.SCONN288_ADR50017P130CC(CHIPS)':
 'VSS95': CDS_PINID='VSS95';
NODE_NAME     J31 222
 '@S9S_MB_2U_LIB.S9S_MB_2U(SCH_1):PAGE112_I178@PURE_QUANTA.SCONN288_ADR50017P130CC(CHIPS)':
 'VSS96': CDS_PINID='VSS96';
NODE_NAME     J31 224
 '@S9S_MB_2U_LIB.S9S_MB_2U(SCH_1):PAGE112_I178@PURE_QUANTA.SCONN288_ADR50017P130CC(CHIPS)':
 'VSS97': CDS_PINID='VSS97';
NODE_NAME     J31 226
 '@S9S_MB_2U_LIB.S9S_MB_2U(SCH_1):PAGE112_I178@PURE_QUANTA.SCONN288_ADR50017P130CC(CHIPS)':
 'VSS98': CDS_PINID='VSS98';
NODE_NAME     J31 228
 '@S9S_MB_2U_LIB.S9S_MB_2U(SCH_1):PAGE112_I178@PURE_QUANTA.SCONN288_ADR50017P130CC(CHIPS)':
 'VSS99': CDS_PINID='VSS99';
NODE_NAME     J31 230
 '@S9S_MB_2U_LIB.S9S_MB_2U(SCH_1):PAGE112_I178@PURE_QUANTA.SCONN288_ADR50017P130CC(CHIPS)':
 'VSS100': CDS_PINID='VSS100';
NODE_NAME     J31 233
 '@S9S_MB_2U_LIB.S9S_MB_2U(SCH_1):PAGE112_I178@PURE_QUANTA.SCONN288_ADR50017P130CC(CHIPS)':
 'VSS101': CDS_PINID='VSS101';
NODE_NAME     J31 235
 '@S9S_MB_2U_LIB.S9S_MB_2U(SCH_1):PAGE112_I178@PURE_QUANTA.SCONN288_ADR50017P130CC(CHIPS)':
 'VSS102': CDS_PINID='VSS102';
NODE_NAME     J31 237
 '@S9S_MB_2U_LIB.S9S_MB_2U(SCH_1):PAGE112_I178@PURE_QUANTA.SCONN288_ADR50017P130CC(CHIPS)':
 'VSS103': CDS_PINID='VSS103';
NODE_NAME     J31 240
 '@S9S_MB_2U_LIB.S9S_MB_2U(SCH_1):PAGE112_I178@PURE_QUANTA.SCONN288_ADR50017P130CC(CHIPS)':
 'VSS104': CDS_PINID='VSS104';
NODE_NAME     J31 242
 '@S9S_MB_2U_LIB.S9S_MB_2U(SCH_1):PAGE112_I178@PURE_QUANTA.SCONN288_ADR50017P130CC(CHIPS)':
 'VSS105': CDS_PINID='VSS105';
NODE_NAME     J31 244
 '@S9S_MB_2U_LIB.S9S_MB_2U(SCH_1):PAGE112_I178@PURE_QUANTA.SCONN288_ADR50017P130CC(CHIPS)':
 'VSS106': CDS_PINID='VSS106';
NODE_NAME     J31 246
 '@S9S_MB_2U_LIB.S9S_MB_2U(SCH_1):PAGE112_I178@PURE_QUANTA.SCONN288_ADR50017P130CC(CHIPS)':
 'VSS107': CDS_PINID='VSS107';
NODE_NAME     J31 248
 '@S9S_MB_2U_LIB.S9S_MB_2U(SCH_1):PAGE112_I178@PURE_QUANTA.SCONN288_ADR50017P130CC(CHIPS)':
 'VSS108': CDS_PINID='VSS108';
NODE_NAME     J31 251
 '@S9S_MB_2U_LIB.S9S_MB_2U(SCH_1):PAGE112_I178@PURE_QUANTA.SCONN288_ADR50017P130CC(CHIPS)':
 'VSS109': CDS_PINID='VSS109';
NODE_NAME     J31 253
 '@S9S_MB_2U_LIB.S9S_MB_2U(SCH_1):PAGE112_I178@PURE_QUANTA.SCONN288_ADR50017P130CC(CHIPS)':
 'VSS110': CDS_PINID='VSS110';
NODE_NAME     J31 255
 '@S9S_MB_2U_LIB.S9S_MB_2U(SCH_1):PAGE112_I178@PURE_QUANTA.SCONN288_ADR50017P130CC(CHIPS)':
 'VSS111': CDS_PINID='VSS111';
NODE_NAME     J31 257
 '@S9S_MB_2U_LIB.S9S_MB_2U(SCH_1):PAGE112_I178@PURE_QUANTA.SCONN288_ADR50017P130CC(CHIPS)':
 'VSS112': CDS_PINID='VSS112';
NODE_NAME     J31 259
 '@S9S_MB_2U_LIB.S9S_MB_2U(SCH_1):PAGE112_I178@PURE_QUANTA.SCONN288_ADR50017P130CC(CHIPS)':
 'VSS113': CDS_PINID='VSS113';
NODE_NAME     J31 262
 '@S9S_MB_2U_LIB.S9S_MB_2U(SCH_1):PAGE112_I178@PURE_QUANTA.SCONN288_ADR50017P130CC(CHIPS)':
 'VSS114': CDS_PINID='VSS114';
NODE_NAME     J31 264
 '@S9S_MB_2U_LIB.S9S_MB_2U(SCH_1):PAGE112_I178@PURE_QUANTA.SCONN288_ADR50017P130CC(CHIPS)':
 'VSS115': CDS_PINID='VSS115';
NODE_NAME     J31 266
 '@S9S_MB_2U_LIB.S9S_MB_2U(SCH_1):PAGE112_I178@PURE_QUANTA.SCONN288_ADR50017P130CC(CHIPS)':
 'VSS116': CDS_PINID='VSS116';
NODE_NAME     J31 268
 '@S9S_MB_2U_LIB.S9S_MB_2U(SCH_1):PAGE112_I178@PURE_QUANTA.SCONN288_ADR50017P130CC(CHIPS)':
 'VSS117': CDS_PINID='VSS117';
NODE_NAME     J31 270
 '@S9S_MB_2U_LIB.S9S_MB_2U(SCH_1):PAGE112_I178@PURE_QUANTA.SCONN288_ADR50017P130CC(CHIPS)':
 'VSS118': CDS_PINID='VSS118';
NODE_NAME     J31 273
 '@S9S_MB_2U_LIB.S9S_MB_2U(SCH_1):PAGE112_I178@PURE_QUANTA.SCONN288_ADR50017P130CC(CHIPS)':
 'VSS119': CDS_PINID='VSS119';
NODE_NAME     J31 275
 '@S9S_MB_2U_LIB.S9S_MB_2U(SCH_1):PAGE112_I178@PURE_QUANTA.SCONN288_ADR50017P130CC(CHIPS)':
 'VSS120': CDS_PINID='VSS120';
NODE_NAME     J31 277
 '@S9S_MB_2U_LIB.S9S_MB_2U(SCH_1):PAGE112_I178@PURE_QUANTA.SCONN288_ADR50017P130CC(CHIPS)':
 'VSS121': CDS_PINID='VSS121';
NODE_NAME     J31 279
 '@S9S_MB_2U_LIB.S9S_MB_2U(SCH_1):PAGE112_I178@PURE_QUANTA.SCONN288_ADR50017P130CC(CHIPS)':
 'VSS122': CDS_PINID='VSS122';
NODE_NAME     J31 281
 '@S9S_MB_2U_LIB.S9S_MB_2U(SCH_1):PAGE112_I178@PURE_QUANTA.SCONN288_ADR50017P130CC(CHIPS)':
 'VSS123': CDS_PINID='VSS123';
NODE_NAME     J31 284
 '@S9S_MB_2U_LIB.S9S_MB_2U(SCH_1):PAGE112_I178@PURE_QUANTA.SCONN288_ADR50017P130CC(CHIPS)':
 'VSS124': CDS_PINID='VSS124';
NODE_NAME     J31 286
 '@S9S_MB_2U_LIB.S9S_MB_2U(SCH_1):PAGE112_I178@PURE_QUANTA.SCONN288_ADR50017P130CC(CHIPS)':
 'VSS125': CDS_PINID='VSS125';
NODE_NAME     J31 288
 '@S9S_MB_2U_LIB.S9S_MB_2U(SCH_1):PAGE112_I178@PURE_QUANTA.SCONN288_ADR50017P130CC(CHIPS)':
 'VSS126': CDS_PINID='VSS126';
NODE_NAME     R72 2
 '@S9S_MB_2U_LIB.S9S_MB_2U(SCH_1):PAGE113_I2@PURE_QUANTA.Q_RES(CHIPS)':
 'B': CDS_PINID='B';
NODE_NAME     C72 2
 '@S9S_MB_2U_LIB.S9S_MB_2U(SCH_1):PAGE113_I116@PURE_QUANTA.Q_CAP(CHIPS)':
 'B': CDS_PINID='B';
NODE_NAME     C73 2
 '@S9S_MB_2U_LIB.S9S_MB_2U(SCH_1):PAGE113_I120@PURE_QUANTA.Q_CAP(CHIPS)':
 'B': CDS_PINID='B';
NODE_NAME     C74 2
 '@S9S_MB_2U_LIB.S9S_MB_2U(SCH_1):PAGE113_I122@PURE_QUANTA.Q_CAP(CHIPS)':
 'B': CDS_PINID='B';
NODE_NAME     J32 G1
 '@S9S_MB_2U_LIB.S9S_MB_2U(SCH_1):PAGE113_I177@PURE_QUANTA.SCONN288_ADR50017P087CC(CHIPS)':
 'G1': CDS_PINID='G1';
NODE_NAME     J32 G2
 '@S9S_MB_2U_LIB.S9S_MB_2U(SCH_1):PAGE113_I177@PURE_QUANTA.SCONN288_ADR50017P087CC(CHIPS)':
 'G2': CDS_PINID='G2';
NODE_NAME     J32 G3
 '@S9S_MB_2U_LIB.S9S_MB_2U(SCH_1):PAGE113_I177@PURE_QUANTA.SCONN288_ADR50017P087CC(CHIPS)':
 'G3': CDS_PINID='G3';
NODE_NAME     J32 6
 '@S9S_MB_2U_LIB.S9S_MB_2U(SCH_1):PAGE113_I177@PURE_QUANTA.SCONN288_ADR50017P087CC(CHIPS)':
 'VSS0': CDS_PINID='VSS0';
NODE_NAME     J32 8
 '@S9S_MB_2U_LIB.S9S_MB_2U(SCH_1):PAGE113_I177@PURE_QUANTA.SCONN288_ADR50017P087CC(CHIPS)':
 'VSS1': CDS_PINID='VSS1';
NODE_NAME     J32 10
 '@S9S_MB_2U_LIB.S9S_MB_2U(SCH_1):PAGE113_I177@PURE_QUANTA.SCONN288_ADR50017P087CC(CHIPS)':
 'VSS2': CDS_PINID='VSS2';
NODE_NAME     J32 13
 '@S9S_MB_2U_LIB.S9S_MB_2U(SCH_1):PAGE113_I177@PURE_QUANTA.SCONN288_ADR50017P087CC(CHIPS)':
 'VSS3': CDS_PINID='VSS3';
NODE_NAME     J32 15
 '@S9S_MB_2U_LIB.S9S_MB_2U(SCH_1):PAGE113_I177@PURE_QUANTA.SCONN288_ADR50017P087CC(CHIPS)':
 'VSS4': CDS_PINID='VSS4';
NODE_NAME     J32 17
 '@S9S_MB_2U_LIB.S9S_MB_2U(SCH_1):PAGE113_I177@PURE_QUANTA.SCONN288_ADR50017P087CC(CHIPS)':
 'VSS5': CDS_PINID='VSS5';
NODE_NAME     J32 19
 '@S9S_MB_2U_LIB.S9S_MB_2U(SCH_1):PAGE113_I177@PURE_QUANTA.SCONN288_ADR50017P087CC(CHIPS)':
 'VSS6': CDS_PINID='VSS6';
NODE_NAME     J32 21
 '@S9S_MB_2U_LIB.S9S_MB_2U(SCH_1):PAGE113_I177@PURE_QUANTA.SCONN288_ADR50017P087CC(CHIPS)':
 'VSS7': CDS_PINID='VSS7';
NODE_NAME     J32 24
 '@S9S_MB_2U_LIB.S9S_MB_2U(SCH_1):PAGE113_I177@PURE_QUANTA.SCONN288_ADR50017P087CC(CHIPS)':
 'VSS8': CDS_PINID='VSS8';
NODE_NAME     J32 26
 '@S9S_MB_2U_LIB.S9S_MB_2U(SCH_1):PAGE113_I177@PURE_QUANTA.SCONN288_ADR50017P087CC(CHIPS)':
 'VSS9': CDS_PINID='VSS9';
NODE_NAME     J32 28
 '@S9S_MB_2U_LIB.S9S_MB_2U(SCH_1):PAGE113_I177@PURE_QUANTA.SCONN288_ADR50017P087CC(CHIPS)':
 'VSS10': CDS_PINID='VSS10';
NODE_NAME     J32 30
 '@S9S_MB_2U_LIB.S9S_MB_2U(SCH_1):PAGE113_I177@PURE_QUANTA.SCONN288_ADR50017P087CC(CHIPS)':
 'VSS11': CDS_PINID='VSS11';
NODE_NAME     J32 32
 '@S9S_MB_2U_LIB.S9S_MB_2U(SCH_1):PAGE113_I177@PURE_QUANTA.SCONN288_ADR50017P087CC(CHIPS)':
 'VSS12': CDS_PINID='VSS12';
NODE_NAME     J32 35
 '@S9S_MB_2U_LIB.S9S_MB_2U(SCH_1):PAGE113_I177@PURE_QUANTA.SCONN288_ADR50017P087CC(CHIPS)':
 'VSS13': CDS_PINID='VSS13';
NODE_NAME     J32 37
 '@S9S_MB_2U_LIB.S9S_MB_2U(SCH_1):PAGE113_I177@PURE_QUANTA.SCONN288_ADR50017P087CC(CHIPS)':
 'VSS14': CDS_PINID='VSS14';
NODE_NAME     J32 39
 '@S9S_MB_2U_LIB.S9S_MB_2U(SCH_1):PAGE113_I177@PURE_QUANTA.SCONN288_ADR50017P087CC(CHIPS)':
 'VSS15': CDS_PINID='VSS15';
NODE_NAME     J32 41
 '@S9S_MB_2U_LIB.S9S_MB_2U(SCH_1):PAGE113_I177@PURE_QUANTA.SCONN288_ADR50017P087CC(CHIPS)':
 'VSS16': CDS_PINID='VSS16';
NODE_NAME     J32 43
 '@S9S_MB_2U_LIB.S9S_MB_2U(SCH_1):PAGE113_I177@PURE_QUANTA.SCONN288_ADR50017P087CC(CHIPS)':
 'VSS17': CDS_PINID='VSS17';
NODE_NAME     J32 46
 '@S9S_MB_2U_LIB.S9S_MB_2U(SCH_1):PAGE113_I177@PURE_QUANTA.SCONN288_ADR50017P087CC(CHIPS)':
 'VSS18': CDS_PINID='VSS18';
NODE_NAME     J32 48
 '@S9S_MB_2U_LIB.S9S_MB_2U(SCH_1):PAGE113_I177@PURE_QUANTA.SCONN288_ADR50017P087CC(CHIPS)':
 'VSS19': CDS_PINID='VSS19';
NODE_NAME     J32 50
 '@S9S_MB_2U_LIB.S9S_MB_2U(SCH_1):PAGE113_I177@PURE_QUANTA.SCONN288_ADR50017P087CC(CHIPS)':
 'VSS20': CDS_PINID='VSS20';
NODE_NAME     J32 52
 '@S9S_MB_2U_LIB.S9S_MB_2U(SCH_1):PAGE113_I177@PURE_QUANTA.SCONN288_ADR50017P087CC(CHIPS)':
 'VSS21': CDS_PINID='VSS21';
NODE_NAME     J32 54
 '@S9S_MB_2U_LIB.S9S_MB_2U(SCH_1):PAGE113_I177@PURE_QUANTA.SCONN288_ADR50017P087CC(CHIPS)':
 'VSS22': CDS_PINID='VSS22';
NODE_NAME     J32 57
 '@S9S_MB_2U_LIB.S9S_MB_2U(SCH_1):PAGE113_I177@PURE_QUANTA.SCONN288_ADR50017P087CC(CHIPS)':
 'VSS23': CDS_PINID='VSS23';
NODE_NAME     J32 59
 '@S9S_MB_2U_LIB.S9S_MB_2U(SCH_1):PAGE113_I177@PURE_QUANTA.SCONN288_ADR50017P087CC(CHIPS)':
 'VSS24': CDS_PINID='VSS24';
NODE_NAME     J32 61
 '@S9S_MB_2U_LIB.S9S_MB_2U(SCH_1):PAGE113_I177@PURE_QUANTA.SCONN288_ADR50017P087CC(CHIPS)':
 'VSS25': CDS_PINID='VSS25';
NODE_NAME     J32 63
 '@S9S_MB_2U_LIB.S9S_MB_2U(SCH_1):PAGE113_I177@PURE_QUANTA.SCONN288_ADR50017P087CC(CHIPS)':
 'VSS26': CDS_PINID='VSS26';
NODE_NAME     J32 65
 '@S9S_MB_2U_LIB.S9S_MB_2U(SCH_1):PAGE113_I177@PURE_QUANTA.SCONN288_ADR50017P087CC(CHIPS)':
 'VSS27': CDS_PINID='VSS27';
NODE_NAME     J32 67
 '@S9S_MB_2U_LIB.S9S_MB_2U(SCH_1):PAGE113_I177@PURE_QUANTA.SCONN288_ADR50017P087CC(CHIPS)':
 'VSS28': CDS_PINID='VSS28';
NODE_NAME     J32 69
 '@S9S_MB_2U_LIB.S9S_MB_2U(SCH_1):PAGE113_I177@PURE_QUANTA.SCONN288_ADR50017P087CC(CHIPS)':
 'VSS29': CDS_PINID='VSS29';
NODE_NAME     J32 71
 '@S9S_MB_2U_LIB.S9S_MB_2U(SCH_1):PAGE113_I177@PURE_QUANTA.SCONN288_ADR50017P087CC(CHIPS)':
 'VSS30': CDS_PINID='VSS30';
NODE_NAME     J32 73
 '@S9S_MB_2U_LIB.S9S_MB_2U(SCH_1):PAGE113_I177@PURE_QUANTA.SCONN288_ADR50017P087CC(CHIPS)':
 'VSS31': CDS_PINID='VSS31';
NODE_NAME     J32 75
 '@S9S_MB_2U_LIB.S9S_MB_2U(SCH_1):PAGE113_I177@PURE_QUANTA.SCONN288_ADR50017P087CC(CHIPS)':
 'VSS32': CDS_PINID='VSS32';
NODE_NAME     J32 77
 '@S9S_MB_2U_LIB.S9S_MB_2U(SCH_1):PAGE113_I177@PURE_QUANTA.SCONN288_ADR50017P087CC(CHIPS)':
 'VSS33': CDS_PINID='VSS33';
NODE_NAME     J32 79
 '@S9S_MB_2U_LIB.S9S_MB_2U(SCH_1):PAGE113_I177@PURE_QUANTA.SCONN288_ADR50017P087CC(CHIPS)':
 'VSS34': CDS_PINID='VSS34';
NODE_NAME     J32 81
 '@S9S_MB_2U_LIB.S9S_MB_2U(SCH_1):PAGE113_I177@PURE_QUANTA.SCONN288_ADR50017P087CC(CHIPS)':
 'VSS35': CDS_PINID='VSS35';
NODE_NAME     J32 83
 '@S9S_MB_2U_LIB.S9S_MB_2U(SCH_1):PAGE113_I177@PURE_QUANTA.SCONN288_ADR50017P087CC(CHIPS)':
 'VSS36': CDS_PINID='VSS36';
NODE_NAME     J32 85
 '@S9S_MB_2U_LIB.S9S_MB_2U(SCH_1):PAGE113_I177@PURE_QUANTA.SCONN288_ADR50017P087CC(CHIPS)':
 'VSS37': CDS_PINID='VSS37';
NODE_NAME     J32 88
 '@S9S_MB_2U_LIB.S9S_MB_2U(SCH_1):PAGE113_I177@PURE_QUANTA.SCONN288_ADR50017P087CC(CHIPS)':
 'VSS38': CDS_PINID='VSS38';
NODE_NAME     J32 90
 '@S9S_MB_2U_LIB.S9S_MB_2U(SCH_1):PAGE113_I177@PURE_QUANTA.SCONN288_ADR50017P087CC(CHIPS)':
 'VSS39': CDS_PINID='VSS39';
NODE_NAME     J32 92
 '@S9S_MB_2U_LIB.S9S_MB_2U(SCH_1):PAGE113_I177@PURE_QUANTA.SCONN288_ADR50017P087CC(CHIPS)':
 'VSS40': CDS_PINID='VSS40';
NODE_NAME     J32 95
 '@S9S_MB_2U_LIB.S9S_MB_2U(SCH_1):PAGE113_I177@PURE_QUANTA.SCONN288_ADR50017P087CC(CHIPS)':
 'VSS41': CDS_PINID='VSS41';
NODE_NAME     J32 97
 '@S9S_MB_2U_LIB.S9S_MB_2U(SCH_1):PAGE113_I177@PURE_QUANTA.SCONN288_ADR50017P087CC(CHIPS)':
 'VSS42': CDS_PINID='VSS42';
NODE_NAME     J32 99
 '@S9S_MB_2U_LIB.S9S_MB_2U(SCH_1):PAGE113_I177@PURE_QUANTA.SCONN288_ADR50017P087CC(CHIPS)':
 'VSS43': CDS_PINID='VSS43';
NODE_NAME     J32 101
 '@S9S_MB_2U_LIB.S9S_MB_2U(SCH_1):PAGE113_I177@PURE_QUANTA.SCONN288_ADR50017P087CC(CHIPS)':
 'VSS44': CDS_PINID='VSS44';
NODE_NAME     J32 103
 '@S9S_MB_2U_LIB.S9S_MB_2U(SCH_1):PAGE113_I177@PURE_QUANTA.SCONN288_ADR50017P087CC(CHIPS)':
 'VSS45': CDS_PINID='VSS45';
NODE_NAME     J32 106
 '@S9S_MB_2U_LIB.S9S_MB_2U(SCH_1):PAGE113_I177@PURE_QUANTA.SCONN288_ADR50017P087CC(CHIPS)':
 'VSS46': CDS_PINID='VSS46';
NODE_NAME     J32 108
 '@S9S_MB_2U_LIB.S9S_MB_2U(SCH_1):PAGE113_I177@PURE_QUANTA.SCONN288_ADR50017P087CC(CHIPS)':
 'VSS47': CDS_PINID='VSS47';
NODE_NAME     J32 110
 '@S9S_MB_2U_LIB.S9S_MB_2U(SCH_1):PAGE113_I177@PURE_QUANTA.SCONN288_ADR50017P087CC(CHIPS)':
 'VSS48': CDS_PINID='VSS48';
NODE_NAME     J32 112
 '@S9S_MB_2U_LIB.S9S_MB_2U(SCH_1):PAGE113_I177@PURE_QUANTA.SCONN288_ADR50017P087CC(CHIPS)':
 'VSS49': CDS_PINID='VSS49';
NODE_NAME     J32 114
 '@S9S_MB_2U_LIB.S9S_MB_2U(SCH_1):PAGE113_I177@PURE_QUANTA.SCONN288_ADR50017P087CC(CHIPS)':
 'VSS50': CDS_PINID='VSS50';
NODE_NAME     J32 117
 '@S9S_MB_2U_LIB.S9S_MB_2U(SCH_1):PAGE113_I177@PURE_QUANTA.SCONN288_ADR50017P087CC(CHIPS)':
 'VSS51': CDS_PINID='VSS51';
NODE_NAME     J32 119
 '@S9S_MB_2U_LIB.S9S_MB_2U(SCH_1):PAGE113_I177@PURE_QUANTA.SCONN288_ADR50017P087CC(CHIPS)':
 'VSS52': CDS_PINID='VSS52';
NODE_NAME     J32 121
 '@S9S_MB_2U_LIB.S9S_MB_2U(SCH_1):PAGE113_I177@PURE_QUANTA.SCONN288_ADR50017P087CC(CHIPS)':
 'VSS53': CDS_PINID='VSS53';
NODE_NAME     J32 123
 '@S9S_MB_2U_LIB.S9S_MB_2U(SCH_1):PAGE113_I177@PURE_QUANTA.SCONN288_ADR50017P087CC(CHIPS)':
 'VSS54': CDS_PINID='VSS54';
NODE_NAME     J32 125
 '@S9S_MB_2U_LIB.S9S_MB_2U(SCH_1):PAGE113_I177@PURE_QUANTA.SCONN288_ADR50017P087CC(CHIPS)':
 'VSS55': CDS_PINID='VSS55';
NODE_NAME     J32 128
 '@S9S_MB_2U_LIB.S9S_MB_2U(SCH_1):PAGE113_I177@PURE_QUANTA.SCONN288_ADR50017P087CC(CHIPS)':
 'VSS56': CDS_PINID='VSS56';
NODE_NAME     J32 130
 '@S9S_MB_2U_LIB.S9S_MB_2U(SCH_1):PAGE113_I177@PURE_QUANTA.SCONN288_ADR50017P087CC(CHIPS)':
 'VSS57': CDS_PINID='VSS57';
NODE_NAME     J32 132
 '@S9S_MB_2U_LIB.S9S_MB_2U(SCH_1):PAGE113_I177@PURE_QUANTA.SCONN288_ADR50017P087CC(CHIPS)':
 'VSS58': CDS_PINID='VSS58';
NODE_NAME     J32 134
 '@S9S_MB_2U_LIB.S9S_MB_2U(SCH_1):PAGE113_I177@PURE_QUANTA.SCONN288_ADR50017P087CC(CHIPS)':
 'VSS59': CDS_PINID='VSS59';
NODE_NAME     J32 136
 '@S9S_MB_2U_LIB.S9S_MB_2U(SCH_1):PAGE113_I177@PURE_QUANTA.SCONN288_ADR50017P087CC(CHIPS)':
 'VSS60': CDS_PINID='VSS60';
NODE_NAME     J32 139
 '@S9S_MB_2U_LIB.S9S_MB_2U(SCH_1):PAGE113_I177@PURE_QUANTA.SCONN288_ADR50017P087CC(CHIPS)':
 'VSS61': CDS_PINID='VSS61';
NODE_NAME     J32 141
 '@S9S_MB_2U_LIB.S9S_MB_2U(SCH_1):PAGE113_I177@PURE_QUANTA.SCONN288_ADR50017P087CC(CHIPS)':
 'VSS62': CDS_PINID='VSS62';
NODE_NAME     J32 143
 '@S9S_MB_2U_LIB.S9S_MB_2U(SCH_1):PAGE113_I177@PURE_QUANTA.SCONN288_ADR50017P087CC(CHIPS)':
 'VSS63': CDS_PINID='VSS63';
NODE_NAME     J32 151
 '@S9S_MB_2U_LIB.S9S_MB_2U(SCH_1):PAGE113_I177@PURE_QUANTA.SCONN288_ADR50017P087CC(CHIPS)':
 'VSS64': CDS_PINID='VSS64';
NODE_NAME     J32 153
 '@S9S_MB_2U_LIB.S9S_MB_2U(SCH_1):PAGE113_I177@PURE_QUANTA.SCONN288_ADR50017P087CC(CHIPS)':
 'VSS65': CDS_PINID='VSS65';
NODE_NAME     J32 155
 '@S9S_MB_2U_LIB.S9S_MB_2U(SCH_1):PAGE113_I177@PURE_QUANTA.SCONN288_ADR50017P087CC(CHIPS)':
 'VSS66': CDS_PINID='VSS66';
NODE_NAME     J32 158
 '@S9S_MB_2U_LIB.S9S_MB_2U(SCH_1):PAGE113_I177@PURE_QUANTA.SCONN288_ADR50017P087CC(CHIPS)':
 'VSS67': CDS_PINID='VSS67';
NODE_NAME     J32 160
 '@S9S_MB_2U_LIB.S9S_MB_2U(SCH_1):PAGE113_I177@PURE_QUANTA.SCONN288_ADR50017P087CC(CHIPS)':
 'VSS68': CDS_PINID='VSS68';
NODE_NAME     J32 162
 '@S9S_MB_2U_LIB.S9S_MB_2U(SCH_1):PAGE113_I177@PURE_QUANTA.SCONN288_ADR50017P087CC(CHIPS)':
 'VSS69': CDS_PINID='VSS69';
NODE_NAME     J32 164
 '@S9S_MB_2U_LIB.S9S_MB_2U(SCH_1):PAGE113_I177@PURE_QUANTA.SCONN288_ADR50017P087CC(CHIPS)':
 'VSS70': CDS_PINID='VSS70';
NODE_NAME     J32 166
 '@S9S_MB_2U_LIB.S9S_MB_2U(SCH_1):PAGE113_I177@PURE_QUANTA.SCONN288_ADR50017P087CC(CHIPS)':
 'VSS71': CDS_PINID='VSS71';
NODE_NAME     J32 169
 '@S9S_MB_2U_LIB.S9S_MB_2U(SCH_1):PAGE113_I177@PURE_QUANTA.SCONN288_ADR50017P087CC(CHIPS)':
 'VSS72': CDS_PINID='VSS72';
NODE_NAME     J32 171
 '@S9S_MB_2U_LIB.S9S_MB_2U(SCH_1):PAGE113_I177@PURE_QUANTA.SCONN288_ADR50017P087CC(CHIPS)':
 'VSS73': CDS_PINID='VSS73';
NODE_NAME     J32 173
 '@S9S_MB_2U_LIB.S9S_MB_2U(SCH_1):PAGE113_I177@PURE_QUANTA.SCONN288_ADR50017P087CC(CHIPS)':
 'VSS74': CDS_PINID='VSS74';
NODE_NAME     J32 175
 '@S9S_MB_2U_LIB.S9S_MB_2U(SCH_1):PAGE113_I177@PURE_QUANTA.SCONN288_ADR50017P087CC(CHIPS)':
 'VSS75': CDS_PINID='VSS75';
NODE_NAME     J32 177
 '@S9S_MB_2U_LIB.S9S_MB_2U(SCH_1):PAGE113_I177@PURE_QUANTA.SCONN288_ADR50017P087CC(CHIPS)':
 'VSS76': CDS_PINID='VSS76';
NODE_NAME     J32 180
 '@S9S_MB_2U_LIB.S9S_MB_2U(SCH_1):PAGE113_I177@PURE_QUANTA.SCONN288_ADR50017P087CC(CHIPS)':
 'VSS77': CDS_PINID='VSS77';
NODE_NAME     J32 182
 '@S9S_MB_2U_LIB.S9S_MB_2U(SCH_1):PAGE113_I177@PURE_QUANTA.SCONN288_ADR50017P087CC(CHIPS)':
 'VSS78': CDS_PINID='VSS78';
NODE_NAME     J32 184
 '@S9S_MB_2U_LIB.S9S_MB_2U(SCH_1):PAGE113_I177@PURE_QUANTA.SCONN288_ADR50017P087CC(CHIPS)':
 'VSS79': CDS_PINID='VSS79';
NODE_NAME     J32 186
 '@S9S_MB_2U_LIB.S9S_MB_2U(SCH_1):PAGE113_I177@PURE_QUANTA.SCONN288_ADR50017P087CC(CHIPS)':
 'VSS80': CDS_PINID='VSS80';
NODE_NAME     J32 188
 '@S9S_MB_2U_LIB.S9S_MB_2U(SCH_1):PAGE113_I177@PURE_QUANTA.SCONN288_ADR50017P087CC(CHIPS)':
 'VSS81': CDS_PINID='VSS81';
NODE_NAME     J32 191
 '@S9S_MB_2U_LIB.S9S_MB_2U(SCH_1):PAGE113_I177@PURE_QUANTA.SCONN288_ADR50017P087CC(CHIPS)':
 'VSS82': CDS_PINID='VSS82';
NODE_NAME     J32 193
 '@S9S_MB_2U_LIB.S9S_MB_2U(SCH_1):PAGE113_I177@PURE_QUANTA.SCONN288_ADR50017P087CC(CHIPS)':
 'VSS83': CDS_PINID='VSS83';
NODE_NAME     J32 195
 '@S9S_MB_2U_LIB.S9S_MB_2U(SCH_1):PAGE113_I177@PURE_QUANTA.SCONN288_ADR50017P087CC(CHIPS)':
 'VSS84': CDS_PINID='VSS84';
NODE_NAME     J32 197
 '@S9S_MB_2U_LIB.S9S_MB_2U(SCH_1):PAGE113_I177@PURE_QUANTA.SCONN288_ADR50017P087CC(CHIPS)':
 'VSS85': CDS_PINID='VSS85';
NODE_NAME     J32 199
 '@S9S_MB_2U_LIB.S9S_MB_2U(SCH_1):PAGE113_I177@PURE_QUANTA.SCONN288_ADR50017P087CC(CHIPS)':
 'VSS86': CDS_PINID='VSS86';
NODE_NAME     J32 202
 '@S9S_MB_2U_LIB.S9S_MB_2U(SCH_1):PAGE113_I177@PURE_QUANTA.SCONN288_ADR50017P087CC(CHIPS)':
 'VSS87': CDS_PINID='VSS87';
NODE_NAME     J32 204
 '@S9S_MB_2U_LIB.S9S_MB_2U(SCH_1):PAGE113_I177@PURE_QUANTA.SCONN288_ADR50017P087CC(CHIPS)':
 'VSS88': CDS_PINID='VSS88';
NODE_NAME     J32 206
 '@S9S_MB_2U_LIB.S9S_MB_2U(SCH_1):PAGE113_I177@PURE_QUANTA.SCONN288_ADR50017P087CC(CHIPS)':
 'VSS89': CDS_PINID='VSS89';
NODE_NAME     J32 208
 '@S9S_MB_2U_LIB.S9S_MB_2U(SCH_1):PAGE113_I177@PURE_QUANTA.SCONN288_ADR50017P087CC(CHIPS)':
 'VSS90': CDS_PINID='VSS90';
NODE_NAME     J32 210
 '@S9S_MB_2U_LIB.S9S_MB_2U(SCH_1):PAGE113_I177@PURE_QUANTA.SCONN288_ADR50017P087CC(CHIPS)':
 'VSS91': CDS_PINID='VSS91';
NODE_NAME     J32 212
 '@S9S_MB_2U_LIB.S9S_MB_2U(SCH_1):PAGE113_I177@PURE_QUANTA.SCONN288_ADR50017P087CC(CHIPS)':
 'VSS92': CDS_PINID='VSS92';
NODE_NAME     J32 214
 '@S9S_MB_2U_LIB.S9S_MB_2U(SCH_1):PAGE113_I177@PURE_QUANTA.SCONN288_ADR50017P087CC(CHIPS)':
 'VSS93': CDS_PINID='VSS93';
NODE_NAME     J32 216
 '@S9S_MB_2U_LIB.S9S_MB_2U(SCH_1):PAGE113_I177@PURE_QUANTA.SCONN288_ADR50017P087CC(CHIPS)':
 'VSS94': CDS_PINID='VSS94';
NODE_NAME     J32 219
 '@S9S_MB_2U_LIB.S9S_MB_2U(SCH_1):PAGE113_I177@PURE_QUANTA.SCONN288_ADR50017P087CC(CHIPS)':
 'VSS95': CDS_PINID='VSS95';
NODE_NAME     J32 222
 '@S9S_MB_2U_LIB.S9S_MB_2U(SCH_1):PAGE113_I177@PURE_QUANTA.SCONN288_ADR50017P087CC(CHIPS)':
 'VSS96': CDS_PINID='VSS96';
NODE_NAME     J32 224
 '@S9S_MB_2U_LIB.S9S_MB_2U(SCH_1):PAGE113_I177@PURE_QUANTA.SCONN288_ADR50017P087CC(CHIPS)':
 'VSS97': CDS_PINID='VSS97';
NODE_NAME     J32 226
 '@S9S_MB_2U_LIB.S9S_MB_2U(SCH_1):PAGE113_I177@PURE_QUANTA.SCONN288_ADR50017P087CC(CHIPS)':
 'VSS98': CDS_PINID='VSS98';
NODE_NAME     J32 228
 '@S9S_MB_2U_LIB.S9S_MB_2U(SCH_1):PAGE113_I177@PURE_QUANTA.SCONN288_ADR50017P087CC(CHIPS)':
 'VSS99': CDS_PINID='VSS99';
NODE_NAME     J32 230
 '@S9S_MB_2U_LIB.S9S_MB_2U(SCH_1):PAGE113_I177@PURE_QUANTA.SCONN288_ADR50017P087CC(CHIPS)':
 'VSS100': CDS_PINID='VSS100';
NODE_NAME     J32 233
 '@S9S_MB_2U_LIB.S9S_MB_2U(SCH_1):PAGE113_I177@PURE_QUANTA.SCONN288_ADR50017P087CC(CHIPS)':
 'VSS101': CDS_PINID='VSS101';
NODE_NAME     J32 235
 '@S9S_MB_2U_LIB.S9S_MB_2U(SCH_1):PAGE113_I177@PURE_QUANTA.SCONN288_ADR50017P087CC(CHIPS)':
 'VSS102': CDS_PINID='VSS102';
NODE_NAME     J32 237
 '@S9S_MB_2U_LIB.S9S_MB_2U(SCH_1):PAGE113_I177@PURE_QUANTA.SCONN288_ADR50017P087CC(CHIPS)':
 'VSS103': CDS_PINID='VSS103';
NODE_NAME     J32 240
 '@S9S_MB_2U_LIB.S9S_MB_2U(SCH_1):PAGE113_I177@PURE_QUANTA.SCONN288_ADR50017P087CC(CHIPS)':
 'VSS104': CDS_PINID='VSS104';
NODE_NAME     J32 242
 '@S9S_MB_2U_LIB.S9S_MB_2U(SCH_1):PAGE113_I177@PURE_QUANTA.SCONN288_ADR50017P087CC(CHIPS)':
 'VSS105': CDS_PINID='VSS105';
NODE_NAME     J32 244
 '@S9S_MB_2U_LIB.S9S_MB_2U(SCH_1):PAGE113_I177@PURE_QUANTA.SCONN288_ADR50017P087CC(CHIPS)':
 'VSS106': CDS_PINID='VSS106';
NODE_NAME     J32 246
 '@S9S_MB_2U_LIB.S9S_MB_2U(SCH_1):PAGE113_I177@PURE_QUANTA.SCONN288_ADR50017P087CC(CHIPS)':
 'VSS107': CDS_PINID='VSS107';
NODE_NAME     J32 248
 '@S9S_MB_2U_LIB.S9S_MB_2U(SCH_1):PAGE113_I177@PURE_QUANTA.SCONN288_ADR50017P087CC(CHIPS)':
 'VSS108': CDS_PINID='VSS108';
NODE_NAME     J32 251
 '@S9S_MB_2U_LIB.S9S_MB_2U(SCH_1):PAGE113_I177@PURE_QUANTA.SCONN288_ADR50017P087CC(CHIPS)':
 'VSS109': CDS_PINID='VSS109';
NODE_NAME     J32 253
 '@S9S_MB_2U_LIB.S9S_MB_2U(SCH_1):PAGE113_I177@PURE_QUANTA.SCONN288_ADR50017P087CC(CHIPS)':
 'VSS110': CDS_PINID='VSS110';
NODE_NAME     J32 255
 '@S9S_MB_2U_LIB.S9S_MB_2U(SCH_1):PAGE113_I177@PURE_QUANTA.SCONN288_ADR50017P087CC(CHIPS)':
 'VSS111': CDS_PINID='VSS111';
NODE_NAME     J32 257
 '@S9S_MB_2U_LIB.S9S_MB_2U(SCH_1):PAGE113_I177@PURE_QUANTA.SCONN288_ADR50017P087CC(CHIPS)':
 'VSS112': CDS_PINID='VSS112';
NODE_NAME     J32 259
 '@S9S_MB_2U_LIB.S9S_MB_2U(SCH_1):PAGE113_I177@PURE_QUANTA.SCONN288_ADR50017P087CC(CHIPS)':
 'VSS113': CDS_PINID='VSS113';
NODE_NAME     J32 262
 '@S9S_MB_2U_LIB.S9S_MB_2U(SCH_1):PAGE113_I177@PURE_QUANTA.SCONN288_ADR50017P087CC(CHIPS)':
 'VSS114': CDS_PINID='VSS114';
NODE_NAME     J32 264
 '@S9S_MB_2U_LIB.S9S_MB_2U(SCH_1):PAGE113_I177@PURE_QUANTA.SCONN288_ADR50017P087CC(CHIPS)':
 'VSS115': CDS_PINID='VSS115';
NODE_NAME     J32 266
 '@S9S_MB_2U_LIB.S9S_MB_2U(SCH_1):PAGE113_I177@PURE_QUANTA.SCONN288_ADR50017P087CC(CHIPS)':
 'VSS116': CDS_PINID='VSS116';
NODE_NAME     J32 268
 '@S9S_MB_2U_LIB.S9S_MB_2U(SCH_1):PAGE113_I177@PURE_QUANTA.SCONN288_ADR50017P087CC(CHIPS)':
 'VSS117': CDS_PINID='VSS117';
NODE_NAME     J32 270
 '@S9S_MB_2U_LIB.S9S_MB_2U(SCH_1):PAGE113_I177@PURE_QUANTA.SCONN288_ADR50017P087CC(CHIPS)':
 'VSS118': CDS_PINID='VSS118';
NODE_NAME     J32 273
 '@S9S_MB_2U_LIB.S9S_MB_2U(SCH_1):PAGE113_I177@PURE_QUANTA.SCONN288_ADR50017P087CC(CHIPS)':
 'VSS119': CDS_PINID='VSS119';
NODE_NAME     J32 275
 '@S9S_MB_2U_LIB.S9S_MB_2U(SCH_1):PAGE113_I177@PURE_QUANTA.SCONN288_ADR50017P087CC(CHIPS)':
 'VSS120': CDS_PINID='VSS120';
NODE_NAME     J32 277
 '@S9S_MB_2U_LIB.S9S_MB_2U(SCH_1):PAGE113_I177@PURE_QUANTA.SCONN288_ADR50017P087CC(CHIPS)':
 'VSS121': CDS_PINID='VSS121';
NODE_NAME     J32 279
 '@S9S_MB_2U_LIB.S9S_MB_2U(SCH_1):PAGE113_I177@PURE_QUANTA.SCONN288_ADR50017P087CC(CHIPS)':
 'VSS122': CDS_PINID='VSS122';
NODE_NAME     J32 281
 '@S9S_MB_2U_LIB.S9S_MB_2U(SCH_1):PAGE113_I177@PURE_QUANTA.SCONN288_ADR50017P087CC(CHIPS)':
 'VSS123': CDS_PINID='VSS123';
NODE_NAME     J32 284
 '@S9S_MB_2U_LIB.S9S_MB_2U(SCH_1):PAGE113_I177@PURE_QUANTA.SCONN288_ADR50017P087CC(CHIPS)':
 'VSS124': CDS_PINID='VSS124';
NODE_NAME     J32 286
 '@S9S_MB_2U_LIB.S9S_MB_2U(SCH_1):PAGE113_I177@PURE_QUANTA.SCONN288_ADR50017P087CC(CHIPS)':
 'VSS125': CDS_PINID='VSS125';
NODE_NAME     J32 288
 '@S9S_MB_2U_LIB.S9S_MB_2U(SCH_1):PAGE113_I177@PURE_QUANTA.SCONN288_ADR50017P087CC(CHIPS)':
 'VSS126': CDS_PINID='VSS126';
NODE_NAME     R1241 2
 '@S9S_MB_2U_LIB.S9S_MB_2U(SCH_1):PAGE117_I17@PURE_QUANTA.Q_RES(CHIPS)':
 'B': CDS_PINID='B';
NODE_NAME     R1243 2
 '@S9S_MB_2U_LIB.S9S_MB_2U(SCH_1):PAGE117_I19@PURE_QUANTA.Q_RES(CHIPS)':
 'B': CDS_PINID='B';
NODE_NAME     R294 1
 '@S9S_MB_2U_LIB.S9S_MB_2U(SCH_1):PAGE119_I71@PURE_QUANTA.Q_RES(CHIPS)':
 'A': CDS_PINID='A';
NODE_NAME     R295 1
 '@S9S_MB_2U_LIB.S9S_MB_2U(SCH_1):PAGE119_I72@PURE_QUANTA.Q_RES(CHIPS)':
 'A': CDS_PINID='A';
NODE_NAME     R291 1
 '@S9S_MB_2U_LIB.S9S_MB_2U(SCH_1):PAGE119_I116@PURE_QUANTA.Q_RES(CHIPS)':
 'A': CDS_PINID='A';
NODE_NAME     R290 1
 '@S9S_MB_2U_LIB.S9S_MB_2U(SCH_1):PAGE119_I135@PURE_QUANTA.Q_RES(CHIPS)':
 'A': CDS_PINID='A';
NODE_NAME     R1237 1
 '@S9S_MB_2U_LIB.S9S_MB_2U(SCH_1):PAGE119_I160@PURE_QUANTA.Q_RES(CHIPS)':
 'A': CDS_PINID='A';
NODE_NAME     R1238 1
 '@S9S_MB_2U_LIB.S9S_MB_2U(SCH_1):PAGE119_I161@PURE_QUANTA.Q_RES(CHIPS)':
 'A': CDS_PINID='A';
NODE_NAME     R1239 1
 '@S9S_MB_2U_LIB.S9S_MB_2U(SCH_1):PAGE119_I163@PURE_QUANTA.Q_RES(CHIPS)':
 'A': CDS_PINID='A';
NODE_NAME     R3024 1
 '@S9S_MB_2U_LIB.S9S_MB_2U(SCH_1):PAGE119_I172@PURE_QUANTA.Q_RES(CHIPS)':
 'A': CDS_PINID='A';
NODE_NAME     R1235 1
 '@S9S_MB_2U_LIB.S9S_MB_2U(SCH_1):PAGE119_I176@PURE_QUANTA.Q_RES(CHIPS)':
 'A': CDS_PINID='A';
NODE_NAME     R1236 1
 '@S9S_MB_2U_LIB.S9S_MB_2U(SCH_1):PAGE119_I177@PURE_QUANTA.Q_RES(CHIPS)':
 'A': CDS_PINID='A';
NODE_NAME     R1391 1
 '@S9S_MB_2U_LIB.S9S_MB_2U(SCH_1):PAGE120_I61@PURE_QUANTA.Q_RES(CHIPS)':
 'A': CDS_PINID='A';
NODE_NAME     R1392 1
 '@S9S_MB_2U_LIB.S9S_MB_2U(SCH_1):PAGE120_I62@PURE_QUANTA.Q_RES(CHIPS)':
 'A': CDS_PINID='A';
NODE_NAME     R1393 1
 '@S9S_MB_2U_LIB.S9S_MB_2U(SCH_1):PAGE120_I66@PURE_QUANTA.Q_RES(CHIPS)':
 'A': CDS_PINID='A';
NODE_NAME     R1394 1
 '@S9S_MB_2U_LIB.S9S_MB_2U(SCH_1):PAGE120_I67@PURE_QUANTA.Q_RES(CHIPS)':
 'A': CDS_PINID='A';
NODE_NAME     R334 2
 '@S9S_MB_2U_LIB.S9S_MB_2U(SCH_1):PAGE127_I1@PURE_QUANTA.Q_RES(CHIPS)':
 'B': CDS_PINID='B';
NODE_NAME     R515 2
 '@S9S_MB_2U_LIB.S9S_MB_2U(SCH_1):PAGE127_I7@PURE_QUANTA.Q_RES(CHIPS)':
 'B': CDS_PINID='B';
NODE_NAME     R630 2
 '@S9S_MB_2U_LIB.S9S_MB_2U(SCH_1):PAGE127_I15@PURE_QUANTA.Q_RES(CHIPS)':
 'B': CDS_PINID='B';
NODE_NAME     R628 2
 '@S9S_MB_2U_LIB.S9S_MB_2U(SCH_1):PAGE127_I17@PURE_QUANTA.Q_RES(CHIPS)':
 'B': CDS_PINID='B';
NODE_NAME     R332 2
 '@S9S_MB_2U_LIB.S9S_MB_2U(SCH_1):PAGE127_I21@PURE_QUANTA.Q_RES(CHIPS)':
 'B': CDS_PINID='B';
NODE_NAME     R626 2
 '@S9S_MB_2U_LIB.S9S_MB_2U(SCH_1):PAGE127_I26@PURE_QUANTA.Q_RES(CHIPS)':
 'B': CDS_PINID='B';
NODE_NAME     R997 2
 '@S9S_MB_2U_LIB.S9S_MB_2U(SCH_1):PAGE127_I31@PURE_QUANTA.Q_RES(CHIPS)':
 'B': CDS_PINID='B';
NODE_NAME     R1005 2
 '@S9S_MB_2U_LIB.S9S_MB_2U(SCH_1):PAGE127_I36@PURE_QUANTA.Q_RES(CHIPS)':
 'B': CDS_PINID='B';
NODE_NAME     R938 2
 '@S9S_MB_2U_LIB.S9S_MB_2U(SCH_1):PAGE128_I77@PURE_QUANTA.Q_RES(CHIPS)':
 'B': CDS_PINID='B';
NODE_NAME     R936 2
 '@S9S_MB_2U_LIB.S9S_MB_2U(SCH_1):PAGE128_I78@PURE_QUANTA.Q_RES(CHIPS)':
 'B': CDS_PINID='B';
NODE_NAME     R934 2
 '@S9S_MB_2U_LIB.S9S_MB_2U(SCH_1):PAGE128_I79@PURE_QUANTA.Q_RES(CHIPS)':
 'B': CDS_PINID='B';
NODE_NAME     R932 2
 '@S9S_MB_2U_LIB.S9S_MB_2U(SCH_1):PAGE128_I80@PURE_QUANTA.Q_RES(CHIPS)':
 'B': CDS_PINID='B';
NODE_NAME     R933 2
 '@S9S_MB_2U_LIB.S9S_MB_2U(SCH_1):PAGE128_I82@PURE_QUANTA.Q_RES(CHIPS)':
 'B': CDS_PINID='B';
NODE_NAME     R939 2
 '@S9S_MB_2U_LIB.S9S_MB_2U(SCH_1):PAGE128_I83@PURE_QUANTA.Q_RES(CHIPS)':
 'B': CDS_PINID='B';
NODE_NAME     R937 2
 '@S9S_MB_2U_LIB.S9S_MB_2U(SCH_1):PAGE128_I85@PURE_QUANTA.Q_RES(CHIPS)':
 'B': CDS_PINID='B';
NODE_NAME     R935 2
 '@S9S_MB_2U_LIB.S9S_MB_2U(SCH_1):PAGE128_I86@PURE_QUANTA.Q_RES(CHIPS)':
 'B': CDS_PINID='B';
NODE_NAME     C622 2
 '@S9S_MB_2U_LIB.S9S_MB_2U(SCH_1):PAGE129_I91@PURE_QUANTA.Q_CAP(CHIPS)':
 'B': CDS_PINID='B';
NODE_NAME     C623 2
 '@S9S_MB_2U_LIB.S9S_MB_2U(SCH_1):PAGE129_I94@PURE_QUANTA.Q_CAP(CHIPS)':
 'B': CDS_PINID='B';
NODE_NAME     C624 2
 '@S9S_MB_2U_LIB.S9S_MB_2U(SCH_1):PAGE129_I99@PURE_QUANTA.Q_CAP(CHIPS)':
 'B': CDS_PINID='B';
NODE_NAME     C621 2
 '@S9S_MB_2U_LIB.S9S_MB_2U(SCH_1):PAGE129_I102@PURE_QUANTA.Q_CAP(CHIPS)':
 'B': CDS_PINID='B';
NODE_NAME     R706 2
 '@S9S_MB_2U_LIB.S9S_MB_2U(SCH_1):PAGE129_I103@PURE_QUANTA.Q_RES(CHIPS)':
 'B': CDS_PINID='B';
NODE_NAME     R707 2
 '@S9S_MB_2U_LIB.S9S_MB_2U(SCH_1):PAGE129_I106@PURE_QUANTA.Q_RES(CHIPS)':
 'B': CDS_PINID='B';
NODE_NAME     R708 2
 '@S9S_MB_2U_LIB.S9S_MB_2U(SCH_1):PAGE129_I109@PURE_QUANTA.Q_RES(CHIPS)':
 'B': CDS_PINID='B';
NODE_NAME     R705 2
 '@S9S_MB_2U_LIB.S9S_MB_2U(SCH_1):PAGE129_I112@PURE_QUANTA.Q_RES(CHIPS)':
 'B': CDS_PINID='B';
NODE_NAME     C616 2
 '@S9S_MB_2U_LIB.S9S_MB_2U(SCH_1):PAGE130_I59@PURE_QUANTA.Q_CAP(CHIPS)':
 'B': CDS_PINID='B';
NODE_NAME     C615 2
 '@S9S_MB_2U_LIB.S9S_MB_2U(SCH_1):PAGE130_I62@PURE_QUANTA.Q_CAP(CHIPS)':
 'B': CDS_PINID='B';
NODE_NAME     R701 2
 '@S9S_MB_2U_LIB.S9S_MB_2U(SCH_1):PAGE130_I63@PURE_QUANTA.Q_RES(CHIPS)':
 'B': CDS_PINID='B';
NODE_NAME     C614 2
 '@S9S_MB_2U_LIB.S9S_MB_2U(SCH_1):PAGE130_I65@PURE_QUANTA.Q_CAP(CHIPS)':
 'B': CDS_PINID='B';
NODE_NAME     C613 2
 '@S9S_MB_2U_LIB.S9S_MB_2U(SCH_1):PAGE130_I68@PURE_QUANTA.Q_CAP(CHIPS)':
 'B': CDS_PINID='B';
NODE_NAME     R704 2
 '@S9S_MB_2U_LIB.S9S_MB_2U(SCH_1):PAGE130_I75@PURE_QUANTA.Q_RES(CHIPS)':
 'B': CDS_PINID='B';
NODE_NAME     R702 2
 '@S9S_MB_2U_LIB.S9S_MB_2U(SCH_1):PAGE130_I76@PURE_QUANTA.Q_RES(CHIPS)':
 'B': CDS_PINID='B';
NODE_NAME     R703 2
 '@S9S_MB_2U_LIB.S9S_MB_2U(SCH_1):PAGE130_I79@PURE_QUANTA.Q_RES(CHIPS)':
 'B': CDS_PINID='B';
NODE_NAME     J42 14
 '@S9S_MB_2U_LIB.S9S_MB_2U(SCH_1):PAGE133_I44@PURE_QUANTA.SCONN60_ASP21410801(CHIPS)':
 '14': CDS_PINID='\14\';
NODE_NAME     J42 16
 '@S9S_MB_2U_LIB.S9S_MB_2U(SCH_1):PAGE133_I44@PURE_QUANTA.SCONN60_ASP21410801(CHIPS)':
 '16': CDS_PINID='\16\';
NODE_NAME     J42 57
 '@S9S_MB_2U_LIB.S9S_MB_2U(SCH_1):PAGE133_I44@PURE_QUANTA.SCONN60_ASP21410801(CHIPS)':
 '57': CDS_PINID='\57\';
NODE_NAME     J42 58
 '@S9S_MB_2U_LIB.S9S_MB_2U(SCH_1):PAGE133_I44@PURE_QUANTA.SCONN60_ASP21410801(CHIPS)':
 '58': CDS_PINID='\58\';
NODE_NAME     J42 60
 '@S9S_MB_2U_LIB.S9S_MB_2U(SCH_1):PAGE133_I44@PURE_QUANTA.SCONN60_ASP21410801(CHIPS)':
 '60': CDS_PINID='\60\';
NODE_NAME     J42 G1
 '@S9S_MB_2U_LIB.S9S_MB_2U(SCH_1):PAGE133_I44@PURE_QUANTA.SCONN60_ASP21410801(CHIPS)':
 'G1': CDS_PINID='G1';
NODE_NAME     J42 G2
 '@S9S_MB_2U_LIB.S9S_MB_2U(SCH_1):PAGE133_I44@PURE_QUANTA.SCONN60_ASP21410801(CHIPS)':
 'G2': CDS_PINID='G2';
NODE_NAME     J42 G3
 '@S9S_MB_2U_LIB.S9S_MB_2U(SCH_1):PAGE133_I44@PURE_QUANTA.SCONN60_ASP21410801(CHIPS)':
 'G3': CDS_PINID='G3';
NODE_NAME     J42 G4
 '@S9S_MB_2U_LIB.S9S_MB_2U(SCH_1):PAGE133_I44@PURE_QUANTA.SCONN60_ASP21410801(CHIPS)':
 'G4': CDS_PINID='G4';
NODE_NAME     C552 2
 '@S9S_MB_2U_LIB.S9S_MB_2U(SCH_1):PAGE133_I96@PURE_QUANTA.Q_CAP(CHIPS)':
 'B': CDS_PINID='B';
NODE_NAME     C550 2
 '@S9S_MB_2U_LIB.S9S_MB_2U(SCH_1):PAGE133_I99@PURE_QUANTA.Q_CAP(CHIPS)':
 'B': CDS_PINID='B';
NODE_NAME     C547 2
 '@S9S_MB_2U_LIB.S9S_MB_2U(SCH_1):PAGE133_I100@PURE_QUANTA.Q_CAP(CHIPS)':
 'B': CDS_PINID='B';
NODE_NAME     R769 2
 '@S9S_MB_2U_LIB.S9S_MB_2U(SCH_1):PAGE133_I102@PURE_QUANTA.Q_RES(CHIPS)':
 'B': CDS_PINID='B';
NODE_NAME     C551 2
 '@S9S_MB_2U_LIB.S9S_MB_2U(SCH_1):PAGE133_I105@PURE_QUANTA.Q_CAP(CHIPS)':
 'B': CDS_PINID='B';
NODE_NAME     C549 2
 '@S9S_MB_2U_LIB.S9S_MB_2U(SCH_1):PAGE133_I129@PURE_QUANTA.Q_CAP(CHIPS)':
 'B': CDS_PINID='B';
NODE_NAME     C548 2
 '@S9S_MB_2U_LIB.S9S_MB_2U(SCH_1):PAGE133_I130@PURE_QUANTA.Q_CAP(CHIPS)':
 'B': CDS_PINID='B';
NODE_NAME     R774 2
 '@S9S_MB_2U_LIB.S9S_MB_2U(SCH_1):PAGE133_I132@PURE_QUANTA.Q_RES(CHIPS)':
 'B': CDS_PINID='B';
NODE_NAME     U17 7
 '@S9S_MB_2U_LIB.S9S_MB_2U(SCH_1):PAGE134_I80@PURE_QUANTA.74CBTLV3126PW(CHIPS)':
 'GND': CDS_PINID='GND';
NODE_NAME     R746 2
 '@S9S_MB_2U_LIB.S9S_MB_2U(SCH_1):PAGE134_I90@PURE_QUANTA.Q_RES(CHIPS)':
 'B': CDS_PINID='B';
NODE_NAME     C545 2
 '@S9S_MB_2U_LIB.S9S_MB_2U(SCH_1):PAGE134_I93@PURE_QUANTA.Q_CAP(CHIPS)':
 'B': CDS_PINID='B';
NODE_NAME     U18 7
 '@S9S_MB_2U_LIB.S9S_MB_2U(SCH_1):PAGE134_I129@PURE_QUANTA.74CBTLV3126PW(CHIPS)':
 'GND': CDS_PINID='GND';
NODE_NAME     C546 2
 '@S9S_MB_2U_LIB.S9S_MB_2U(SCH_1):PAGE134_I135@PURE_QUANTA.Q_CAP(CHIPS)':
 'B': CDS_PINID='B';
NODE_NAME     U21 2
 '@S9S_MB_2U_LIB.S9S_MB_2U(SCH_1):PAGE135_I58@PURE_QUANTA.NC7SB3157(CHIPS)':
 'GND': CDS_PINID='GND';
NODE_NAME     C541 2
 '@S9S_MB_2U_LIB.S9S_MB_2U(SCH_1):PAGE135_I61@PURE_QUANTA.Q_CAP(CHIPS)':
 'B': CDS_PINID='B';
NODE_NAME     C539 2
 '@S9S_MB_2U_LIB.S9S_MB_2U(SCH_1):PAGE135_I70@PURE_QUANTA.Q_CAP(CHIPS)':
 'B': CDS_PINID='B';
NODE_NAME     U22 2
 '@S9S_MB_2U_LIB.S9S_MB_2U(SCH_1):PAGE135_I71@PURE_QUANTA.NC7SB3157(CHIPS)':
 'GND': CDS_PINID='GND';
NODE_NAME     C542 2
 '@S9S_MB_2U_LIB.S9S_MB_2U(SCH_1):PAGE135_I80@PURE_QUANTA.Q_CAP(CHIPS)':
 'B': CDS_PINID='B';
NODE_NAME     C540 2
 '@S9S_MB_2U_LIB.S9S_MB_2U(SCH_1):PAGE135_I81@PURE_QUANTA.Q_CAP(CHIPS)':
 'B': CDS_PINID='B';
NODE_NAME     C544 2
 '@S9S_MB_2U_LIB.S9S_MB_2U(SCH_1):PAGE135_I94@PURE_QUANTA.Q_CAP(CHIPS)':
 'B': CDS_PINID='B';
NODE_NAME     U23 3
 '@S9S_MB_2U_LIB.S9S_MB_2U(SCH_1):PAGE135_I96@PURE_QUANTA.74LVC1G02GW(CHIPS)':
 'GND': CDS_PINID='GND';
NODE_NAME     C543 2
 '@S9S_MB_2U_LIB.S9S_MB_2U(SCH_1):PAGE135_I100@PURE_QUANTA.Q_CAP(CHIPS)':
 'B': CDS_PINID='B';
NODE_NAME     U86 7
 '@S9S_MB_2U_LIB.S9S_MB_2U(SCH_1):PAGE137_I84@PURE_QUANTA.74CBTLV3126PW(CHIPS)':
 'GND': CDS_PINID='GND';
NODE_NAME     C1292 2
 '@S9S_MB_2U_LIB.S9S_MB_2U(SCH_1):PAGE137_I90@PURE_QUANTA.Q_CAP(CHIPS)':
 'B': CDS_PINID='B';
NODE_NAME     C1293 2
 '@S9S_MB_2U_LIB.S9S_MB_2U(SCH_1):PAGE137_I95@PURE_QUANTA.Q_CAP(CHIPS)':
 'B': CDS_PINID='B';
NODE_NAME     R1375 2
 '@S9S_MB_2U_LIB.S9S_MB_2U(SCH_1):PAGE137_I97@PURE_QUANTA.Q_RES(CHIPS)':
 'B': CDS_PINID='B';
NODE_NAME     R3025 2
 '@S9S_MB_2U_LIB.S9S_MB_2U(SCH_1):PAGE137_I102@PURE_QUANTA.Q_RES(CHIPS)':
 'B': CDS_PINID='B';
NODE_NAME     R1374 2
 '@S9S_MB_2U_LIB.S9S_MB_2U(SCH_1):PAGE137_I103@PURE_QUANTA.Q_RES(CHIPS)':
 'B': CDS_PINID='B';
NODE_NAME     R3027 2
 '@S9S_MB_2U_LIB.S9S_MB_2U(SCH_1):PAGE137_I105@PURE_QUANTA.Q_RES(CHIPS)':
 'B': CDS_PINID='B';
NODE_NAME     R3026 2
 '@S9S_MB_2U_LIB.S9S_MB_2U(SCH_1):PAGE137_I106@PURE_QUANTA.Q_RES(CHIPS)':
 'B': CDS_PINID='B';
NODE_NAME     U85 2
 '@S9S_MB_2U_LIB.S9S_MB_2U(SCH_1):PAGE137_I109@PURE_QUANTA.NC7SB3157(CHIPS)':
 'GND': CDS_PINID='GND';
NODE_NAME     C1289 2
 '@S9S_MB_2U_LIB.S9S_MB_2U(SCH_1):PAGE137_I110@PURE_QUANTA.Q_CAP(CHIPS)':
 'B': CDS_PINID='B';
NODE_NAME     C1288 2
 '@S9S_MB_2U_LIB.S9S_MB_2U(SCH_1):PAGE137_I112@PURE_QUANTA.Q_CAP(CHIPS)':
 'B': CDS_PINID='B';
NODE_NAME     R1365 2
 '@S9S_MB_2U_LIB.S9S_MB_2U(SCH_1):PAGE137_I116@PURE_QUANTA.Q_RES(CHIPS)':
 'B': CDS_PINID='B';
NODE_NAME     R1353 2
 '@S9S_MB_2U_LIB.S9S_MB_2U(SCH_1):PAGE151_I56@PURE_QUANTA.Q_RES(CHIPS)':
 'B': CDS_PINID='B';
NODE_NAME     U75 3
 '@S9S_MB_2U_LIB.S9S_MB_2U(SCH_1):PAGE152_I1@PURE_QUANTA.74LVC1G17GW(CHIPS)':
 'GND': CDS_PINID='GND';
NODE_NAME     C1173 2
 '@S9S_MB_2U_LIB.S9S_MB_2U(SCH_1):PAGE152_I4@PURE_QUANTA.Q_CAP(CHIPS)':
 'B': CDS_PINID='B';
NODE_NAME     C1175 2
 '@S9S_MB_2U_LIB.S9S_MB_2U(SCH_1):PAGE152_I24@PURE_QUANTA.Q_CAP(CHIPS)':
 'B': CDS_PINID='B';
NODE_NAME     C188 2
 '@S9S_MB_2U_LIB.S9S_MB_2U(SCH_1):PAGE152_I44@PURE_QUANTA.Q_CAP(CHIPS)':
 'B': CDS_PINID='B';
NODE_NAME     U90 4
 '@S9S_MB_2U_LIB.S9S_MB_2U(SCH_1):PAGE152_I46@PURE_QUANTA.PI6CV304LE(CHIPS)':
 'GND': CDS_PINID='GND';
NODE_NAME     C1275 2
 '@S9S_MB_2U_LIB.S9S_MB_2U(SCH_1):PAGE152_I49@PURE_QUANTA.Q_CAP(CHIPS)':
 'B': CDS_PINID='B';
NODE_NAME     C1274 2
 '@S9S_MB_2U_LIB.S9S_MB_2U(SCH_1):PAGE152_I59@PURE_QUANTA.Q_CAP(CHIPS)':
 'B': CDS_PINID='B';
NODE_NAME     U104 3
 '@S9S_MB_2U_LIB.S9S_MB_2U(SCH_1):PAGE152_I63@PURE_QUANTA.74LVC1G07GV(CHIPS)':
 'GND': CDS_PINID='GND';
NODE_NAME     U157 3
 '@S9S_MB_2U_LIB.S9S_MB_2U(SCH_1):PAGE152_I65@PURE_QUANTA.74LVC1G07GV(CHIPS)':
 'GND': CDS_PINID='GND';
NODE_NAME     C1663 2
 '@S9S_MB_2U_LIB.S9S_MB_2U(SCH_1):PAGE152_I68@PURE_QUANTA.Q_CAP(CHIPS)':
 'B': CDS_PINID='B';
NODE_NAME     R1128 2
 '@S9S_MB_2U_LIB.S9S_MB_2U(SCH_1):PAGE154_I137@PURE_QUANTA.Q_RES(CHIPS)':
 'B': CDS_PINID='B';
NODE_NAME     R1126 2
 '@S9S_MB_2U_LIB.S9S_MB_2U(SCH_1):PAGE154_I140@PURE_QUANTA.Q_RES(CHIPS)':
 'B': CDS_PINID='B';
NODE_NAME     R1124 2
 '@S9S_MB_2U_LIB.S9S_MB_2U(SCH_1):PAGE154_I143@PURE_QUANTA.Q_RES(CHIPS)':
 'B': CDS_PINID='B';
NODE_NAME     C581 2
 '@S9S_MB_2U_LIB.S9S_MB_2U(SCH_1):PAGE154_I148@PURE_QUANTA.Q_CAP(CHIPS)':
 'B': CDS_PINID='B';
NODE_NAME     C578 2
 '@S9S_MB_2U_LIB.S9S_MB_2U(SCH_1):PAGE154_I169@PURE_QUANTA.Q_CAP(CHIPS)':
 'B': CDS_PINID='B';
NODE_NAME     U49 S
 '@S9S_MB_2U_LIB.S9S_MB_2U(SCH_1):PAGE154_I177@PURE_QUANTA.MOSFET_N(CHIPS)':
 'SOURCE': CDS_PINID='SOURCE';
NODE_NAME     C1507 2
 '@S9S_MB_2U_LIB.S9S_MB_2U(SCH_1):PAGE171_I10@PURE_QUANTA.Q_CAP(CHIPS)':
 'B': CDS_PINID='B';
NODE_NAME     C1508 2
 '@S9S_MB_2U_LIB.S9S_MB_2U(SCH_1):PAGE171_I17@PURE_QUANTA.Q_CAP(CHIPS)':
 'B': CDS_PINID='B';
NODE_NAME     R477 2
 '@S9S_MB_2U_LIB.S9S_MB_2U(SCH_1):PAGE171_I69@PURE_QUANTA.Q_RES(CHIPS)':
 'B': CDS_PINID='B';
NODE_NAME     Y7 2
 '@S9S_MB_2U_LIB.S9S_MB_2U(SCH_1):PAGE171_I75@PURE_QUANTA.Q_XTAL_4P_13BI_24GND(CHIPS)':
 'G1': CDS_PINID='G1';
NODE_NAME     Y7 4
 '@S9S_MB_2U_LIB.S9S_MB_2U(SCH_1):PAGE171_I75@PURE_QUANTA.Q_XTAL_4P_13BI_24GND(CHIPS)':
 'G2': CDS_PINID='G2';
NODE_NAME     C104 2
 '@S9S_MB_2U_LIB.S9S_MB_2U(SCH_1):PAGE171_I76@PURE_QUANTA.Q_CAP(CHIPS)':
 'B': CDS_PINID='B';
NODE_NAME     C103 2
 '@S9S_MB_2U_LIB.S9S_MB_2U(SCH_1):PAGE171_I77@PURE_QUANTA.Q_CAP(CHIPS)':
 'B': CDS_PINID='B';
NODE_NAME     C609 2
 '@S9S_MB_2U_LIB.S9S_MB_2U(SCH_1):PAGE171_I89@PURE_QUANTA.Q_CAP(CHIPS)':
 'B': CDS_PINID='B';
NODE_NAME     R496 2
 '@S9S_MB_2U_LIB.S9S_MB_2U(SCH_1):PAGE172_I10@PURE_QUANTA.Q_RES(CHIPS)':
 'B': CDS_PINID='B';
NODE_NAME     R1025 2
 '@S9S_MB_2U_LIB.S9S_MB_2U(SCH_1):PAGE174_I38@PURE_QUANTA.Q_RES(CHIPS)':
 'B': CDS_PINID='B';
NODE_NAME     R1024 2
 '@S9S_MB_2U_LIB.S9S_MB_2U(SCH_1):PAGE174_I41@PURE_QUANTA.Q_RES(CHIPS)':
 'B': CDS_PINID='B';
NODE_NAME     R1197 1
 '@S9S_MB_2U_LIB.S9S_MB_2U(SCH_1):PAGE174_I50@PURE_QUANTA.Q_RES(CHIPS)':
 'A': CDS_PINID='A';
NODE_NAME     R1676 2
 '@S9S_MB_2U_LIB.S9S_MB_2U(SCH_1):PAGE174_I94@PURE_QUANTA.Q_RES(CHIPS)':
 'B': CDS_PINID='B';
NODE_NAME     R1487 2
 '@S9S_MB_2U_LIB.S9S_MB_2U(SCH_1):PAGE175_I125@PURE_QUANTA.Q_RES(CHIPS)':
 'B': CDS_PINID='B';
NODE_NAME     R1269 2
 '@S9S_MB_2U_LIB.S9S_MB_2U(SCH_1):PAGE175_I225@PURE_QUANTA.Q_RES(CHIPS)':
 'B': CDS_PINID='B';
NODE_NAME     JP4 2
 '@S9S_MB_2U_LIB.S9S_MB_2U(SCH_1):PAGE175_I256@PURE_QUANTA.CONN3_210HP1030BR1(CHIPS)':
 '2': CDS_PINID='\2\';
NODE_NAME     JP9 2
 '@S9S_MB_2U_LIB.S9S_MB_2U(SCH_1):PAGE175_I263@PURE_QUANTA.CONN3_210HP1030BR1(CHIPS)':
 '2': CDS_PINID='\2\';
NODE_NAME     R2509 2
 '@S9S_MB_2U_LIB.S9S_MB_2U(SCH_1):PAGE176_I174@PURE_QUANTA.Q_RES(CHIPS)':
 'B': CDS_PINID='B';
NODE_NAME     R2511 2
 '@S9S_MB_2U_LIB.S9S_MB_2U(SCH_1):PAGE176_I176@PURE_QUANTA.Q_RES(CHIPS)':
 'B': CDS_PINID='B';
NODE_NAME     BT1 2
 '@S9S_MB_2U_LIB.S9S_MB_2U(SCH_1):PAGE177_I63@PURE_QUANTA.CONN2_AAABAT029Y19(CHIPS)':
 '2': CDS_PINID='\2\';
NODE_NAME     C611 2
 '@S9S_MB_2U_LIB.S9S_MB_2U(SCH_1):PAGE177_I65@PURE_QUANTA.Q_CAP(CHIPS)':
 'B': CDS_PINID='B';
NODE_NAME     C610 2
 '@S9S_MB_2U_LIB.S9S_MB_2U(SCH_1):PAGE177_I68@PURE_QUANTA.Q_CAP(CHIPS)':
 'B': CDS_PINID='B';
NODE_NAME     U4 BG40
 '@S9S_MB_2U_LIB.S9S_MB_2U(SCH_1):PAGE178_I11@PURE_QUANTA.EMMITSBURG_REV0P9(CHIPS)':
 'VSS_BG40': CDS_PINID='VSS_BG40';
NODE_NAME     R497 2
 '@S9S_MB_2U_LIB.S9S_MB_2U(SCH_1):PAGE179_I2@PURE_QUANTA.Q_RES(CHIPS)':
 'B': CDS_PINID='B';
NODE_NAME     U4 AY3
 '@S9S_MB_2U_LIB.S9S_MB_2U(SCH_1):PAGE180_I7@PURE_QUANTA.EMMITSBURG_REV0P9(CHIPS)':
 'VSS_AY3': CDS_PINID='VSS_AY3';
NODE_NAME     U4 AY5
 '@S9S_MB_2U_LIB.S9S_MB_2U(SCH_1):PAGE180_I7@PURE_QUANTA.EMMITSBURG_REV0P9(CHIPS)':
 'VSS_AY5': CDS_PINID='VSS_AY5';
NODE_NAME     U4 AY8
 '@S9S_MB_2U_LIB.S9S_MB_2U(SCH_1):PAGE180_I7@PURE_QUANTA.EMMITSBURG_REV0P9(CHIPS)':
 'VSS_AY8': CDS_PINID='VSS_AY8';
NODE_NAME     U4 AY28
 '@S9S_MB_2U_LIB.S9S_MB_2U(SCH_1):PAGE180_I7@PURE_QUANTA.EMMITSBURG_REV0P9(CHIPS)':
 'VSS_AY28': CDS_PINID='VSS_AY28';
NODE_NAME     U4 AY31
 '@S9S_MB_2U_LIB.S9S_MB_2U(SCH_1):PAGE180_I7@PURE_QUANTA.EMMITSBURG_REV0P9(CHIPS)':
 'VSS_AY31': CDS_PINID='VSS_AY31';
NODE_NAME     U4 AY34
 '@S9S_MB_2U_LIB.S9S_MB_2U(SCH_1):PAGE180_I7@PURE_QUANTA.EMMITSBURG_REV0P9(CHIPS)':
 'VSS_AY34': CDS_PINID='VSS_AY34';
NODE_NAME     U4 AY37
 '@S9S_MB_2U_LIB.S9S_MB_2U(SCH_1):PAGE180_I7@PURE_QUANTA.EMMITSBURG_REV0P9(CHIPS)':
 'VSS_AY37': CDS_PINID='VSS_AY37';
NODE_NAME     U4 AY39
 '@S9S_MB_2U_LIB.S9S_MB_2U(SCH_1):PAGE180_I7@PURE_QUANTA.EMMITSBURG_REV0P9(CHIPS)':
 'VSS_AY39': CDS_PINID='VSS_AY39';
NODE_NAME     U4 B9
 '@S9S_MB_2U_LIB.S9S_MB_2U(SCH_1):PAGE180_I7@PURE_QUANTA.EMMITSBURG_REV0P9(CHIPS)':
 'VSS_B9': CDS_PINID='VSS_B9';
NODE_NAME     U4 B13
 '@S9S_MB_2U_LIB.S9S_MB_2U(SCH_1):PAGE180_I7@PURE_QUANTA.EMMITSBURG_REV0P9(CHIPS)':
 'VSS_B13': CDS_PINID='VSS_B13';
NODE_NAME     U4 B29
 '@S9S_MB_2U_LIB.S9S_MB_2U(SCH_1):PAGE180_I7@PURE_QUANTA.EMMITSBURG_REV0P9(CHIPS)':
 'VSS_B29': CDS_PINID='VSS_B29';
NODE_NAME     U4 B39
 '@S9S_MB_2U_LIB.S9S_MB_2U(SCH_1):PAGE180_I7@PURE_QUANTA.EMMITSBURG_REV0P9(CHIPS)':
 'VSS_B39': CDS_PINID='VSS_B39';
NODE_NAME     U4 BB5
 '@S9S_MB_2U_LIB.S9S_MB_2U(SCH_1):PAGE180_I7@PURE_QUANTA.EMMITSBURG_REV0P9(CHIPS)':
 'VSS_BB5': CDS_PINID='VSS_BB5';
NODE_NAME     U4 BB39
 '@S9S_MB_2U_LIB.S9S_MB_2U(SCH_1):PAGE180_I7@PURE_QUANTA.EMMITSBURG_REV0P9(CHIPS)':
 'VSS_BB39': CDS_PINID='VSS_BB39';
NODE_NAME     U4 BC6
 '@S9S_MB_2U_LIB.S9S_MB_2U(SCH_1):PAGE180_I7@PURE_QUANTA.EMMITSBURG_REV0P9(CHIPS)':
 'VSS_BC6': CDS_PINID='VSS_BC6';
NODE_NAME     U4 BC8
 '@S9S_MB_2U_LIB.S9S_MB_2U(SCH_1):PAGE180_I7@PURE_QUANTA.EMMITSBURG_REV0P9(CHIPS)':
 'VSS_BC8': CDS_PINID='VSS_BC8';
NODE_NAME     U4 BC10
 '@S9S_MB_2U_LIB.S9S_MB_2U(SCH_1):PAGE180_I7@PURE_QUANTA.EMMITSBURG_REV0P9(CHIPS)':
 'VSS_BC10': CDS_PINID='VSS_BC10';
NODE_NAME     U4 BC12
 '@S9S_MB_2U_LIB.S9S_MB_2U(SCH_1):PAGE180_I7@PURE_QUANTA.EMMITSBURG_REV0P9(CHIPS)':
 'VSS_BC12': CDS_PINID='VSS_BC12';
NODE_NAME     U4 BC14
 '@S9S_MB_2U_LIB.S9S_MB_2U(SCH_1):PAGE180_I7@PURE_QUANTA.EMMITSBURG_REV0P9(CHIPS)':
 'VSS_BC14': CDS_PINID='VSS_BC14';
NODE_NAME     U4 BC16
 '@S9S_MB_2U_LIB.S9S_MB_2U(SCH_1):PAGE180_I7@PURE_QUANTA.EMMITSBURG_REV0P9(CHIPS)':
 'VSS_BC16': CDS_PINID='VSS_BC16';
NODE_NAME     U4 BC18
 '@S9S_MB_2U_LIB.S9S_MB_2U(SCH_1):PAGE180_I7@PURE_QUANTA.EMMITSBURG_REV0P9(CHIPS)':
 'VSS_BC18': CDS_PINID='VSS_BC18';
NODE_NAME     U4 BC20
 '@S9S_MB_2U_LIB.S9S_MB_2U(SCH_1):PAGE180_I7@PURE_QUANTA.EMMITSBURG_REV0P9(CHIPS)':
 'VSS_BC20': CDS_PINID='VSS_BC20';
NODE_NAME     U4 BC22
 '@S9S_MB_2U_LIB.S9S_MB_2U(SCH_1):PAGE180_I7@PURE_QUANTA.EMMITSBURG_REV0P9(CHIPS)':
 'VSS_BC22': CDS_PINID='VSS_BC22';
NODE_NAME     U4 BC24
 '@S9S_MB_2U_LIB.S9S_MB_2U(SCH_1):PAGE180_I7@PURE_QUANTA.EMMITSBURG_REV0P9(CHIPS)':
 'VSS_BC24': CDS_PINID='VSS_BC24';
NODE_NAME     U4 BC26
 '@S9S_MB_2U_LIB.S9S_MB_2U(SCH_1):PAGE180_I7@PURE_QUANTA.EMMITSBURG_REV0P9(CHIPS)':
 'VSS_BC26': CDS_PINID='VSS_BC26';
NODE_NAME     U4 BC28
 '@S9S_MB_2U_LIB.S9S_MB_2U(SCH_1):PAGE180_I7@PURE_QUANTA.EMMITSBURG_REV0P9(CHIPS)':
 'VSS_BC28': CDS_PINID='VSS_BC28';
NODE_NAME     U4 BC30
 '@S9S_MB_2U_LIB.S9S_MB_2U(SCH_1):PAGE180_I7@PURE_QUANTA.EMMITSBURG_REV0P9(CHIPS)':
 'VSS_BC30': CDS_PINID='VSS_BC30';
NODE_NAME     U4 BC32
 '@S9S_MB_2U_LIB.S9S_MB_2U(SCH_1):PAGE180_I7@PURE_QUANTA.EMMITSBURG_REV0P9(CHIPS)':
 'VSS_BC32': CDS_PINID='VSS_BC32';
NODE_NAME     U4 BC34
 '@S9S_MB_2U_LIB.S9S_MB_2U(SCH_1):PAGE180_I7@PURE_QUANTA.EMMITSBURG_REV0P9(CHIPS)':
 'VSS_BC34': CDS_PINID='VSS_BC34';
NODE_NAME     U4 BC36
 '@S9S_MB_2U_LIB.S9S_MB_2U(SCH_1):PAGE180_I7@PURE_QUANTA.EMMITSBURG_REV0P9(CHIPS)':
 'VSS_BC36': CDS_PINID='VSS_BC36';
NODE_NAME     U4 BC38
 '@S9S_MB_2U_LIB.S9S_MB_2U(SCH_1):PAGE180_I7@PURE_QUANTA.EMMITSBURG_REV0P9(CHIPS)':
 'VSS_BC38': CDS_PINID='VSS_BC38';
NODE_NAME     U4 BD5
 '@S9S_MB_2U_LIB.S9S_MB_2U(SCH_1):PAGE180_I7@PURE_QUANTA.EMMITSBURG_REV0P9(CHIPS)':
 'VSS_BD5': CDS_PINID='VSS_BD5';
NODE_NAME     U4 BD21
 '@S9S_MB_2U_LIB.S9S_MB_2U(SCH_1):PAGE180_I7@PURE_QUANTA.EMMITSBURG_REV0P9(CHIPS)':
 'VSS_BD21': CDS_PINID='VSS_BD21';
NODE_NAME     U4 BD39
 '@S9S_MB_2U_LIB.S9S_MB_2U(SCH_1):PAGE180_I7@PURE_QUANTA.EMMITSBURG_REV0P9(CHIPS)':
 'VSS_BD39': CDS_PINID='VSS_BD39';
NODE_NAME     U4 BE10
 '@S9S_MB_2U_LIB.S9S_MB_2U(SCH_1):PAGE180_I7@PURE_QUANTA.EMMITSBURG_REV0P9(CHIPS)':
 'VSS_BE10': CDS_PINID='VSS_BE10';
NODE_NAME     U4 BE34
 '@S9S_MB_2U_LIB.S9S_MB_2U(SCH_1):PAGE180_I7@PURE_QUANTA.EMMITSBURG_REV0P9(CHIPS)':
 'VSS_BE34': CDS_PINID='VSS_BE34';
NODE_NAME     U4 BF21
 '@S9S_MB_2U_LIB.S9S_MB_2U(SCH_1):PAGE180_I7@PURE_QUANTA.EMMITSBURG_REV0P9(CHIPS)':
 'VSS_BF21': CDS_PINID='VSS_BF21';
NODE_NAME     U4 BG10
 '@S9S_MB_2U_LIB.S9S_MB_2U(SCH_1):PAGE180_I7@PURE_QUANTA.EMMITSBURG_REV0P9(CHIPS)':
 'VSS_BG10': CDS_PINID='VSS_BG10';
NODE_NAME     U4 BG34
 '@S9S_MB_2U_LIB.S9S_MB_2U(SCH_1):PAGE180_I7@PURE_QUANTA.EMMITSBURG_REV0P9(CHIPS)':
 'VSS_BG34': CDS_PINID='VSS_BG34';
NODE_NAME     U4 C4
 '@S9S_MB_2U_LIB.S9S_MB_2U(SCH_1):PAGE180_I7@PURE_QUANTA.EMMITSBURG_REV0P9(CHIPS)':
 'VSS_C4': CDS_PINID='VSS_C4';
NODE_NAME     U4 C20
 '@S9S_MB_2U_LIB.S9S_MB_2U(SCH_1):PAGE180_I7@PURE_QUANTA.EMMITSBURG_REV0P9(CHIPS)':
 'VSS_C20': CDS_PINID='VSS_C20';
NODE_NAME     U4 C22
 '@S9S_MB_2U_LIB.S9S_MB_2U(SCH_1):PAGE180_I7@PURE_QUANTA.EMMITSBURG_REV0P9(CHIPS)':
 'VSS_C22': CDS_PINID='VSS_C22';
NODE_NAME     U4 C24
 '@S9S_MB_2U_LIB.S9S_MB_2U(SCH_1):PAGE180_I7@PURE_QUANTA.EMMITSBURG_REV0P9(CHIPS)':
 'VSS_C24': CDS_PINID='VSS_C24';
NODE_NAME     U4 C26
 '@S9S_MB_2U_LIB.S9S_MB_2U(SCH_1):PAGE180_I7@PURE_QUANTA.EMMITSBURG_REV0P9(CHIPS)':
 'VSS_C26': CDS_PINID='VSS_C26';
NODE_NAME     U4 C38
 '@S9S_MB_2U_LIB.S9S_MB_2U(SCH_1):PAGE180_I7@PURE_QUANTA.EMMITSBURG_REV0P9(CHIPS)':
 'VSS_C38': CDS_PINID='VSS_C38';
NODE_NAME     U4 D5
 '@S9S_MB_2U_LIB.S9S_MB_2U(SCH_1):PAGE180_I7@PURE_QUANTA.EMMITSBURG_REV0P9(CHIPS)':
 'VSS_D5': CDS_PINID='VSS_D5';
NODE_NAME     U4 D9
 '@S9S_MB_2U_LIB.S9S_MB_2U(SCH_1):PAGE180_I7@PURE_QUANTA.EMMITSBURG_REV0P9(CHIPS)':
 'VSS_D9': CDS_PINID='VSS_D9';
NODE_NAME     U4 D13
 '@S9S_MB_2U_LIB.S9S_MB_2U(SCH_1):PAGE180_I7@PURE_QUANTA.EMMITSBURG_REV0P9(CHIPS)':
 'VSS_D13': CDS_PINID='VSS_D13';
NODE_NAME     U4 D29
 '@S9S_MB_2U_LIB.S9S_MB_2U(SCH_1):PAGE180_I7@PURE_QUANTA.EMMITSBURG_REV0P9(CHIPS)':
 'VSS_D29': CDS_PINID='VSS_D29';
NODE_NAME     U4 E6
 '@S9S_MB_2U_LIB.S9S_MB_2U(SCH_1):PAGE180_I7@PURE_QUANTA.EMMITSBURG_REV0P9(CHIPS)':
 'VSS_E6': CDS_PINID='VSS_E6';
NODE_NAME     U4 E8
 '@S9S_MB_2U_LIB.S9S_MB_2U(SCH_1):PAGE180_I7@PURE_QUANTA.EMMITSBURG_REV0P9(CHIPS)':
 'VSS_E8': CDS_PINID='VSS_E8';
NODE_NAME     U4 E10
 '@S9S_MB_2U_LIB.S9S_MB_2U(SCH_1):PAGE180_I7@PURE_QUANTA.EMMITSBURG_REV0P9(CHIPS)':
 'VSS_E10': CDS_PINID='VSS_E10';
NODE_NAME     U4 E12
 '@S9S_MB_2U_LIB.S9S_MB_2U(SCH_1):PAGE180_I7@PURE_QUANTA.EMMITSBURG_REV0P9(CHIPS)':
 'VSS_E12': CDS_PINID='VSS_E12';
NODE_NAME     U4 E14
 '@S9S_MB_2U_LIB.S9S_MB_2U(SCH_1):PAGE180_I7@PURE_QUANTA.EMMITSBURG_REV0P9(CHIPS)':
 'VSS_E14': CDS_PINID='VSS_E14';
NODE_NAME     U4 E16
 '@S9S_MB_2U_LIB.S9S_MB_2U(SCH_1):PAGE180_I7@PURE_QUANTA.EMMITSBURG_REV0P9(CHIPS)':
 'VSS_E16': CDS_PINID='VSS_E16';
NODE_NAME     U4 E18
 '@S9S_MB_2U_LIB.S9S_MB_2U(SCH_1):PAGE180_I7@PURE_QUANTA.EMMITSBURG_REV0P9(CHIPS)':
 'VSS_E18': CDS_PINID='VSS_E18';
NODE_NAME     U4 E20
 '@S9S_MB_2U_LIB.S9S_MB_2U(SCH_1):PAGE180_I7@PURE_QUANTA.EMMITSBURG_REV0P9(CHIPS)':
 'VSS_E20': CDS_PINID='VSS_E20';
NODE_NAME     U4 E22
 '@S9S_MB_2U_LIB.S9S_MB_2U(SCH_1):PAGE180_I7@PURE_QUANTA.EMMITSBURG_REV0P9(CHIPS)':
 'VSS_E22': CDS_PINID='VSS_E22';
NODE_NAME     U4 E24
 '@S9S_MB_2U_LIB.S9S_MB_2U(SCH_1):PAGE180_I7@PURE_QUANTA.EMMITSBURG_REV0P9(CHIPS)':
 'VSS_E24': CDS_PINID='VSS_E24';
NODE_NAME     U4 E26
 '@S9S_MB_2U_LIB.S9S_MB_2U(SCH_1):PAGE180_I7@PURE_QUANTA.EMMITSBURG_REV0P9(CHIPS)':
 'VSS_E26': CDS_PINID='VSS_E26';
NODE_NAME     U4 E28
 '@S9S_MB_2U_LIB.S9S_MB_2U(SCH_1):PAGE180_I7@PURE_QUANTA.EMMITSBURG_REV0P9(CHIPS)':
 'VSS_E28': CDS_PINID='VSS_E28';
NODE_NAME     U4 E30
 '@S9S_MB_2U_LIB.S9S_MB_2U(SCH_1):PAGE180_I7@PURE_QUANTA.EMMITSBURG_REV0P9(CHIPS)':
 'VSS_E30': CDS_PINID='VSS_E30';
NODE_NAME     U4 E32
 '@S9S_MB_2U_LIB.S9S_MB_2U(SCH_1):PAGE180_I7@PURE_QUANTA.EMMITSBURG_REV0P9(CHIPS)':
 'VSS_E32': CDS_PINID='VSS_E32';
NODE_NAME     U4 E34
 '@S9S_MB_2U_LIB.S9S_MB_2U(SCH_1):PAGE180_I7@PURE_QUANTA.EMMITSBURG_REV0P9(CHIPS)':
 'VSS_E34': CDS_PINID='VSS_E34';
NODE_NAME     U4 E36
 '@S9S_MB_2U_LIB.S9S_MB_2U(SCH_1):PAGE180_I7@PURE_QUANTA.EMMITSBURG_REV0P9(CHIPS)':
 'VSS_E36': CDS_PINID='VSS_E36';
NODE_NAME     U4 E38
 '@S9S_MB_2U_LIB.S9S_MB_2U(SCH_1):PAGE180_I7@PURE_QUANTA.EMMITSBURG_REV0P9(CHIPS)':
 'VSS_E38': CDS_PINID='VSS_E38';
NODE_NAME     U4 E40
 '@S9S_MB_2U_LIB.S9S_MB_2U(SCH_1):PAGE180_I7@PURE_QUANTA.EMMITSBURG_REV0P9(CHIPS)':
 'VSS_E40': CDS_PINID='VSS_E40';
NODE_NAME     U4 F15
 '@S9S_MB_2U_LIB.S9S_MB_2U(SCH_1):PAGE180_I7@PURE_QUANTA.EMMITSBURG_REV0P9(CHIPS)':
 'VSS_F15': CDS_PINID='VSS_F15';
NODE_NAME     U4 F24
 '@S9S_MB_2U_LIB.S9S_MB_2U(SCH_1):PAGE180_I7@PURE_QUANTA.EMMITSBURG_REV0P9(CHIPS)':
 'VSS_F24': CDS_PINID='VSS_F24';
NODE_NAME     U4 F31
 '@S9S_MB_2U_LIB.S9S_MB_2U(SCH_1):PAGE180_I7@PURE_QUANTA.EMMITSBURG_REV0P9(CHIPS)':
 'VSS_F31': CDS_PINID='VSS_F31';
NODE_NAME     U4 F34
 '@S9S_MB_2U_LIB.S9S_MB_2U(SCH_1):PAGE180_I7@PURE_QUANTA.EMMITSBURG_REV0P9(CHIPS)':
 'VSS_F34': CDS_PINID='VSS_F34';
NODE_NAME     U4 F39
 '@S9S_MB_2U_LIB.S9S_MB_2U(SCH_1):PAGE180_I7@PURE_QUANTA.EMMITSBURG_REV0P9(CHIPS)':
 'VSS_F39': CDS_PINID='VSS_F39';
NODE_NAME     U4 F41
 '@S9S_MB_2U_LIB.S9S_MB_2U(SCH_1):PAGE180_I7@PURE_QUANTA.EMMITSBURG_REV0P9(CHIPS)':
 'VSS_F41': CDS_PINID='VSS_F41';
NODE_NAME     U4 G13
 '@S9S_MB_2U_LIB.S9S_MB_2U(SCH_1):PAGE180_I7@PURE_QUANTA.EMMITSBURG_REV0P9(CHIPS)':
 'VSS_G13': CDS_PINID='VSS_G13';
NODE_NAME     U4 G20
 '@S9S_MB_2U_LIB.S9S_MB_2U(SCH_1):PAGE180_I7@PURE_QUANTA.EMMITSBURG_REV0P9(CHIPS)':
 'VSS_G20': CDS_PINID='VSS_G20';
NODE_NAME     U4 G26
 '@S9S_MB_2U_LIB.S9S_MB_2U(SCH_1):PAGE180_I7@PURE_QUANTA.EMMITSBURG_REV0P9(CHIPS)':
 'VSS_G26': CDS_PINID='VSS_G26';
NODE_NAME     U4 H5
 '@S9S_MB_2U_LIB.S9S_MB_2U(SCH_1):PAGE180_I7@PURE_QUANTA.EMMITSBURG_REV0P9(CHIPS)':
 'VSS_H5': CDS_PINID='VSS_H5';
NODE_NAME     U4 H8
 '@S9S_MB_2U_LIB.S9S_MB_2U(SCH_1):PAGE180_I7@PURE_QUANTA.EMMITSBURG_REV0P9(CHIPS)':
 'VSS_H8': CDS_PINID='VSS_H8';
NODE_NAME     U4 H39
 '@S9S_MB_2U_LIB.S9S_MB_2U(SCH_1):PAGE180_I7@PURE_QUANTA.EMMITSBURG_REV0P9(CHIPS)':
 'VSS_H39': CDS_PINID='VSS_H39';
NODE_NAME     U4 J13
 '@S9S_MB_2U_LIB.S9S_MB_2U(SCH_1):PAGE180_I7@PURE_QUANTA.EMMITSBURG_REV0P9(CHIPS)':
 'VSS_J13': CDS_PINID='VSS_J13';
NODE_NAME     U4 J20
 '@S9S_MB_2U_LIB.S9S_MB_2U(SCH_1):PAGE180_I7@PURE_QUANTA.EMMITSBURG_REV0P9(CHIPS)':
 'VSS_J20': CDS_PINID='VSS_J20';
NODE_NAME     U4 J26
 '@S9S_MB_2U_LIB.S9S_MB_2U(SCH_1):PAGE180_I7@PURE_QUANTA.EMMITSBURG_REV0P9(CHIPS)':
 'VSS_J26': CDS_PINID='VSS_J26';
NODE_NAME     U4 K5
 '@S9S_MB_2U_LIB.S9S_MB_2U(SCH_1):PAGE180_I7@PURE_QUANTA.EMMITSBURG_REV0P9(CHIPS)':
 'VSS_K5': CDS_PINID='VSS_K5';
NODE_NAME     U4 K11
 '@S9S_MB_2U_LIB.S9S_MB_2U(SCH_1):PAGE180_I7@PURE_QUANTA.EMMITSBURG_REV0P9(CHIPS)':
 'VSS_K11': CDS_PINID='VSS_K11';
NODE_NAME     U4 K15
 '@S9S_MB_2U_LIB.S9S_MB_2U(SCH_1):PAGE180_I7@PURE_QUANTA.EMMITSBURG_REV0P9(CHIPS)':
 'VSS_K15': CDS_PINID='VSS_K15';
NODE_NAME     U4 K24
 '@S9S_MB_2U_LIB.S9S_MB_2U(SCH_1):PAGE180_I7@PURE_QUANTA.EMMITSBURG_REV0P9(CHIPS)':
 'VSS_K24': CDS_PINID='VSS_K24';
NODE_NAME     U4 K34
 '@S9S_MB_2U_LIB.S9S_MB_2U(SCH_1):PAGE180_I7@PURE_QUANTA.EMMITSBURG_REV0P9(CHIPS)':
 'VSS_K34': CDS_PINID='VSS_K34';
NODE_NAME     U4 K39
 '@S9S_MB_2U_LIB.S9S_MB_2U(SCH_1):PAGE180_I7@PURE_QUANTA.EMMITSBURG_REV0P9(CHIPS)':
 'VSS_K39': CDS_PINID='VSS_K39';
NODE_NAME     U4 L10
 '@S9S_MB_2U_LIB.S9S_MB_2U(SCH_1):PAGE180_I7@PURE_QUANTA.EMMITSBURG_REV0P9(CHIPS)':
 'VSS_L10': CDS_PINID='VSS_L10';
NODE_NAME     U4 L16
 '@S9S_MB_2U_LIB.S9S_MB_2U(SCH_1):PAGE180_I7@PURE_QUANTA.EMMITSBURG_REV0P9(CHIPS)':
 'VSS_L16': CDS_PINID='VSS_L16';
NODE_NAME     U4 L20
 '@S9S_MB_2U_LIB.S9S_MB_2U(SCH_1):PAGE180_I7@PURE_QUANTA.EMMITSBURG_REV0P9(CHIPS)':
 'VSS_L20': CDS_PINID='VSS_L20';
NODE_NAME     U4 L23
 '@S9S_MB_2U_LIB.S9S_MB_2U(SCH_1):PAGE180_I7@PURE_QUANTA.EMMITSBURG_REV0P9(CHIPS)':
 'VSS_L23': CDS_PINID='VSS_L23';
NODE_NAME     U4 L26
 '@S9S_MB_2U_LIB.S9S_MB_2U(SCH_1):PAGE180_I7@PURE_QUANTA.EMMITSBURG_REV0P9(CHIPS)':
 'VSS_L26': CDS_PINID='VSS_L26';
NODE_NAME     U4 L29
 '@S9S_MB_2U_LIB.S9S_MB_2U(SCH_1):PAGE180_I7@PURE_QUANTA.EMMITSBURG_REV0P9(CHIPS)':
 'VSS_L29': CDS_PINID='VSS_L29';
NODE_NAME     U4 L36
 '@S9S_MB_2U_LIB.S9S_MB_2U(SCH_1):PAGE180_I7@PURE_QUANTA.EMMITSBURG_REV0P9(CHIPS)':
 'VSS_L36': CDS_PINID='VSS_L36';
NODE_NAME     U4 M1
 '@S9S_MB_2U_LIB.S9S_MB_2U(SCH_1):PAGE180_I7@PURE_QUANTA.EMMITSBURG_REV0P9(CHIPS)':
 'VSS_M1': CDS_PINID='VSS_M1';
NODE_NAME     U4 M3
 '@S9S_MB_2U_LIB.S9S_MB_2U(SCH_1):PAGE180_I7@PURE_QUANTA.EMMITSBURG_REV0P9(CHIPS)':
 'VSS_M3': CDS_PINID='VSS_M3';
NODE_NAME     U4 M5
 '@S9S_MB_2U_LIB.S9S_MB_2U(SCH_1):PAGE180_I7@PURE_QUANTA.EMMITSBURG_REV0P9(CHIPS)':
 'VSS_M5': CDS_PINID='VSS_M5';
NODE_NAME     U4 M11
 '@S9S_MB_2U_LIB.S9S_MB_2U(SCH_1):PAGE180_I7@PURE_QUANTA.EMMITSBURG_REV0P9(CHIPS)':
 'VSS_M11': CDS_PINID='VSS_M11';
NODE_NAME     U4 M15
 '@S9S_MB_2U_LIB.S9S_MB_2U(SCH_1):PAGE180_I7@PURE_QUANTA.EMMITSBURG_REV0P9(CHIPS)':
 'VSS_M15': CDS_PINID='VSS_M15';
NODE_NAME     U4 M18
 '@S9S_MB_2U_LIB.S9S_MB_2U(SCH_1):PAGE180_I7@PURE_QUANTA.EMMITSBURG_REV0P9(CHIPS)':
 'VSS_M18': CDS_PINID='VSS_M18';
NODE_NAME     U4 M21
 '@S9S_MB_2U_LIB.S9S_MB_2U(SCH_1):PAGE180_I7@PURE_QUANTA.EMMITSBURG_REV0P9(CHIPS)':
 'VSS_M21': CDS_PINID='VSS_M21';
NODE_NAME     U4 M28
 '@S9S_MB_2U_LIB.S9S_MB_2U(SCH_1):PAGE180_I7@PURE_QUANTA.EMMITSBURG_REV0P9(CHIPS)':
 'VSS_M28': CDS_PINID='VSS_M28';
NODE_NAME     U4 M31
 '@S9S_MB_2U_LIB.S9S_MB_2U(SCH_1):PAGE180_I7@PURE_QUANTA.EMMITSBURG_REV0P9(CHIPS)':
 'VSS_M31': CDS_PINID='VSS_M31';
NODE_NAME     U4 M34
 '@S9S_MB_2U_LIB.S9S_MB_2U(SCH_1):PAGE180_I7@PURE_QUANTA.EMMITSBURG_REV0P9(CHIPS)':
 'VSS_M34': CDS_PINID='VSS_M34';
NODE_NAME     U4 M37
 '@S9S_MB_2U_LIB.S9S_MB_2U(SCH_1):PAGE180_I7@PURE_QUANTA.EMMITSBURG_REV0P9(CHIPS)':
 'VSS_M37': CDS_PINID='VSS_M37';
NODE_NAME     U4 M39
 '@S9S_MB_2U_LIB.S9S_MB_2U(SCH_1):PAGE180_I7@PURE_QUANTA.EMMITSBURG_REV0P9(CHIPS)':
 'VSS_M39': CDS_PINID='VSS_M39';
NODE_NAME     U4 N16
 '@S9S_MB_2U_LIB.S9S_MB_2U(SCH_1):PAGE180_I7@PURE_QUANTA.EMMITSBURG_REV0P9(CHIPS)':
 'VSS_N16': CDS_PINID='VSS_N16';
NODE_NAME     U4 N32
 '@S9S_MB_2U_LIB.S9S_MB_2U(SCH_1):PAGE180_I7@PURE_QUANTA.EMMITSBURG_REV0P9(CHIPS)':
 'VSS_N32': CDS_PINID='VSS_N32';
NODE_NAME     U4 P5
 '@S9S_MB_2U_LIB.S9S_MB_2U(SCH_1):PAGE180_I7@PURE_QUANTA.EMMITSBURG_REV0P9(CHIPS)':
 'VSS_P5': CDS_PINID='VSS_P5';
NODE_NAME     U4 P8
 '@S9S_MB_2U_LIB.S9S_MB_2U(SCH_1):PAGE180_I7@PURE_QUANTA.EMMITSBURG_REV0P9(CHIPS)':
 'VSS_P8': CDS_PINID='VSS_P8';
NODE_NAME     U4 P11
 '@S9S_MB_2U_LIB.S9S_MB_2U(SCH_1):PAGE180_I7@PURE_QUANTA.EMMITSBURG_REV0P9(CHIPS)':
 'VSS_P11': CDS_PINID='VSS_P11';
NODE_NAME     U4 P24
 '@S9S_MB_2U_LIB.S9S_MB_2U(SCH_1):PAGE180_I7@PURE_QUANTA.EMMITSBURG_REV0P9(CHIPS)':
 'VSS_P24': CDS_PINID='VSS_P24';
NODE_NAME     U4 P28
 '@S9S_MB_2U_LIB.S9S_MB_2U(SCH_1):PAGE180_I7@PURE_QUANTA.EMMITSBURG_REV0P9(CHIPS)':
 'VSS_P28': CDS_PINID='VSS_P28';
NODE_NAME     U4 P31
 '@S9S_MB_2U_LIB.S9S_MB_2U(SCH_1):PAGE180_I7@PURE_QUANTA.EMMITSBURG_REV0P9(CHIPS)':
 'VSS_P31': CDS_PINID='VSS_P31';
NODE_NAME     U4 P37
 '@S9S_MB_2U_LIB.S9S_MB_2U(SCH_1):PAGE180_I7@PURE_QUANTA.EMMITSBURG_REV0P9(CHIPS)':
 'VSS_P37': CDS_PINID='VSS_P37';
NODE_NAME     U4 P39
 '@S9S_MB_2U_LIB.S9S_MB_2U(SCH_1):PAGE180_I7@PURE_QUANTA.EMMITSBURG_REV0P9(CHIPS)':
 'VSS_P39': CDS_PINID='VSS_P39';
NODE_NAME     U4 P41
 '@S9S_MB_2U_LIB.S9S_MB_2U(SCH_1):PAGE180_I7@PURE_QUANTA.EMMITSBURG_REV0P9(CHIPS)':
 'VSS_P41': CDS_PINID='VSS_P41';
NODE_NAME     U4 P43
 '@S9S_MB_2U_LIB.S9S_MB_2U(SCH_1):PAGE180_I7@PURE_QUANTA.EMMITSBURG_REV0P9(CHIPS)':
 'VSS_P43': CDS_PINID='VSS_P43';
NODE_NAME     U4 R13
 '@S9S_MB_2U_LIB.S9S_MB_2U(SCH_1):PAGE180_I7@PURE_QUANTA.EMMITSBURG_REV0P9(CHIPS)':
 'VSS_R13': CDS_PINID='VSS_R13';
NODE_NAME     U4 R16
 '@S9S_MB_2U_LIB.S9S_MB_2U(SCH_1):PAGE180_I7@PURE_QUANTA.EMMITSBURG_REV0P9(CHIPS)':
 'VSS_R16': CDS_PINID='VSS_R16';
NODE_NAME     U4 R20
 '@S9S_MB_2U_LIB.S9S_MB_2U(SCH_1):PAGE180_I7@PURE_QUANTA.EMMITSBURG_REV0P9(CHIPS)':
 'VSS_R20': CDS_PINID='VSS_R20';
NODE_NAME     U4 R36
 '@S9S_MB_2U_LIB.S9S_MB_2U(SCH_1):PAGE180_I7@PURE_QUANTA.EMMITSBURG_REV0P9(CHIPS)':
 'VSS_R36': CDS_PINID='VSS_R36';
NODE_NAME     U4 T31
 '@S9S_MB_2U_LIB.S9S_MB_2U(SCH_1):PAGE180_I7@PURE_QUANTA.EMMITSBURG_REV0P9(CHIPS)':
 'VSS_T31': CDS_PINID='VSS_T31';
NODE_NAME     U4 U5
 '@S9S_MB_2U_LIB.S9S_MB_2U(SCH_1):PAGE180_I7@PURE_QUANTA.EMMITSBURG_REV0P9(CHIPS)':
 'VSS_U5': CDS_PINID='VSS_U5';
NODE_NAME     U4 U10
 '@S9S_MB_2U_LIB.S9S_MB_2U(SCH_1):PAGE180_I7@PURE_QUANTA.EMMITSBURG_REV0P9(CHIPS)':
 'VSS_U10': CDS_PINID='VSS_U10';
NODE_NAME     U4 U13
 '@S9S_MB_2U_LIB.S9S_MB_2U(SCH_1):PAGE180_I7@PURE_QUANTA.EMMITSBURG_REV0P9(CHIPS)':
 'VSS_U13': CDS_PINID='VSS_U13';
NODE_NAME     U4 U25
 '@S9S_MB_2U_LIB.S9S_MB_2U(SCH_1):PAGE180_I7@PURE_QUANTA.EMMITSBURG_REV0P9(CHIPS)':
 'VSS_U25': CDS_PINID='VSS_U25';
NODE_NAME     U4 U39
 '@S9S_MB_2U_LIB.S9S_MB_2U(SCH_1):PAGE180_I7@PURE_QUANTA.EMMITSBURG_REV0P9(CHIPS)':
 'VSS_U39': CDS_PINID='VSS_U39';
NODE_NAME     U4 V2
 '@S9S_MB_2U_LIB.S9S_MB_2U(SCH_1):PAGE180_I7@PURE_QUANTA.EMMITSBURG_REV0P9(CHIPS)':
 'VSS_V2': CDS_PINID='VSS_V2';
NODE_NAME     U4 V31
 '@S9S_MB_2U_LIB.S9S_MB_2U(SCH_1):PAGE180_I7@PURE_QUANTA.EMMITSBURG_REV0P9(CHIPS)':
 'VSS_V31': CDS_PINID='VSS_V31';
NODE_NAME     U4 W3
 '@S9S_MB_2U_LIB.S9S_MB_2U(SCH_1):PAGE180_I7@PURE_QUANTA.EMMITSBURG_REV0P9(CHIPS)':
 'VSS_W3': CDS_PINID='VSS_W3';
NODE_NAME     U4 W5
 '@S9S_MB_2U_LIB.S9S_MB_2U(SCH_1):PAGE180_I7@PURE_QUANTA.EMMITSBURG_REV0P9(CHIPS)':
 'VSS_W5': CDS_PINID='VSS_W5';
NODE_NAME     U4 W25
 '@S9S_MB_2U_LIB.S9S_MB_2U(SCH_1):PAGE180_I7@PURE_QUANTA.EMMITSBURG_REV0P9(CHIPS)':
 'VSS_W25': CDS_PINID='VSS_W25';
NODE_NAME     U4 W39
 '@S9S_MB_2U_LIB.S9S_MB_2U(SCH_1):PAGE180_I7@PURE_QUANTA.EMMITSBURG_REV0P9(CHIPS)':
 'VSS_W39': CDS_PINID='VSS_W39';
NODE_NAME     U4 Y8
 '@S9S_MB_2U_LIB.S9S_MB_2U(SCH_1):PAGE180_I7@PURE_QUANTA.EMMITSBURG_REV0P9(CHIPS)':
 'VSS_Y8': CDS_PINID='VSS_Y8';
NODE_NAME     U4 Y11
 '@S9S_MB_2U_LIB.S9S_MB_2U(SCH_1):PAGE180_I7@PURE_QUANTA.EMMITSBURG_REV0P9(CHIPS)':
 'VSS_Y11': CDS_PINID='VSS_Y11';
NODE_NAME     U4 Y15
 '@S9S_MB_2U_LIB.S9S_MB_2U(SCH_1):PAGE180_I7@PURE_QUANTA.EMMITSBURG_REV0P9(CHIPS)':
 'VSS_Y15': CDS_PINID='VSS_Y15';
NODE_NAME     U4 Y31
 '@S9S_MB_2U_LIB.S9S_MB_2U(SCH_1):PAGE180_I7@PURE_QUANTA.EMMITSBURG_REV0P9(CHIPS)':
 'VSS_Y31': CDS_PINID='VSS_Y31';
NODE_NAME     U4 Y34
 '@S9S_MB_2U_LIB.S9S_MB_2U(SCH_1):PAGE180_I7@PURE_QUANTA.EMMITSBURG_REV0P9(CHIPS)':
 'VSS_Y34': CDS_PINID='VSS_Y34';
NODE_NAME     U4 A6
 '@S9S_MB_2U_LIB.S9S_MB_2U(SCH_1):PAGE180_I9@PURE_QUANTA.EMMITSBURG_REV0P9(CHIPS)':
 'VSS_A6': CDS_PINID='VSS_A6';
NODE_NAME     U4 A20
 '@S9S_MB_2U_LIB.S9S_MB_2U(SCH_1):PAGE180_I9@PURE_QUANTA.EMMITSBURG_REV0P9(CHIPS)':
 'VSS_A20': CDS_PINID='VSS_A20';
NODE_NAME     U4 A22
 '@S9S_MB_2U_LIB.S9S_MB_2U(SCH_1):PAGE180_I9@PURE_QUANTA.EMMITSBURG_REV0P9(CHIPS)':
 'VSS_A22': CDS_PINID='VSS_A22';
NODE_NAME     U4 A24
 '@S9S_MB_2U_LIB.S9S_MB_2U(SCH_1):PAGE180_I9@PURE_QUANTA.EMMITSBURG_REV0P9(CHIPS)':
 'VSS_A24': CDS_PINID='VSS_A24';
NODE_NAME     U4 A26
 '@S9S_MB_2U_LIB.S9S_MB_2U(SCH_1):PAGE180_I9@PURE_QUANTA.EMMITSBURG_REV0P9(CHIPS)':
 'VSS_A26': CDS_PINID='VSS_A26';
NODE_NAME     U4 A38
 '@S9S_MB_2U_LIB.S9S_MB_2U(SCH_1):PAGE180_I9@PURE_QUANTA.EMMITSBURG_REV0P9(CHIPS)':
 'VSS_A38': CDS_PINID='VSS_A38';
NODE_NAME     U4 A40
 '@S9S_MB_2U_LIB.S9S_MB_2U(SCH_1):PAGE180_I9@PURE_QUANTA.EMMITSBURG_REV0P9(CHIPS)':
 'VSS_A40': CDS_PINID='VSS_A40';
NODE_NAME     U4 AA5
 '@S9S_MB_2U_LIB.S9S_MB_2U(SCH_1):PAGE180_I9@PURE_QUANTA.EMMITSBURG_REV0P9(CHIPS)':
 'VSS_AA5': CDS_PINID='VSS_AA5';
NODE_NAME     U4 AA17
 '@S9S_MB_2U_LIB.S9S_MB_2U(SCH_1):PAGE180_I9@PURE_QUANTA.EMMITSBURG_REV0P9(CHIPS)':
 'VSS_AA17': CDS_PINID='VSS_AA17';
NODE_NAME     U4 AA19
 '@S9S_MB_2U_LIB.S9S_MB_2U(SCH_1):PAGE180_I9@PURE_QUANTA.EMMITSBURG_REV0P9(CHIPS)':
 'VSS_AA19': CDS_PINID='VSS_AA19';
NODE_NAME     U4 AA20
 '@S9S_MB_2U_LIB.S9S_MB_2U(SCH_1):PAGE180_I9@PURE_QUANTA.EMMITSBURG_REV0P9(CHIPS)':
 'VSS_AA20': CDS_PINID='VSS_AA20';
NODE_NAME     U4 AA22
 '@S9S_MB_2U_LIB.S9S_MB_2U(SCH_1):PAGE180_I9@PURE_QUANTA.EMMITSBURG_REV0P9(CHIPS)':
 'VSS_AA22': CDS_PINID='VSS_AA22';
NODE_NAME     U4 AA24
 '@S9S_MB_2U_LIB.S9S_MB_2U(SCH_1):PAGE180_I9@PURE_QUANTA.EMMITSBURG_REV0P9(CHIPS)':
 'VSS_AA24': CDS_PINID='VSS_AA24';
NODE_NAME     U4 AA25
 '@S9S_MB_2U_LIB.S9S_MB_2U(SCH_1):PAGE180_I9@PURE_QUANTA.EMMITSBURG_REV0P9(CHIPS)':
 'VSS_AA25': CDS_PINID='VSS_AA25';
NODE_NAME     U4 AA27
 '@S9S_MB_2U_LIB.S9S_MB_2U(SCH_1):PAGE180_I9@PURE_QUANTA.EMMITSBURG_REV0P9(CHIPS)':
 'VSS_AA27': CDS_PINID='VSS_AA27';
NODE_NAME     U4 AA32
 '@S9S_MB_2U_LIB.S9S_MB_2U(SCH_1):PAGE180_I9@PURE_QUANTA.EMMITSBURG_REV0P9(CHIPS)':
 'VSS_AA32': CDS_PINID='VSS_AA32';
NODE_NAME     U4 AA36
 '@S9S_MB_2U_LIB.S9S_MB_2U(SCH_1):PAGE180_I9@PURE_QUANTA.EMMITSBURG_REV0P9(CHIPS)':
 'VSS_AA36': CDS_PINID='VSS_AA36';
NODE_NAME     U4 AA39
 '@S9S_MB_2U_LIB.S9S_MB_2U(SCH_1):PAGE180_I9@PURE_QUANTA.EMMITSBURG_REV0P9(CHIPS)':
 'VSS_AA39': CDS_PINID='VSS_AA39';
NODE_NAME     U4 AB15
 '@S9S_MB_2U_LIB.S9S_MB_2U(SCH_1):PAGE180_I9@PURE_QUANTA.EMMITSBURG_REV0P9(CHIPS)':
 'VSS_AB15': CDS_PINID='VSS_AB15';
NODE_NAME     U4 AB17
 '@S9S_MB_2U_LIB.S9S_MB_2U(SCH_1):PAGE180_I9@PURE_QUANTA.EMMITSBURG_REV0P9(CHIPS)':
 'VSS_AB17': CDS_PINID='VSS_AB17';
NODE_NAME     U4 AB25
 '@S9S_MB_2U_LIB.S9S_MB_2U(SCH_1):PAGE180_I9@PURE_QUANTA.EMMITSBURG_REV0P9(CHIPS)':
 'VSS_AB25': CDS_PINID='VSS_AB25';
NODE_NAME     U4 AB37
 '@S9S_MB_2U_LIB.S9S_MB_2U(SCH_1):PAGE180_I9@PURE_QUANTA.EMMITSBURG_REV0P9(CHIPS)':
 'VSS_AB37': CDS_PINID='VSS_AB37';
NODE_NAME     U4 AC5
 '@S9S_MB_2U_LIB.S9S_MB_2U(SCH_1):PAGE180_I9@PURE_QUANTA.EMMITSBURG_REV0P9(CHIPS)':
 'VSS_AC5': CDS_PINID='VSS_AC5';
NODE_NAME     U4 AC29
 '@S9S_MB_2U_LIB.S9S_MB_2U(SCH_1):PAGE180_I9@PURE_QUANTA.EMMITSBURG_REV0P9(CHIPS)':
 'VSS_AC29': CDS_PINID='VSS_AC29';
NODE_NAME     U4 AC32
 '@S9S_MB_2U_LIB.S9S_MB_2U(SCH_1):PAGE180_I9@PURE_QUANTA.EMMITSBURG_REV0P9(CHIPS)':
 'VSS_AC32': CDS_PINID='VSS_AC32';
NODE_NAME     U4 AC36
 '@S9S_MB_2U_LIB.S9S_MB_2U(SCH_1):PAGE180_I9@PURE_QUANTA.EMMITSBURG_REV0P9(CHIPS)':
 'VSS_AC36': CDS_PINID='VSS_AC36';
NODE_NAME     U4 AC39
 '@S9S_MB_2U_LIB.S9S_MB_2U(SCH_1):PAGE180_I9@PURE_QUANTA.EMMITSBURG_REV0P9(CHIPS)':
 'VSS_AC39': CDS_PINID='VSS_AC39';
NODE_NAME     U4 AD8
 '@S9S_MB_2U_LIB.S9S_MB_2U(SCH_1):PAGE180_I9@PURE_QUANTA.EMMITSBURG_REV0P9(CHIPS)':
 'VSS_AD8': CDS_PINID='VSS_AD8';
NODE_NAME     U4 AD11
 '@S9S_MB_2U_LIB.S9S_MB_2U(SCH_1):PAGE180_I9@PURE_QUANTA.EMMITSBURG_REV0P9(CHIPS)':
 'VSS_AD11': CDS_PINID='VSS_AD11';
NODE_NAME     U4 AD19
 '@S9S_MB_2U_LIB.S9S_MB_2U(SCH_1):PAGE180_I9@PURE_QUANTA.EMMITSBURG_REV0P9(CHIPS)':
 'VSS_AD19': CDS_PINID='VSS_AD19';
NODE_NAME     U4 AD20
 '@S9S_MB_2U_LIB.S9S_MB_2U(SCH_1):PAGE180_I9@PURE_QUANTA.EMMITSBURG_REV0P9(CHIPS)':
 'VSS_AD20': CDS_PINID='VSS_AD20';
NODE_NAME     U4 AD22
 '@S9S_MB_2U_LIB.S9S_MB_2U(SCH_1):PAGE180_I9@PURE_QUANTA.EMMITSBURG_REV0P9(CHIPS)':
 'VSS_AD22': CDS_PINID='VSS_AD22';
NODE_NAME     U4 AD24
 '@S9S_MB_2U_LIB.S9S_MB_2U(SCH_1):PAGE180_I9@PURE_QUANTA.EMMITSBURG_REV0P9(CHIPS)':
 'VSS_AD24': CDS_PINID='VSS_AD24';
NODE_NAME     U4 AD31
 '@S9S_MB_2U_LIB.S9S_MB_2U(SCH_1):PAGE180_I9@PURE_QUANTA.EMMITSBURG_REV0P9(CHIPS)':
 'VSS_AD31': CDS_PINID='VSS_AD31';
NODE_NAME     U4 AD34
 '@S9S_MB_2U_LIB.S9S_MB_2U(SCH_1):PAGE180_I9@PURE_QUANTA.EMMITSBURG_REV0P9(CHIPS)':
 'VSS_AD34': CDS_PINID='VSS_AD34';
NODE_NAME     U4 AE5
 '@S9S_MB_2U_LIB.S9S_MB_2U(SCH_1):PAGE180_I9@PURE_QUANTA.EMMITSBURG_REV0P9(CHIPS)':
 'VSS_AE5': CDS_PINID='VSS_AE5';
NODE_NAME     U4 AE13
 '@S9S_MB_2U_LIB.S9S_MB_2U(SCH_1):PAGE180_I9@PURE_QUANTA.EMMITSBURG_REV0P9(CHIPS)':
 'VSS_AE13': CDS_PINID='VSS_AE13';
NODE_NAME     U4 AE39
 '@S9S_MB_2U_LIB.S9S_MB_2U(SCH_1):PAGE180_I9@PURE_QUANTA.EMMITSBURG_REV0P9(CHIPS)':
 'VSS_AE39': CDS_PINID='VSS_AE39';
NODE_NAME     U4 AF19
 '@S9S_MB_2U_LIB.S9S_MB_2U(SCH_1):PAGE180_I9@PURE_QUANTA.EMMITSBURG_REV0P9(CHIPS)':
 'VSS_AF19': CDS_PINID='VSS_AF19';
NODE_NAME     U4 AF24
 '@S9S_MB_2U_LIB.S9S_MB_2U(SCH_1):PAGE180_I9@PURE_QUANTA.EMMITSBURG_REV0P9(CHIPS)':
 'VSS_AF24': CDS_PINID='VSS_AF24';
NODE_NAME     U4 AF31
 '@S9S_MB_2U_LIB.S9S_MB_2U(SCH_1):PAGE180_I9@PURE_QUANTA.EMMITSBURG_REV0P9(CHIPS)':
 'VSS_AF31': CDS_PINID='VSS_AF31';
NODE_NAME     U4 AF40
 '@S9S_MB_2U_LIB.S9S_MB_2U(SCH_1):PAGE180_I9@PURE_QUANTA.EMMITSBURG_REV0P9(CHIPS)':
 'VSS_AF40': CDS_PINID='VSS_AF40';
NODE_NAME     U4 AF42
 '@S9S_MB_2U_LIB.S9S_MB_2U(SCH_1):PAGE180_I9@PURE_QUANTA.EMMITSBURG_REV0P9(CHIPS)':
 'VSS_AF42': CDS_PINID='VSS_AF42';
NODE_NAME     U4 AG5
 '@S9S_MB_2U_LIB.S9S_MB_2U(SCH_1):PAGE180_I9@PURE_QUANTA.EMMITSBURG_REV0P9(CHIPS)':
 'VSS_AG5': CDS_PINID='VSS_AG5';
NODE_NAME     U4 AG13
 '@S9S_MB_2U_LIB.S9S_MB_2U(SCH_1):PAGE180_I9@PURE_QUANTA.EMMITSBURG_REV0P9(CHIPS)':
 'VSS_AG13': CDS_PINID='VSS_AG13';
NODE_NAME     U4 AG19
 '@S9S_MB_2U_LIB.S9S_MB_2U(SCH_1):PAGE180_I9@PURE_QUANTA.EMMITSBURG_REV0P9(CHIPS)':
 'VSS_AG19': CDS_PINID='VSS_AG19';
NODE_NAME     U4 AG24
 '@S9S_MB_2U_LIB.S9S_MB_2U(SCH_1):PAGE180_I9@PURE_QUANTA.EMMITSBURG_REV0P9(CHIPS)':
 'VSS_AG24': CDS_PINID='VSS_AG24';
NODE_NAME     U4 AG39
 '@S9S_MB_2U_LIB.S9S_MB_2U(SCH_1):PAGE180_I9@PURE_QUANTA.EMMITSBURG_REV0P9(CHIPS)':
 'VSS_AG39': CDS_PINID='VSS_AG39';
NODE_NAME     U4 AH8
 '@S9S_MB_2U_LIB.S9S_MB_2U(SCH_1):PAGE180_I9@PURE_QUANTA.EMMITSBURG_REV0P9(CHIPS)':
 'VSS_AH8': CDS_PINID='VSS_AH8';
NODE_NAME     U4 AH31
 '@S9S_MB_2U_LIB.S9S_MB_2U(SCH_1):PAGE180_I9@PURE_QUANTA.EMMITSBURG_REV0P9(CHIPS)':
 'VSS_AH31': CDS_PINID='VSS_AH31';
NODE_NAME     U4 AJ5
 '@S9S_MB_2U_LIB.S9S_MB_2U(SCH_1):PAGE180_I9@PURE_QUANTA.EMMITSBURG_REV0P9(CHIPS)':
 'VSS_AJ5': CDS_PINID='VSS_AJ5';
NODE_NAME     U4 AJ19
 '@S9S_MB_2U_LIB.S9S_MB_2U(SCH_1):PAGE180_I9@PURE_QUANTA.EMMITSBURG_REV0P9(CHIPS)':
 'VSS_AJ19': CDS_PINID='VSS_AJ19';
NODE_NAME     U4 AJ24
 '@S9S_MB_2U_LIB.S9S_MB_2U(SCH_1):PAGE180_I9@PURE_QUANTA.EMMITSBURG_REV0P9(CHIPS)':
 'VSS_AJ24': CDS_PINID='VSS_AJ24';
NODE_NAME     U4 AJ29
 '@S9S_MB_2U_LIB.S9S_MB_2U(SCH_1):PAGE180_I9@PURE_QUANTA.EMMITSBURG_REV0P9(CHIPS)':
 'VSS_AJ29': CDS_PINID='VSS_AJ29';
NODE_NAME     U4 AJ36
 '@S9S_MB_2U_LIB.S9S_MB_2U(SCH_1):PAGE180_I9@PURE_QUANTA.EMMITSBURG_REV0P9(CHIPS)':
 'VSS_AJ36': CDS_PINID='VSS_AJ36';
NODE_NAME     U4 AJ39
 '@S9S_MB_2U_LIB.S9S_MB_2U(SCH_1):PAGE180_I9@PURE_QUANTA.EMMITSBURG_REV0P9(CHIPS)':
 'VSS_AJ39': CDS_PINID='VSS_AJ39';
NODE_NAME     U4 AK2
 '@S9S_MB_2U_LIB.S9S_MB_2U(SCH_1):PAGE180_I9@PURE_QUANTA.EMMITSBURG_REV0P9(CHIPS)':
 'VSS_AK2': CDS_PINID='VSS_AK2';
NODE_NAME     U4 AK4
 '@S9S_MB_2U_LIB.S9S_MB_2U(SCH_1):PAGE180_I9@PURE_QUANTA.EMMITSBURG_REV0P9(CHIPS)':
 'VSS_AK4': CDS_PINID='VSS_AK4';
NODE_NAME     U4 AK11
 '@S9S_MB_2U_LIB.S9S_MB_2U(SCH_1):PAGE180_I9@PURE_QUANTA.EMMITSBURG_REV0P9(CHIPS)':
 'VSS_AK11': CDS_PINID='VSS_AK11';
NODE_NAME     U4 AK37
 '@S9S_MB_2U_LIB.S9S_MB_2U(SCH_1):PAGE180_I9@PURE_QUANTA.EMMITSBURG_REV0P9(CHIPS)':
 'VSS_AK37': CDS_PINID='VSS_AK37';
NODE_NAME     U4 AL19
 '@S9S_MB_2U_LIB.S9S_MB_2U(SCH_1):PAGE180_I9@PURE_QUANTA.EMMITSBURG_REV0P9(CHIPS)':
 'VSS_AL19': CDS_PINID='VSS_AL19';
NODE_NAME     U4 AL24
 '@S9S_MB_2U_LIB.S9S_MB_2U(SCH_1):PAGE180_I9@PURE_QUANTA.EMMITSBURG_REV0P9(CHIPS)':
 'VSS_AL24': CDS_PINID='VSS_AL24';
NODE_NAME     U4 AL27
 '@S9S_MB_2U_LIB.S9S_MB_2U(SCH_1):PAGE180_I9@PURE_QUANTA.EMMITSBURG_REV0P9(CHIPS)':
 'VSS_AL27': CDS_PINID='VSS_AL27';
NODE_NAME     U4 AL29
 '@S9S_MB_2U_LIB.S9S_MB_2U(SCH_1):PAGE180_I9@PURE_QUANTA.EMMITSBURG_REV0P9(CHIPS)':
 'VSS_AL29': CDS_PINID='VSS_AL29';
NODE_NAME     U4 AL39
 '@S9S_MB_2U_LIB.S9S_MB_2U(SCH_1):PAGE180_I9@PURE_QUANTA.EMMITSBURG_REV0P9(CHIPS)':
 'VSS_AL39': CDS_PINID='VSS_AL39';
NODE_NAME     U4 AM8
 '@S9S_MB_2U_LIB.S9S_MB_2U(SCH_1):PAGE180_I9@PURE_QUANTA.EMMITSBURG_REV0P9(CHIPS)':
 'VSS_AM8': CDS_PINID='VSS_AM8';
NODE_NAME     U4 AM15
 '@S9S_MB_2U_LIB.S9S_MB_2U(SCH_1):PAGE180_I9@PURE_QUANTA.EMMITSBURG_REV0P9(CHIPS)':
 'VSS_AM15': CDS_PINID='VSS_AM15';
NODE_NAME     U4 AM31
 '@S9S_MB_2U_LIB.S9S_MB_2U(SCH_1):PAGE180_I9@PURE_QUANTA.EMMITSBURG_REV0P9(CHIPS)':
 'VSS_AM31': CDS_PINID='VSS_AM31';
NODE_NAME     U4 AN13
 '@S9S_MB_2U_LIB.S9S_MB_2U(SCH_1):PAGE180_I9@PURE_QUANTA.EMMITSBURG_REV0P9(CHIPS)':
 'VSS_AN13': CDS_PINID='VSS_AN13';
NODE_NAME     U4 AN16
 '@S9S_MB_2U_LIB.S9S_MB_2U(SCH_1):PAGE180_I9@PURE_QUANTA.EMMITSBURG_REV0P9(CHIPS)':
 'VSS_AN16': CDS_PINID='VSS_AN16';
NODE_NAME     U4 AN29
 '@S9S_MB_2U_LIB.S9S_MB_2U(SCH_1):PAGE180_I9@PURE_QUANTA.EMMITSBURG_REV0P9(CHIPS)':
 'VSS_AN29': CDS_PINID='VSS_AN29';
NODE_NAME     U4 AN32
 '@S9S_MB_2U_LIB.S9S_MB_2U(SCH_1):PAGE180_I9@PURE_QUANTA.EMMITSBURG_REV0P9(CHIPS)':
 'VSS_AN32': CDS_PINID='VSS_AN32';
NODE_NAME     U4 AP5
 '@S9S_MB_2U_LIB.S9S_MB_2U(SCH_1):PAGE180_I9@PURE_QUANTA.EMMITSBURG_REV0P9(CHIPS)':
 'VSS_AP5': CDS_PINID='VSS_AP5';
NODE_NAME     U4 AP11
 '@S9S_MB_2U_LIB.S9S_MB_2U(SCH_1):PAGE180_I9@PURE_QUANTA.EMMITSBURG_REV0P9(CHIPS)':
 'VSS_AP11': CDS_PINID='VSS_AP11';
NODE_NAME     U4 AP18
 '@S9S_MB_2U_LIB.S9S_MB_2U(SCH_1):PAGE180_I9@PURE_QUANTA.EMMITSBURG_REV0P9(CHIPS)':
 'VSS_AP18': CDS_PINID='VSS_AP18';
NODE_NAME     U4 AP24
 '@S9S_MB_2U_LIB.S9S_MB_2U(SCH_1):PAGE180_I9@PURE_QUANTA.EMMITSBURG_REV0P9(CHIPS)':
 'VSS_AP24': CDS_PINID='VSS_AP24';
NODE_NAME     U4 AP28
 '@S9S_MB_2U_LIB.S9S_MB_2U(SCH_1):PAGE180_I9@PURE_QUANTA.EMMITSBURG_REV0P9(CHIPS)':
 'VSS_AP28': CDS_PINID='VSS_AP28';
NODE_NAME     U4 AP37
 '@S9S_MB_2U_LIB.S9S_MB_2U(SCH_1):PAGE180_I9@PURE_QUANTA.EMMITSBURG_REV0P9(CHIPS)':
 'VSS_AP37': CDS_PINID='VSS_AP37';
NODE_NAME     U4 AP39
 '@S9S_MB_2U_LIB.S9S_MB_2U(SCH_1):PAGE180_I9@PURE_QUANTA.EMMITSBURG_REV0P9(CHIPS)':
 'VSS_AP39': CDS_PINID='VSS_AP39';
NODE_NAME     U4 AR20
 '@S9S_MB_2U_LIB.S9S_MB_2U(SCH_1):PAGE180_I9@PURE_QUANTA.EMMITSBURG_REV0P9(CHIPS)':
 'VSS_AR20': CDS_PINID='VSS_AR20';
NODE_NAME     U4 AR32
 '@S9S_MB_2U_LIB.S9S_MB_2U(SCH_1):PAGE180_I9@PURE_QUANTA.EMMITSBURG_REV0P9(CHIPS)':
 'VSS_AR32': CDS_PINID='VSS_AR32';
NODE_NAME     U4 AT5
 '@S9S_MB_2U_LIB.S9S_MB_2U(SCH_1):PAGE180_I9@PURE_QUANTA.EMMITSBURG_REV0P9(CHIPS)':
 'VSS_AT5': CDS_PINID='VSS_AT5';
NODE_NAME     U4 AT8
 '@S9S_MB_2U_LIB.S9S_MB_2U(SCH_1):PAGE180_I9@PURE_QUANTA.EMMITSBURG_REV0P9(CHIPS)':
 'VSS_AT8': CDS_PINID='VSS_AT8';
NODE_NAME     U4 AT11
 '@S9S_MB_2U_LIB.S9S_MB_2U(SCH_1):PAGE180_I9@PURE_QUANTA.EMMITSBURG_REV0P9(CHIPS)':
 'VSS_AT11': CDS_PINID='VSS_AT11';
NODE_NAME     U4 AT15
 '@S9S_MB_2U_LIB.S9S_MB_2U(SCH_1):PAGE180_I9@PURE_QUANTA.EMMITSBURG_REV0P9(CHIPS)':
 'VSS_AT15': CDS_PINID='VSS_AT15';
NODE_NAME     U4 AT21
 '@S9S_MB_2U_LIB.S9S_MB_2U(SCH_1):PAGE180_I9@PURE_QUANTA.EMMITSBURG_REV0P9(CHIPS)':
 'VSS_AT21': CDS_PINID='VSS_AT21';
NODE_NAME     U4 AT24
 '@S9S_MB_2U_LIB.S9S_MB_2U(SCH_1):PAGE180_I9@PURE_QUANTA.EMMITSBURG_REV0P9(CHIPS)':
 'VSS_AT24': CDS_PINID='VSS_AT24';
NODE_NAME     U4 AT28
 '@S9S_MB_2U_LIB.S9S_MB_2U(SCH_1):PAGE180_I9@PURE_QUANTA.EMMITSBURG_REV0P9(CHIPS)':
 'VSS_AT28': CDS_PINID='VSS_AT28';
NODE_NAME     U4 AT31
 '@S9S_MB_2U_LIB.S9S_MB_2U(SCH_1):PAGE180_I9@PURE_QUANTA.EMMITSBURG_REV0P9(CHIPS)':
 'VSS_AT31': CDS_PINID='VSS_AT31';
NODE_NAME     U4 AT34
 '@S9S_MB_2U_LIB.S9S_MB_2U(SCH_1):PAGE180_I9@PURE_QUANTA.EMMITSBURG_REV0P9(CHIPS)':
 'VSS_AT34': CDS_PINID='VSS_AT34';
NODE_NAME     U4 AT39
 '@S9S_MB_2U_LIB.S9S_MB_2U(SCH_1):PAGE180_I9@PURE_QUANTA.EMMITSBURG_REV0P9(CHIPS)':
 'VSS_AT39': CDS_PINID='VSS_AT39';
NODE_NAME     U4 AU20
 '@S9S_MB_2U_LIB.S9S_MB_2U(SCH_1):PAGE180_I9@PURE_QUANTA.EMMITSBURG_REV0P9(CHIPS)':
 'VSS_AU20': CDS_PINID='VSS_AU20';
NODE_NAME     U4 AU23
 '@S9S_MB_2U_LIB.S9S_MB_2U(SCH_1):PAGE180_I9@PURE_QUANTA.EMMITSBURG_REV0P9(CHIPS)':
 'VSS_AU23': CDS_PINID='VSS_AU23';
NODE_NAME     U4 AU26
 '@S9S_MB_2U_LIB.S9S_MB_2U(SCH_1):PAGE180_I9@PURE_QUANTA.EMMITSBURG_REV0P9(CHIPS)':
 'VSS_AU26': CDS_PINID='VSS_AU26';
NODE_NAME     U4 AU29
 '@S9S_MB_2U_LIB.S9S_MB_2U(SCH_1):PAGE180_I9@PURE_QUANTA.EMMITSBURG_REV0P9(CHIPS)':
 'VSS_AU29': CDS_PINID='VSS_AU29';
NODE_NAME     U4 AU32
 '@S9S_MB_2U_LIB.S9S_MB_2U(SCH_1):PAGE180_I9@PURE_QUANTA.EMMITSBURG_REV0P9(CHIPS)':
 'VSS_AU32': CDS_PINID='VSS_AU32';
NODE_NAME     U4 AU36
 '@S9S_MB_2U_LIB.S9S_MB_2U(SCH_1):PAGE180_I9@PURE_QUANTA.EMMITSBURG_REV0P9(CHIPS)':
 'VSS_AU36': CDS_PINID='VSS_AU36';
NODE_NAME     U4 AV5
 '@S9S_MB_2U_LIB.S9S_MB_2U(SCH_1):PAGE180_I9@PURE_QUANTA.EMMITSBURG_REV0P9(CHIPS)':
 'VSS_AV5': CDS_PINID='VSS_AV5';
NODE_NAME     U4 AV8
 '@S9S_MB_2U_LIB.S9S_MB_2U(SCH_1):PAGE180_I9@PURE_QUANTA.EMMITSBURG_REV0P9(CHIPS)':
 'VSS_AV8': CDS_PINID='VSS_AV8';
NODE_NAME     U4 AV37
 '@S9S_MB_2U_LIB.S9S_MB_2U(SCH_1):PAGE180_I9@PURE_QUANTA.EMMITSBURG_REV0P9(CHIPS)':
 'VSS_AV37': CDS_PINID='VSS_AV37';
NODE_NAME     U4 AV39
 '@S9S_MB_2U_LIB.S9S_MB_2U(SCH_1):PAGE180_I9@PURE_QUANTA.EMMITSBURG_REV0P9(CHIPS)':
 'VSS_AV39': CDS_PINID='VSS_AV39';
NODE_NAME     U4 AW7
 '@S9S_MB_2U_LIB.S9S_MB_2U(SCH_1):PAGE180_I9@PURE_QUANTA.EMMITSBURG_REV0P9(CHIPS)':
 'VSS_AW7': CDS_PINID='VSS_AW7';
NODE_NAME     U4 AY11
 '@S9S_MB_2U_LIB.S9S_MB_2U(SCH_1):PAGE180_I9@PURE_QUANTA.EMMITSBURG_REV0P9(CHIPS)':
 'VSS_AY11': CDS_PINID='VSS_AY11';
NODE_NAME     U4 AY15
 '@S9S_MB_2U_LIB.S9S_MB_2U(SCH_1):PAGE180_I9@PURE_QUANTA.EMMITSBURG_REV0P9(CHIPS)':
 'VSS_AY15': CDS_PINID='VSS_AY15';
NODE_NAME     U4 AY18
 '@S9S_MB_2U_LIB.S9S_MB_2U(SCH_1):PAGE180_I9@PURE_QUANTA.EMMITSBURG_REV0P9(CHIPS)':
 'VSS_AY18': CDS_PINID='VSS_AY18';
NODE_NAME     U4 AY21
 '@S9S_MB_2U_LIB.S9S_MB_2U(SCH_1):PAGE180_I9@PURE_QUANTA.EMMITSBURG_REV0P9(CHIPS)':
 'VSS_AY21': CDS_PINID='VSS_AY21';
NODE_NAME     U4 AY24
 '@S9S_MB_2U_LIB.S9S_MB_2U(SCH_1):PAGE180_I9@PURE_QUANTA.EMMITSBURG_REV0P9(CHIPS)':
 'VSS_AY24': CDS_PINID='VSS_AY24';
NODE_NAME     U4 BB1
 '@S9S_MB_2U_LIB.S9S_MB_2U(SCH_1):PAGE180_I9@PURE_QUANTA.EMMITSBURG_REV0P9(CHIPS)':
 'VSS_BB1': CDS_PINID='VSS_BB1';
NODE_NAME     U4 BC2
 '@S9S_MB_2U_LIB.S9S_MB_2U(SCH_1):PAGE180_I9@PURE_QUANTA.EMMITSBURG_REV0P9(CHIPS)':
 'VSS_BC2': CDS_PINID='VSS_BC2';
NODE_NAME     U4 BC42
 '@S9S_MB_2U_LIB.S9S_MB_2U(SCH_1):PAGE180_I9@PURE_QUANTA.EMMITSBURG_REV0P9(CHIPS)':
 'VSS_BC42': CDS_PINID='VSS_BC42';
NODE_NAME     U4 BD1
 '@S9S_MB_2U_LIB.S9S_MB_2U(SCH_1):PAGE180_I9@PURE_QUANTA.EMMITSBURG_REV0P9(CHIPS)':
 'VSS_BD1': CDS_PINID='VSS_BD1';
NODE_NAME     U4 BD3
 '@S9S_MB_2U_LIB.S9S_MB_2U(SCH_1):PAGE180_I9@PURE_QUANTA.EMMITSBURG_REV0P9(CHIPS)':
 'VSS_BD3': CDS_PINID='VSS_BD3';
NODE_NAME     U4 BD41
 '@S9S_MB_2U_LIB.S9S_MB_2U(SCH_1):PAGE180_I9@PURE_QUANTA.EMMITSBURG_REV0P9(CHIPS)':
 'VSS_BD41': CDS_PINID='VSS_BD41';
NODE_NAME     U4 BD43
 '@S9S_MB_2U_LIB.S9S_MB_2U(SCH_1):PAGE180_I9@PURE_QUANTA.EMMITSBURG_REV0P9(CHIPS)':
 'VSS_BD43': CDS_PINID='VSS_BD43';
NODE_NAME     U4 BE1
 '@S9S_MB_2U_LIB.S9S_MB_2U(SCH_1):PAGE180_I9@PURE_QUANTA.EMMITSBURG_REV0P9(CHIPS)':
 'VSS_BE1': CDS_PINID='VSS_BE1';
NODE_NAME     U4 BE3
 '@S9S_MB_2U_LIB.S9S_MB_2U(SCH_1):PAGE180_I9@PURE_QUANTA.EMMITSBURG_REV0P9(CHIPS)':
 'VSS_BE3': CDS_PINID='VSS_BE3';
NODE_NAME     U4 BE41
 '@S9S_MB_2U_LIB.S9S_MB_2U(SCH_1):PAGE180_I9@PURE_QUANTA.EMMITSBURG_REV0P9(CHIPS)':
 'VSS_BE41': CDS_PINID='VSS_BE41';
NODE_NAME     U4 BE43
 '@S9S_MB_2U_LIB.S9S_MB_2U(SCH_1):PAGE180_I9@PURE_QUANTA.EMMITSBURG_REV0P9(CHIPS)':
 'VSS_BE43': CDS_PINID='VSS_BE43';
NODE_NAME     U4 BG4
 '@S9S_MB_2U_LIB.S9S_MB_2U(SCH_1):PAGE180_I9@PURE_QUANTA.EMMITSBURG_REV0P9(CHIPS)':
 'VSS_BG4': CDS_PINID='VSS_BG4';
NODE_NAME     U4 BG6
 '@S9S_MB_2U_LIB.S9S_MB_2U(SCH_1):PAGE180_I9@PURE_QUANTA.EMMITSBURG_REV0P9(CHIPS)':
 'VSS_BG6': CDS_PINID='VSS_BG6';
NODE_NAME     U4 BG38
 '@S9S_MB_2U_LIB.S9S_MB_2U(SCH_1):PAGE180_I9@PURE_QUANTA.EMMITSBURG_REV0P9(CHIPS)':
 'VSS_BG38': CDS_PINID='VSS_BG38';
NODE_NAME     U4 BG41
 '@S9S_MB_2U_LIB.S9S_MB_2U(SCH_1):PAGE180_I9@PURE_QUANTA.EMMITSBURG_REV0P9(CHIPS)':
 'VSS_BG41': CDS_PINID='VSS_BG41';
NODE_NAME     U4 C3
 '@S9S_MB_2U_LIB.S9S_MB_2U(SCH_1):PAGE180_I9@PURE_QUANTA.EMMITSBURG_REV0P9(CHIPS)':
 'VSS_C3': CDS_PINID='VSS_C3';
NODE_NAME     U4 C41
 '@S9S_MB_2U_LIB.S9S_MB_2U(SCH_1):PAGE180_I9@PURE_QUANTA.EMMITSBURG_REV0P9(CHIPS)':
 'VSS_C41': CDS_PINID='VSS_C41';
NODE_NAME     U4 C43
 '@S9S_MB_2U_LIB.S9S_MB_2U(SCH_1):PAGE180_I9@PURE_QUANTA.EMMITSBURG_REV0P9(CHIPS)':
 'VSS_C43': CDS_PINID='VSS_C43';
NODE_NAME     U4 D1
 '@S9S_MB_2U_LIB.S9S_MB_2U(SCH_1):PAGE180_I9@PURE_QUANTA.EMMITSBURG_REV0P9(CHIPS)':
 'VSS_D1': CDS_PINID='VSS_D1';
NODE_NAME     U4 D3
 '@S9S_MB_2U_LIB.S9S_MB_2U(SCH_1):PAGE180_I9@PURE_QUANTA.EMMITSBURG_REV0P9(CHIPS)':
 'VSS_D3': CDS_PINID='VSS_D3';
NODE_NAME     U4 D41
 '@S9S_MB_2U_LIB.S9S_MB_2U(SCH_1):PAGE180_I9@PURE_QUANTA.EMMITSBURG_REV0P9(CHIPS)':
 'VSS_D41': CDS_PINID='VSS_D41';
NODE_NAME     U4 D43
 '@S9S_MB_2U_LIB.S9S_MB_2U(SCH_1):PAGE180_I9@PURE_QUANTA.EMMITSBURG_REV0P9(CHIPS)':
 'VSS_D43': CDS_PINID='VSS_D43';
NODE_NAME     U4 E2
 '@S9S_MB_2U_LIB.S9S_MB_2U(SCH_1):PAGE180_I9@PURE_QUANTA.EMMITSBURG_REV0P9(CHIPS)':
 'VSS_E2': CDS_PINID='VSS_E2';
NODE_NAME     U4 E42
 '@S9S_MB_2U_LIB.S9S_MB_2U(SCH_1):PAGE180_I9@PURE_QUANTA.EMMITSBURG_REV0P9(CHIPS)':
 'VSS_E42': CDS_PINID='VSS_E42';
NODE_NAME     U4 F43
 '@S9S_MB_2U_LIB.S9S_MB_2U(SCH_1):PAGE180_I9@PURE_QUANTA.EMMITSBURG_REV0P9(CHIPS)':
 'VSS_F43': CDS_PINID='VSS_F43';
NODE_NAME     C1178 2
 '@S9S_MB_2U_LIB.S9S_MB_2U(SCH_1):PAGE181_I6@PURE_QUANTA.Q_CAP(CHIPS)':
 'B': CDS_PINID='B';
NODE_NAME     C1185 2
 '@S9S_MB_2U_LIB.S9S_MB_2U(SCH_1):PAGE181_I7@PURE_QUANTA.Q_CAP(CHIPS)':
 'B': CDS_PINID='B';
NODE_NAME     C1192 2
 '@S9S_MB_2U_LIB.S9S_MB_2U(SCH_1):PAGE181_I8@PURE_QUANTA.Q_CAP(CHIPS)':
 'B': CDS_PINID='B';
NODE_NAME     C1205 2
 '@S9S_MB_2U_LIB.S9S_MB_2U(SCH_1):PAGE181_I12@PURE_QUANTA.Q_CAP(CHIPS)':
 'B': CDS_PINID='B';
NODE_NAME     C1228 2
 '@S9S_MB_2U_LIB.S9S_MB_2U(SCH_1):PAGE181_I13@PURE_QUANTA.Q_CAP(CHIPS)':
 'B': CDS_PINID='B';
NODE_NAME     C1186 2
 '@S9S_MB_2U_LIB.S9S_MB_2U(SCH_1):PAGE181_I25@PURE_QUANTA.Q_CAP(CHIPS)':
 'B': CDS_PINID='B';
NODE_NAME     C1181 2
 '@S9S_MB_2U_LIB.S9S_MB_2U(SCH_1):PAGE181_I27@PURE_QUANTA.Q_CAP(CHIPS)':
 'B': CDS_PINID='B';
NODE_NAME     C1202 2
 '@S9S_MB_2U_LIB.S9S_MB_2U(SCH_1):PAGE181_I29@PURE_QUANTA.Q_CAP(CHIPS)':
 'B': CDS_PINID='B';
NODE_NAME     C1197 2
 '@S9S_MB_2U_LIB.S9S_MB_2U(SCH_1):PAGE181_I30@PURE_QUANTA.Q_CAP(CHIPS)':
 'B': CDS_PINID='B';
NODE_NAME     C1207 2
 '@S9S_MB_2U_LIB.S9S_MB_2U(SCH_1):PAGE181_I32@PURE_QUANTA.Q_CAP(CHIPS)':
 'B': CDS_PINID='B';
NODE_NAME     C1187 2
 '@S9S_MB_2U_LIB.S9S_MB_2U(SCH_1):PAGE181_I40@PURE_QUANTA.Q_CAP(CHIPS)':
 'B': CDS_PINID='B';
NODE_NAME     C1182 2
 '@S9S_MB_2U_LIB.S9S_MB_2U(SCH_1):PAGE181_I42@PURE_QUANTA.Q_CAP(CHIPS)':
 'B': CDS_PINID='B';
NODE_NAME     C1198 2
 '@S9S_MB_2U_LIB.S9S_MB_2U(SCH_1):PAGE181_I43@PURE_QUANTA.Q_CAP(CHIPS)':
 'B': CDS_PINID='B';
NODE_NAME     C1210 2
 '@S9S_MB_2U_LIB.S9S_MB_2U(SCH_1):PAGE181_I45@PURE_QUANTA.Q_CAP(CHIPS)':
 'B': CDS_PINID='B';
NODE_NAME     C1203 2
 '@S9S_MB_2U_LIB.S9S_MB_2U(SCH_1):PAGE181_I48@PURE_QUANTA.Q_CAP(CHIPS)':
 'B': CDS_PINID='B';
NODE_NAME     C1231 2
 '@S9S_MB_2U_LIB.S9S_MB_2U(SCH_1):PAGE181_I49@PURE_QUANTA.Q_CAP(CHIPS)':
 'B': CDS_PINID='B';
NODE_NAME     C1183 2
 '@S9S_MB_2U_LIB.S9S_MB_2U(SCH_1):PAGE181_I51@PURE_QUANTA.Q_CAP(CHIPS)':
 'B': CDS_PINID='B';
NODE_NAME     C1189 2
 '@S9S_MB_2U_LIB.S9S_MB_2U(SCH_1):PAGE181_I58@PURE_QUANTA.Q_CAP(CHIPS)':
 'B': CDS_PINID='B';
NODE_NAME     C1200 2
 '@S9S_MB_2U_LIB.S9S_MB_2U(SCH_1):PAGE181_I59@PURE_QUANTA.Q_CAP(CHIPS)':
 'B': CDS_PINID='B';
NODE_NAME     C1204 2
 '@S9S_MB_2U_LIB.S9S_MB_2U(SCH_1):PAGE181_I60@PURE_QUANTA.Q_CAP(CHIPS)':
 'B': CDS_PINID='B';
NODE_NAME     C1214 2
 '@S9S_MB_2U_LIB.S9S_MB_2U(SCH_1):PAGE181_I61@PURE_QUANTA.Q_CAP(CHIPS)':
 'B': CDS_PINID='B';
NODE_NAME     C1242 2
 '@S9S_MB_2U_LIB.S9S_MB_2U(SCH_1):PAGE181_I63@PURE_QUANTA.Q_CAP(CHIPS)':
 'B': CDS_PINID='B';
NODE_NAME     C1206 2
 '@S9S_MB_2U_LIB.S9S_MB_2U(SCH_1):PAGE181_I78@PURE_QUANTA.Q_CAP(CHIPS)':
 'B': CDS_PINID='B';
NODE_NAME     C1201 2
 '@S9S_MB_2U_LIB.S9S_MB_2U(SCH_1):PAGE181_I87@PURE_QUANTA.Q_CAP(CHIPS)':
 'B': CDS_PINID='B';
NODE_NAME     C1191 2
 '@S9S_MB_2U_LIB.S9S_MB_2U(SCH_1):PAGE181_I89@PURE_QUANTA.Q_CAP(CHIPS)':
 'B': CDS_PINID='B';
NODE_NAME     C1184 2
 '@S9S_MB_2U_LIB.S9S_MB_2U(SCH_1):PAGE181_I91@PURE_QUANTA.Q_CAP(CHIPS)':
 'B': CDS_PINID='B';
NODE_NAME     C1262 2
 '@S9S_MB_2U_LIB.S9S_MB_2U(SCH_1):PAGE181_I104@PURE_QUANTA.Q_CAP(CHIPS)':
 'B': CDS_PINID='B';
NODE_NAME     C1251 2
 '@S9S_MB_2U_LIB.S9S_MB_2U(SCH_1):PAGE181_I110@PURE_QUANTA.Q_CAP(CHIPS)':
 'B': CDS_PINID='B';
NODE_NAME     C1254 2
 '@S9S_MB_2U_LIB.S9S_MB_2U(SCH_1):PAGE181_I111@PURE_QUANTA.Q_CAP(CHIPS)':
 'B': CDS_PINID='B';
NODE_NAME     C1263 2
 '@S9S_MB_2U_LIB.S9S_MB_2U(SCH_1):PAGE181_I119@PURE_QUANTA.Q_CAP(CHIPS)':
 'B': CDS_PINID='B';
NODE_NAME     C1255 2
 '@S9S_MB_2U_LIB.S9S_MB_2U(SCH_1):PAGE181_I123@PURE_QUANTA.Q_CAP(CHIPS)':
 'B': CDS_PINID='B';
NODE_NAME     C1252 2
 '@S9S_MB_2U_LIB.S9S_MB_2U(SCH_1):PAGE181_I125@PURE_QUANTA.Q_CAP(CHIPS)':
 'B': CDS_PINID='B';
NODE_NAME     C1266 2
 '@S9S_MB_2U_LIB.S9S_MB_2U(SCH_1):PAGE181_I127@PURE_QUANTA.Q_CAP(CHIPS)':
 'B': CDS_PINID='B';
NODE_NAME     C1260 2
 '@S9S_MB_2U_LIB.S9S_MB_2U(SCH_1):PAGE181_I131@PURE_QUANTA.Q_CAP(CHIPS)':
 'B': CDS_PINID='B';
NODE_NAME     C1264 2
 '@S9S_MB_2U_LIB.S9S_MB_2U(SCH_1):PAGE181_I133@PURE_QUANTA.Q_CAP(CHIPS)':
 'B': CDS_PINID='B';
NODE_NAME     C1256 2
 '@S9S_MB_2U_LIB.S9S_MB_2U(SCH_1):PAGE181_I136@PURE_QUANTA.Q_CAP(CHIPS)':
 'B': CDS_PINID='B';
NODE_NAME     C1250 2
 '@S9S_MB_2U_LIB.S9S_MB_2U(SCH_1):PAGE181_I137@PURE_QUANTA.Q_CAP(CHIPS)':
 'B': CDS_PINID='B';
NODE_NAME     C1265 2
 '@S9S_MB_2U_LIB.S9S_MB_2U(SCH_1):PAGE181_I140@PURE_QUANTA.Q_CAP(CHIPS)':
 'B': CDS_PINID='B';
NODE_NAME     C1261 2
 '@S9S_MB_2U_LIB.S9S_MB_2U(SCH_1):PAGE181_I142@PURE_QUANTA.Q_CAP(CHIPS)':
 'B': CDS_PINID='B';
NODE_NAME     C1257 2
 '@S9S_MB_2U_LIB.S9S_MB_2U(SCH_1):PAGE181_I146@PURE_QUANTA.Q_CAP(CHIPS)':
 'B': CDS_PINID='B';
NODE_NAME     C1253 2
 '@S9S_MB_2U_LIB.S9S_MB_2U(SCH_1):PAGE181_I147@PURE_QUANTA.Q_CAP(CHIPS)':
 'B': CDS_PINID='B';
NODE_NAME     C1920 2
 '@S9S_MB_2U_LIB.S9S_MB_2U(SCH_1):PAGE182_I88@PURE_QUANTA.Q_CAP(CHIPS)':
 'B': CDS_PINID='B';
NODE_NAME     C1921 2
 '@S9S_MB_2U_LIB.S9S_MB_2U(SCH_1):PAGE182_I90@PURE_QUANTA.Q_CAP(CHIPS)':
 'B': CDS_PINID='B';
NODE_NAME     C1922 2
 '@S9S_MB_2U_LIB.S9S_MB_2U(SCH_1):PAGE182_I96@PURE_QUANTA.Q_CAP(CHIPS)':
 'B': CDS_PINID='B';
NODE_NAME     C1923 2
 '@S9S_MB_2U_LIB.S9S_MB_2U(SCH_1):PAGE182_I97@PURE_QUANTA.Q_CAP(CHIPS)':
 'B': CDS_PINID='B';
NODE_NAME     C1924 2
 '@S9S_MB_2U_LIB.S9S_MB_2U(SCH_1):PAGE182_I98@PURE_QUANTA.Q_CAP(CHIPS)':
 'B': CDS_PINID='B';
NODE_NAME     C1925 2
 '@S9S_MB_2U_LIB.S9S_MB_2U(SCH_1):PAGE182_I100@PURE_QUANTA.Q_CAP(CHIPS)':
 'B': CDS_PINID='B';
NODE_NAME     R1605 2
 '@S9S_MB_2U_LIB.S9S_MB_2U(SCH_1):PAGE182_I105@PURE_QUANTA.Q_RES(CHIPS)':
 'B': CDS_PINID='B';
NODE_NAME     R491 2
 '@S9S_MB_2U_LIB.S9S_MB_2U(SCH_1):PAGE182_I164@PURE_QUANTA.Q_RES(CHIPS)':
 'B': CDS_PINID='B';
NODE_NAME     J59 G1
 '@S9S_MB_2U_LIB.S9S_MB_2U(SCH_1):PAGE182_I178@PURE_QUANTA.SCONN75K_APCI0155P004A(CHIPS)':
 'G1': CDS_PINID='G1';
NODE_NAME     J59 G2
 '@S9S_MB_2U_LIB.S9S_MB_2U(SCH_1):PAGE182_I178@PURE_QUANTA.SCONN75K_APCI0155P004A(CHIPS)':
 'G2': CDS_PINID='G2';
NODE_NAME     J59 3
 '@S9S_MB_2U_LIB.S9S_MB_2U(SCH_1):PAGE182_I178@PURE_QUANTA.SCONN75K_APCI0155P004A(CHIPS)':
 'GND2': CDS_PINID='GND2';
NODE_NAME     J59 9
 '@S9S_MB_2U_LIB.S9S_MB_2U(SCH_1):PAGE182_I178@PURE_QUANTA.SCONN75K_APCI0155P004A(CHIPS)':
 'GND3': CDS_PINID='GND3';
NODE_NAME     J59 15
 '@S9S_MB_2U_LIB.S9S_MB_2U(SCH_1):PAGE182_I178@PURE_QUANTA.SCONN75K_APCI0155P004A(CHIPS)':
 'GND4': CDS_PINID='GND4';
NODE_NAME     J59 21
 '@S9S_MB_2U_LIB.S9S_MB_2U(SCH_1):PAGE182_I178@PURE_QUANTA.SCONN75K_APCI0155P004A(CHIPS)':
 'GND5': CDS_PINID='GND5';
NODE_NAME     J59 27
 '@S9S_MB_2U_LIB.S9S_MB_2U(SCH_1):PAGE182_I178@PURE_QUANTA.SCONN75K_APCI0155P004A(CHIPS)':
 'GND6': CDS_PINID='GND6';
NODE_NAME     J59 33
 '@S9S_MB_2U_LIB.S9S_MB_2U(SCH_1):PAGE182_I178@PURE_QUANTA.SCONN75K_APCI0155P004A(CHIPS)':
 'GND7': CDS_PINID='GND7';
NODE_NAME     J59 39
 '@S9S_MB_2U_LIB.S9S_MB_2U(SCH_1):PAGE182_I178@PURE_QUANTA.SCONN75K_APCI0155P004A(CHIPS)':
 'GND8': CDS_PINID='GND8';
NODE_NAME     J59 45
 '@S9S_MB_2U_LIB.S9S_MB_2U(SCH_1):PAGE182_I178@PURE_QUANTA.SCONN75K_APCI0155P004A(CHIPS)':
 'GND9': CDS_PINID='GND9';
NODE_NAME     J59 51
 '@S9S_MB_2U_LIB.S9S_MB_2U(SCH_1):PAGE182_I178@PURE_QUANTA.SCONN75K_APCI0155P004A(CHIPS)':
 'GND10': CDS_PINID='GND10';
NODE_NAME     J59 57
 '@S9S_MB_2U_LIB.S9S_MB_2U(SCH_1):PAGE182_I178@PURE_QUANTA.SCONN75K_APCI0155P004A(CHIPS)':
 'GND11': CDS_PINID='GND11';
NODE_NAME     J59 71
 '@S9S_MB_2U_LIB.S9S_MB_2U(SCH_1):PAGE182_I178@PURE_QUANTA.SCONN75K_APCI0155P004A(CHIPS)':
 'GND12': CDS_PINID='GND12';
NODE_NAME     J59 73
 '@S9S_MB_2U_LIB.S9S_MB_2U(SCH_1):PAGE182_I178@PURE_QUANTA.SCONN75K_APCI0155P004A(CHIPS)':
 'GND13': CDS_PINID='GND13';
NODE_NAME     J59 75
 '@S9S_MB_2U_LIB.S9S_MB_2U(SCH_1):PAGE182_I178@PURE_QUANTA.SCONN75K_APCI0155P004A(CHIPS)':
 'GND14': CDS_PINID='GND14';
NODE_NAME     U98 1
 '@S9S_MB_2U_LIB.S9S_MB_2U(SCH_1):PAGE183_I27@PURE_QUANTA.PCA9306DP1(CHIPS)':
 'GND': CDS_PINID='GND';
NODE_NAME     C1323 2
 '@S9S_MB_2U_LIB.S9S_MB_2U(SCH_1):PAGE183_I28@PURE_QUANTA.Q_CAP(CHIPS)':
 'B': CDS_PINID='B';
NODE_NAME     C1305 2
 '@S9S_MB_2U_LIB.S9S_MB_2U(SCH_1):PAGE183_I52@PURE_QUANTA.Q_CAP(CHIPS)':
 'B': CDS_PINID='B';
NODE_NAME     U142 2
 '@S9S_MB_2U_LIB.S9S_MB_2U(SCH_1):PAGE185_I35@PURE_QUANTA.NC7SB3157(CHIPS)':
 'GND': CDS_PINID='GND';
NODE_NAME     C1612 2
 '@S9S_MB_2U_LIB.S9S_MB_2U(SCH_1):PAGE185_I36@PURE_QUANTA.Q_CAP(CHIPS)':
 'B': CDS_PINID='B';
NODE_NAME     R2252 2
 '@S9S_MB_2U_LIB.S9S_MB_2U(SCH_1):PAGE185_I42@PURE_QUANTA.Q_RES(CHIPS)':
 'B': CDS_PINID='B';
NODE_NAME     R372 2
 '@S9S_MB_2U_LIB.S9S_MB_2U(SCH_1):PAGE186_I46@PURE_QUANTA.Q_RES(CHIPS)':
 'B': CDS_PINID='B';
NODE_NAME     R375 2
 '@S9S_MB_2U_LIB.S9S_MB_2U(SCH_1):PAGE186_I61@PURE_QUANTA.Q_RES(CHIPS)':
 'B': CDS_PINID='B';
NODE_NAME     R379 2
 '@S9S_MB_2U_LIB.S9S_MB_2U(SCH_1):PAGE186_I76@PURE_QUANTA.Q_RES(CHIPS)':
 'B': CDS_PINID='B';
NODE_NAME     R381 2
 '@S9S_MB_2U_LIB.S9S_MB_2U(SCH_1):PAGE186_I81@PURE_QUANTA.Q_RES(CHIPS)':
 'B': CDS_PINID='B';
NODE_NAME     R1810 2
 '@S9S_MB_2U_LIB.S9S_MB_2U(SCH_1):PAGE186_I88@PURE_QUANTA.Q_RES(CHIPS)':
 'B': CDS_PINID='B';
NODE_NAME     R1962 2
 '@S9S_MB_2U_LIB.S9S_MB_2U(SCH_1):PAGE186_I90@PURE_QUANTA.Q_RES(CHIPS)':
 'B': CDS_PINID='B';
NODE_NAME     R624 2
 '@S9S_MB_2U_LIB.S9S_MB_2U(SCH_1):PAGE187_I14@PURE_QUANTA.Q_RES(CHIPS)':
 'B': CDS_PINID='B';
NODE_NAME     R614 2
 '@S9S_MB_2U_LIB.S9S_MB_2U(SCH_1):PAGE187_I23@PURE_QUANTA.Q_RES(CHIPS)':
 'B': CDS_PINID='B';
NODE_NAME     R608 2
 '@S9S_MB_2U_LIB.S9S_MB_2U(SCH_1):PAGE187_I36@PURE_QUANTA.Q_RES(CHIPS)':
 'B': CDS_PINID='B';
NODE_NAME     R610 2
 '@S9S_MB_2U_LIB.S9S_MB_2U(SCH_1):PAGE187_I40@PURE_QUANTA.Q_RES(CHIPS)':
 'B': CDS_PINID='B';
NODE_NAME     R612 2
 '@S9S_MB_2U_LIB.S9S_MB_2U(SCH_1):PAGE187_I44@PURE_QUANTA.Q_RES(CHIPS)':
 'B': CDS_PINID='B';
NODE_NAME     R618 2
 '@S9S_MB_2U_LIB.S9S_MB_2U(SCH_1):PAGE187_I53@PURE_QUANTA.Q_RES(CHIPS)':
 'B': CDS_PINID='B';
NODE_NAME     R622 2
 '@S9S_MB_2U_LIB.S9S_MB_2U(SCH_1):PAGE187_I56@PURE_QUANTA.Q_RES(CHIPS)':
 'B': CDS_PINID='B';
NODE_NAME     R1299 2
 '@S9S_MB_2U_LIB.S9S_MB_2U(SCH_1):PAGE188_I21@PURE_QUANTA.Q_RES(CHIPS)':
 'B': CDS_PINID='B';
NODE_NAME     R1311 2
 '@S9S_MB_2U_LIB.S9S_MB_2U(SCH_1):PAGE188_I31@PURE_QUANTA.Q_RES(CHIPS)':
 'B': CDS_PINID='B';
NODE_NAME     R1457 2
 '@S9S_MB_2U_LIB.S9S_MB_2U(SCH_1):PAGE188_I36@PURE_QUANTA.Q_RES(CHIPS)':
 'B': CDS_PINID='B';
NODE_NAME     R1476 2
 '@S9S_MB_2U_LIB.S9S_MB_2U(SCH_1):PAGE188_I43@PURE_QUANTA.Q_RES(CHIPS)':
 'B': CDS_PINID='B';
NODE_NAME     R1478 2
 '@S9S_MB_2U_LIB.S9S_MB_2U(SCH_1):PAGE188_I50@PURE_QUANTA.Q_RES(CHIPS)':
 'B': CDS_PINID='B';
NODE_NAME     R1221 2
 '@S9S_MB_2U_LIB.S9S_MB_2U(SCH_1):PAGE188_I64@PURE_QUANTA.Q_RES(CHIPS)':
 'B': CDS_PINID='B';
NODE_NAME     R1497 2
 '@S9S_MB_2U_LIB.S9S_MB_2U(SCH_1):PAGE188_I70@PURE_QUANTA.Q_RES(CHIPS)':
 'B': CDS_PINID='B';
NODE_NAME     R1499 2
 '@S9S_MB_2U_LIB.S9S_MB_2U(SCH_1):PAGE188_I77@PURE_QUANTA.Q_RES(CHIPS)':
 'B': CDS_PINID='B';
NODE_NAME     U60 2
 '@S9S_MB_2U_LIB.S9S_MB_2U(SCH_1):PAGE190_I34@PURE_QUANTA.NC7SB3157(CHIPS)':
 'GND': CDS_PINID='GND';
NODE_NAME     C607 2
 '@S9S_MB_2U_LIB.S9S_MB_2U(SCH_1):PAGE190_I36@PURE_QUANTA.Q_CAP(CHIPS)':
 'B': CDS_PINID='B';
NODE_NAME     C605 2
 '@S9S_MB_2U_LIB.S9S_MB_2U(SCH_1):PAGE190_I37@PURE_QUANTA.Q_CAP(CHIPS)':
 'B': CDS_PINID='B';
NODE_NAME     U61 2
 '@S9S_MB_2U_LIB.S9S_MB_2U(SCH_1):PAGE190_I39@PURE_QUANTA.NC7SB3157(CHIPS)':
 'GND': CDS_PINID='GND';
NODE_NAME     C608 2
 '@S9S_MB_2U_LIB.S9S_MB_2U(SCH_1):PAGE190_I43@PURE_QUANTA.Q_CAP(CHIPS)':
 'B': CDS_PINID='B';
NODE_NAME     C606 2
 '@S9S_MB_2U_LIB.S9S_MB_2U(SCH_1):PAGE190_I45@PURE_QUANTA.Q_CAP(CHIPS)':
 'B': CDS_PINID='B';
NODE_NAME     C1647 2
 '@S9S_MB_2U_LIB.S9S_MB_2U(SCH_1):PAGE190_I84@PURE_QUANTA.Q_CAP(CHIPS)':
 'B': CDS_PINID='B';
NODE_NAME     R1749 2
 '@S9S_MB_2U_LIB.S9S_MB_2U(SCH_1):PAGE190_I89@PURE_QUANTA.Q_RES(CHIPS)':
 'B': CDS_PINID='B';
NODE_NAME     U38 TH
 '@S9S_MB_2U_LIB.S9S_MB_2U(SCH_1):PAGE195_I119@PURE_QUANTA.9QXL2001BNHGI8(CHIPS)':
 'EPAD': CDS_PINID='EPAD';
NODE_NAME     C209 2
 '@S9S_MB_2U_LIB.S9S_MB_2U(SCH_1):PAGE195_I164@PURE_QUANTA.Q_CAP(CHIPS)':
 'B': CDS_PINID='B';
NODE_NAME     C211 2
 '@S9S_MB_2U_LIB.S9S_MB_2U(SCH_1):PAGE195_I165@PURE_QUANTA.Q_CAP(CHIPS)':
 'B': CDS_PINID='B';
NODE_NAME     C208 2
 '@S9S_MB_2U_LIB.S9S_MB_2U(SCH_1):PAGE195_I167@PURE_QUANTA.Q_CAP(CHIPS)':
 'B': CDS_PINID='B';
NODE_NAME     C210 2
 '@S9S_MB_2U_LIB.S9S_MB_2U(SCH_1):PAGE195_I168@PURE_QUANTA.Q_CAP(CHIPS)':
 'B': CDS_PINID='B';
NODE_NAME     C204 2
 '@S9S_MB_2U_LIB.S9S_MB_2U(SCH_1):PAGE195_I171@PURE_QUANTA.Q_CAP(CHIPS)':
 'B': CDS_PINID='B';
NODE_NAME     C205 2
 '@S9S_MB_2U_LIB.S9S_MB_2U(SCH_1):PAGE195_I172@PURE_QUANTA.Q_CAP(CHIPS)':
 'B': CDS_PINID='B';
NODE_NAME     C206 2
 '@S9S_MB_2U_LIB.S9S_MB_2U(SCH_1):PAGE195_I173@PURE_QUANTA.Q_CAP(CHIPS)':
 'B': CDS_PINID='B';
NODE_NAME     C207 2
 '@S9S_MB_2U_LIB.S9S_MB_2U(SCH_1):PAGE195_I174@PURE_QUANTA.Q_CAP(CHIPS)':
 'B': CDS_PINID='B';
NODE_NAME     R568 2
 '@S9S_MB_2U_LIB.S9S_MB_2U(SCH_1):PAGE195_I178@PURE_QUANTA.Q_RES(CHIPS)':
 'B': CDS_PINID='B';
NODE_NAME     R570 2
 '@S9S_MB_2U_LIB.S9S_MB_2U(SCH_1):PAGE195_I187@PURE_QUANTA.Q_RES(CHIPS)':
 'B': CDS_PINID='B';
NODE_NAME     R574 2
 '@S9S_MB_2U_LIB.S9S_MB_2U(SCH_1):PAGE195_I197@PURE_QUANTA.Q_RES(CHIPS)':
 'B': CDS_PINID='B';
NODE_NAME     R106 1
 '@S9S_MB_2U_LIB.S9S_MB_2U(SCH_1):PAGE195_I304@PURE_QUANTA.Q_RES(CHIPS)':
 'A': CDS_PINID='A';
NODE_NAME     C1409 2
 '@S9S_MB_2U_LIB.S9S_MB_2U(SCH_1):PAGE195_I419@PURE_QUANTA.Q_CAP(CHIPS)':
 'B': CDS_PINID='B';
NODE_NAME     U13 C1
 '@S9S_MB_2U_LIB.S9S_MB_2U(SCH_1):PAGE197_I180@PURE_QUANTA.9SQ440NQQI8(CHIPS)':
 'EPAD': CDS_PINID='EPAD';
NODE_NAME     U13 B10
 '@S9S_MB_2U_LIB.S9S_MB_2U(SCH_1):PAGE197_I180@PURE_QUANTA.9SQ440NQQI8(CHIPS)':
 'GNDS': CDS_PINID='GNDS';
NODE_NAME     U13 A14
 '@S9S_MB_2U_LIB.S9S_MB_2U(SCH_1):PAGE197_I180@PURE_QUANTA.9SQ440NQQI8(CHIPS)':
 'GNDXTAL': CDS_PINID='GNDXTAL';
NODE_NAME     U13 B12
 '@S9S_MB_2U_LIB.S9S_MB_2U(SCH_1):PAGE197_I180@PURE_QUANTA.9SQ440NQQI8(CHIPS)':
 'NVGND': CDS_PINID='NVGND';
NODE_NAME     R1484 2
 '@S9S_MB_2U_LIB.S9S_MB_2U(SCH_1):PAGE197_I268@PURE_QUANTA.Q_RES(CHIPS)':
 'B': CDS_PINID='B';
NODE_NAME     R1527 2
 '@S9S_MB_2U_LIB.S9S_MB_2U(SCH_1):PAGE197_I269@PURE_QUANTA.Q_RES(CHIPS)':
 'B': CDS_PINID='B';
NODE_NAME     R1502 2
 '@S9S_MB_2U_LIB.S9S_MB_2U(SCH_1):PAGE197_I270@PURE_QUANTA.Q_RES(CHIPS)':
 'B': CDS_PINID='B';
NODE_NAME     R1500 2
 '@S9S_MB_2U_LIB.S9S_MB_2U(SCH_1):PAGE197_I271@PURE_QUANTA.Q_RES(CHIPS)':
 'B': CDS_PINID='B';
NODE_NAME     R1462 2
 '@S9S_MB_2U_LIB.S9S_MB_2U(SCH_1):PAGE197_I274@PURE_QUANTA.Q_RES(CHIPS)':
 'B': CDS_PINID='B';
NODE_NAME     R1390 2
 '@S9S_MB_2U_LIB.S9S_MB_2U(SCH_1):PAGE197_I275@PURE_QUANTA.Q_RES(CHIPS)':
 'B': CDS_PINID='B';
NODE_NAME     R1267 2
 '@S9S_MB_2U_LIB.S9S_MB_2U(SCH_1):PAGE197_I276@PURE_QUANTA.Q_RES(CHIPS)':
 'B': CDS_PINID='B';
NODE_NAME     R1196 2
 '@S9S_MB_2U_LIB.S9S_MB_2U(SCH_1):PAGE197_I281@PURE_QUANTA.Q_RES(CHIPS)':
 'B': CDS_PINID='B';
NODE_NAME     R953 2
 '@S9S_MB_2U_LIB.S9S_MB_2U(SCH_1):PAGE197_I282@PURE_QUANTA.Q_RES(CHIPS)':
 'B': CDS_PINID='B';
NODE_NAME     R734 2
 '@S9S_MB_2U_LIB.S9S_MB_2U(SCH_1):PAGE197_I283@PURE_QUANTA.Q_RES(CHIPS)':
 'B': CDS_PINID='B';
NODE_NAME     C1324 2
 '@S9S_MB_2U_LIB.S9S_MB_2U(SCH_1):PAGE197_I286@PURE_QUANTA.Q_CAP(CHIPS)':
 'B': CDS_PINID='B';
NODE_NAME     C172 2
 '@S9S_MB_2U_LIB.S9S_MB_2U(SCH_1):PAGE199_I6@PURE_QUANTA.Q_CAP(CHIPS)':
 'B': CDS_PINID='B';
NODE_NAME     C108 2
 '@S9S_MB_2U_LIB.S9S_MB_2U(SCH_1):PAGE199_I19@PURE_QUANTA.Q_CAP(CHIPS)':
 'B': CDS_PINID='B';
NODE_NAME     C1311 2
 '@S9S_MB_2U_LIB.S9S_MB_2U(SCH_1):PAGE199_I43@PURE_QUANTA.Q_CAP(CHIPS)':
 'B': CDS_PINID='B';
NODE_NAME     C1309 2
 '@S9S_MB_2U_LIB.S9S_MB_2U(SCH_1):PAGE199_I44@PURE_QUANTA.Q_CAP(CHIPS)':
 'B': CDS_PINID='B';
NODE_NAME     C1313 2
 '@S9S_MB_2U_LIB.S9S_MB_2U(SCH_1):PAGE199_I48@PURE_QUANTA.Q_CAP(CHIPS)':
 'B': CDS_PINID='B';
NODE_NAME     C1314 2
 '@S9S_MB_2U_LIB.S9S_MB_2U(SCH_1):PAGE199_I53@PURE_QUANTA.Q_CAP(CHIPS)':
 'B': CDS_PINID='B';
NODE_NAME     C1312 2
 '@S9S_MB_2U_LIB.S9S_MB_2U(SCH_1):PAGE199_I58@PURE_QUANTA.Q_CAP(CHIPS)':
 'B': CDS_PINID='B';
NODE_NAME     C1310 2
 '@S9S_MB_2U_LIB.S9S_MB_2U(SCH_1):PAGE199_I59@PURE_QUANTA.Q_CAP(CHIPS)':
 'B': CDS_PINID='B';
NODE_NAME     C2331 2
 '@S9S_MB_2U_LIB.S9S_MB_2U(SCH_1):PAGE200_I5@PURE_QUANTA.Q_CAP(CHIPS)':
 'B': CDS_PINID='B';
NODE_NAME     C2332 2
 '@S9S_MB_2U_LIB.S9S_MB_2U(SCH_1):PAGE200_I10@PURE_QUANTA.Q_CAP(CHIPS)':
 'B': CDS_PINID='B';
NODE_NAME     U89 S
 '@S9S_MB_2U_LIB.S9S_MB_2U(SCH_1):PAGE207_I236@PURE_QUANTA.MOSFET_N(CHIPS)':
 'SOURCE': CDS_PINID='SOURCE';
NODE_NAME     R2339 2
 '@S9S_MB_2U_LIB.S9S_MB_2U(SCH_1):PAGE207_I268@PURE_QUANTA.Q_RES(CHIPS)':
 'B': CDS_PINID='B';
NODE_NAME     R1415 2
 '@S9S_MB_2U_LIB.S9S_MB_2U(SCH_1):PAGE208_I4@PURE_QUANTA.Q_RES(CHIPS)':
 'B': CDS_PINID='B';
NODE_NAME     R1416 2
 '@S9S_MB_2U_LIB.S9S_MB_2U(SCH_1):PAGE208_I5@PURE_QUANTA.Q_RES(CHIPS)':
 'B': CDS_PINID='B';
NODE_NAME     R1418 2
 '@S9S_MB_2U_LIB.S9S_MB_2U(SCH_1):PAGE208_I6@PURE_QUANTA.Q_RES(CHIPS)':
 'B': CDS_PINID='B';
NODE_NAME     R1417 2
 '@S9S_MB_2U_LIB.S9S_MB_2U(SCH_1):PAGE208_I7@PURE_QUANTA.Q_RES(CHIPS)':
 'B': CDS_PINID='B';
NODE_NAME     R1419 2
 '@S9S_MB_2U_LIB.S9S_MB_2U(SCH_1):PAGE208_I8@PURE_QUANTA.Q_RES(CHIPS)':
 'B': CDS_PINID='B';
NODE_NAME     R1420 2
 '@S9S_MB_2U_LIB.S9S_MB_2U(SCH_1):PAGE208_I9@PURE_QUANTA.Q_RES(CHIPS)':
 'B': CDS_PINID='B';
NODE_NAME     R1421 2
 '@S9S_MB_2U_LIB.S9S_MB_2U(SCH_1):PAGE208_I10@PURE_QUANTA.Q_RES(CHIPS)':
 'B': CDS_PINID='B';
NODE_NAME     R1326 2
 '@S9S_MB_2U_LIB.S9S_MB_2U(SCH_1):PAGE208_I11@PURE_QUANTA.Q_RES(CHIPS)':
 'B': CDS_PINID='B';
NODE_NAME     R1302 2
 '@S9S_MB_2U_LIB.S9S_MB_2U(SCH_1):PAGE208_I12@PURE_QUANTA.Q_RES(CHIPS)':
 'B': CDS_PINID='B';
NODE_NAME     R1328 2
 '@S9S_MB_2U_LIB.S9S_MB_2U(SCH_1):PAGE208_I13@PURE_QUANTA.Q_RES(CHIPS)':
 'B': CDS_PINID='B';
NODE_NAME     R1327 2
 '@S9S_MB_2U_LIB.S9S_MB_2U(SCH_1):PAGE208_I14@PURE_QUANTA.Q_RES(CHIPS)':
 'B': CDS_PINID='B';
NODE_NAME     R1329 2
 '@S9S_MB_2U_LIB.S9S_MB_2U(SCH_1):PAGE208_I15@PURE_QUANTA.Q_RES(CHIPS)':
 'B': CDS_PINID='B';
NODE_NAME     R1330 2
 '@S9S_MB_2U_LIB.S9S_MB_2U(SCH_1):PAGE208_I16@PURE_QUANTA.Q_RES(CHIPS)':
 'B': CDS_PINID='B';
NODE_NAME     R1388 2
 '@S9S_MB_2U_LIB.S9S_MB_2U(SCH_1):PAGE208_I17@PURE_QUANTA.Q_RES(CHIPS)':
 'B': CDS_PINID='B';
NODE_NAME     R990 2
 '@S9S_MB_2U_LIB.S9S_MB_2U(SCH_1):PAGE208_I18@PURE_QUANTA.Q_RES(CHIPS)':
 'B': CDS_PINID='B';
NODE_NAME     R4533 2
 '@S9S_MB_2U_LIB.S9S_MB_2U(SCH_1):PAGE208_I19@PURE_QUANTA.Q_RES(CHIPS)':
 'B': CDS_PINID='B';
NODE_NAME     R991 2
 '@S9S_MB_2U_LIB.S9S_MB_2U(SCH_1):PAGE208_I20@PURE_QUANTA.Q_RES(CHIPS)':
 'B': CDS_PINID='B';
NODE_NAME     R992 2
 '@S9S_MB_2U_LIB.S9S_MB_2U(SCH_1):PAGE208_I21@PURE_QUANTA.Q_RES(CHIPS)':
 'B': CDS_PINID='B';
NODE_NAME     R1398 2
 '@S9S_MB_2U_LIB.S9S_MB_2U(SCH_1):PAGE208_I22@PURE_QUANTA.Q_RES(CHIPS)':
 'B': CDS_PINID='B';
NODE_NAME     R1402 2
 '@S9S_MB_2U_LIB.S9S_MB_2U(SCH_1):PAGE208_I23@PURE_QUANTA.Q_RES(CHIPS)':
 'B': CDS_PINID='B';
NODE_NAME     R1403 2
 '@S9S_MB_2U_LIB.S9S_MB_2U(SCH_1):PAGE208_I24@PURE_QUANTA.Q_RES(CHIPS)':
 'B': CDS_PINID='B';
NODE_NAME     R1404 2
 '@S9S_MB_2U_LIB.S9S_MB_2U(SCH_1):PAGE208_I25@PURE_QUANTA.Q_RES(CHIPS)':
 'B': CDS_PINID='B';
NODE_NAME     R1405 2
 '@S9S_MB_2U_LIB.S9S_MB_2U(SCH_1):PAGE208_I26@PURE_QUANTA.Q_RES(CHIPS)':
 'B': CDS_PINID='B';
NODE_NAME     R1406 2
 '@S9S_MB_2U_LIB.S9S_MB_2U(SCH_1):PAGE208_I51@PURE_QUANTA.Q_RES(CHIPS)':
 'B': CDS_PINID='B';
NODE_NAME     R1407 2
 '@S9S_MB_2U_LIB.S9S_MB_2U(SCH_1):PAGE208_I52@PURE_QUANTA.Q_RES(CHIPS)':
 'B': CDS_PINID='B';
NODE_NAME     R1408 2
 '@S9S_MB_2U_LIB.S9S_MB_2U(SCH_1):PAGE208_I53@PURE_QUANTA.Q_RES(CHIPS)':
 'B': CDS_PINID='B';
NODE_NAME     R1410 2
 '@S9S_MB_2U_LIB.S9S_MB_2U(SCH_1):PAGE208_I54@PURE_QUANTA.Q_RES(CHIPS)':
 'B': CDS_PINID='B';
NODE_NAME     R1409 2
 '@S9S_MB_2U_LIB.S9S_MB_2U(SCH_1):PAGE208_I55@PURE_QUANTA.Q_RES(CHIPS)':
 'B': CDS_PINID='B';
NODE_NAME     R1411 2
 '@S9S_MB_2U_LIB.S9S_MB_2U(SCH_1):PAGE208_I56@PURE_QUANTA.Q_RES(CHIPS)':
 'B': CDS_PINID='B';
NODE_NAME     R1412 2
 '@S9S_MB_2U_LIB.S9S_MB_2U(SCH_1):PAGE208_I57@PURE_QUANTA.Q_RES(CHIPS)':
 'B': CDS_PINID='B';
NODE_NAME     R1414 2
 '@S9S_MB_2U_LIB.S9S_MB_2U(SCH_1):PAGE208_I58@PURE_QUANTA.Q_RES(CHIPS)':
 'B': CDS_PINID='B';
NODE_NAME     R1413 2
 '@S9S_MB_2U_LIB.S9S_MB_2U(SCH_1):PAGE208_I59@PURE_QUANTA.Q_RES(CHIPS)':
 'B': CDS_PINID='B';
NODE_NAME     R930 2
 '@S9S_MB_2U_LIB.S9S_MB_2U(SCH_1):PAGE210_I63@PURE_QUANTA.Q_RES(CHIPS)':
 'B': CDS_PINID='B';
NODE_NAME     R920 2
 '@S9S_MB_2U_LIB.S9S_MB_2U(SCH_1):PAGE210_I76@PURE_QUANTA.Q_RES(CHIPS)':
 'B': CDS_PINID='B';
NODE_NAME     U70 S
 '@S9S_MB_2U_LIB.S9S_MB_2U(SCH_1):PAGE212_I19@PURE_QUANTA.MOSFET_N(CHIPS)':
 'SOURCE': CDS_PINID='SOURCE';
NODE_NAME     R1541 1
 '@S9S_MB_2U_LIB.S9S_MB_2U(SCH_1):PAGE212_I92@PURE_QUANTA.Q_RES(CHIPS)':
 'A': CDS_PINID='A';
NODE_NAME     R537 2
 '@S9S_MB_2U_LIB.S9S_MB_2U(SCH_1):PAGE219_I2@PURE_QUANTA.Q_RES(CHIPS)':
 'B': CDS_PINID='B';
NODE_NAME     R539 2
 '@S9S_MB_2U_LIB.S9S_MB_2U(SCH_1):PAGE219_I6@PURE_QUANTA.Q_RES(CHIPS)':
 'B': CDS_PINID='B';
NODE_NAME     C561 2
 '@S9S_MB_2U_LIB.S9S_MB_2U(SCH_1):PAGE223_I18@PURE_QUANTA.Q_CAP(CHIPS)':
 'B': CDS_PINID='B';
NODE_NAME     C559 2
 '@S9S_MB_2U_LIB.S9S_MB_2U(SCH_1):PAGE223_I20@PURE_QUANTA.Q_CAP(CHIPS)':
 'B': CDS_PINID='B';
NODE_NAME     C562 2
 '@S9S_MB_2U_LIB.S9S_MB_2U(SCH_1):PAGE223_I31@PURE_QUANTA.Q_CAP(CHIPS)':
 'B': CDS_PINID='B';
NODE_NAME     U28 4
 '@S9S_MB_2U_LIB.S9S_MB_2U(SCH_1):PAGE223_I39@PURE_QUANTA.PCA9617ADP(CHIPS)':
 'GND': CDS_PINID='GND';
NODE_NAME     C560 2
 '@S9S_MB_2U_LIB.S9S_MB_2U(SCH_1):PAGE223_I42@PURE_QUANTA.Q_CAP(CHIPS)':
 'B': CDS_PINID='B';
NODE_NAME     U29 4
 '@S9S_MB_2U_LIB.S9S_MB_2U(SCH_1):PAGE223_I43@PURE_QUANTA.PCA9617ADP(CHIPS)':
 'GND': CDS_PINID='GND';
NODE_NAME     JP7 2
 '@S9S_MB_2U_LIB.S9S_MB_2U(SCH_1):PAGE223_I64@PURE_QUANTA.CONN3_210HP1030BR1(CHIPS)':
 '2': CDS_PINID='\2\';
NODE_NAME     C569 2
 '@S9S_MB_2U_LIB.S9S_MB_2U(SCH_1):PAGE224_I22@PURE_QUANTA.Q_CAP(CHIPS)':
 'B': CDS_PINID='B';
NODE_NAME     C567 2
 '@S9S_MB_2U_LIB.S9S_MB_2U(SCH_1):PAGE224_I25@PURE_QUANTA.Q_CAP(CHIPS)':
 'B': CDS_PINID='B';
NODE_NAME     U30 4
 '@S9S_MB_2U_LIB.S9S_MB_2U(SCH_1):PAGE224_I28@PURE_QUANTA.PCA9517AD(CHIPS)':
 'GND': CDS_PINID='GND';
NODE_NAME     C570 2
 '@S9S_MB_2U_LIB.S9S_MB_2U(SCH_1):PAGE224_I33@PURE_QUANTA.Q_CAP(CHIPS)':
 'B': CDS_PINID='B';
NODE_NAME     C568 2
 '@S9S_MB_2U_LIB.S9S_MB_2U(SCH_1):PAGE224_I35@PURE_QUANTA.Q_CAP(CHIPS)':
 'B': CDS_PINID='B';
NODE_NAME     U31 4
 '@S9S_MB_2U_LIB.S9S_MB_2U(SCH_1):PAGE224_I37@PURE_QUANTA.PCA9517AD(CHIPS)':
 'GND': CDS_PINID='GND';
NODE_NAME     C1613 2
 '@S9S_MB_2U_LIB.S9S_MB_2U(SCH_1):PAGE224_I68@PURE_QUANTA.Q_CAP(CHIPS)':
 'B': CDS_PINID='B';
NODE_NAME     R2309 2
 '@S9S_MB_2U_LIB.S9S_MB_2U(SCH_1):PAGE224_I85@PURE_QUANTA.Q_RES(CHIPS)':
 'B': CDS_PINID='B';
NODE_NAME     R2311 2
 '@S9S_MB_2U_LIB.S9S_MB_2U(SCH_1):PAGE224_I86@PURE_QUANTA.Q_RES(CHIPS)':
 'B': CDS_PINID='B';
NODE_NAME     R1347 2
 '@S9S_MB_2U_LIB.S9S_MB_2U(SCH_1):PAGE226_I10@PURE_QUANTA.Q_RES(CHIPS)':
 'B': CDS_PINID='B';
NODE_NAME     C1291 2
 '@S9S_MB_2U_LIB.S9S_MB_2U(SCH_1):PAGE226_I16@PURE_QUANTA.Q_CAP(CHIPS)':
 'B': CDS_PINID='B';
NODE_NAME     U84 7
 '@S9S_MB_2U_LIB.S9S_MB_2U(SCH_1):PAGE226_I18@PURE_QUANTA.GTL2014PW(CHIPS)':
 'GND_0': CDS_PINID='GND_0';
NODE_NAME     U84 8
 '@S9S_MB_2U_LIB.S9S_MB_2U(SCH_1):PAGE226_I18@PURE_QUANTA.GTL2014PW(CHIPS)':
 'GND_1': CDS_PINID='GND_1';
NODE_NAME     U84 11
 '@S9S_MB_2U_LIB.S9S_MB_2U(SCH_1):PAGE226_I18@PURE_QUANTA.GTL2014PW(CHIPS)':
 'GND_2': CDS_PINID='GND_2';
NODE_NAME     C1322 2
 '@S9S_MB_2U_LIB.S9S_MB_2U(SCH_1):PAGE226_I27@PURE_QUANTA.Q_CAP(CHIPS)':
 'B': CDS_PINID='B';
NODE_NAME     R1346 2
 '@S9S_MB_2U_LIB.S9S_MB_2U(SCH_1):PAGE226_I34@PURE_QUANTA.Q_RES(CHIPS)':
 'B': CDS_PINID='B';
NODE_NAME     U97 5
 '@S9S_MB_2U_LIB.S9S_MB_2U(SCH_1):PAGE226_I38@PURE_QUANTA.NX3L2267GM(CHIPS)':
 'GND': CDS_PINID='GND';
NODE_NAME     C1290 2
 '@S9S_MB_2U_LIB.S9S_MB_2U(SCH_1):PAGE226_I43@PURE_QUANTA.Q_CAP(CHIPS)':
 'B': CDS_PINID='B';
NODE_NAME     U83 7
 '@S9S_MB_2U_LIB.S9S_MB_2U(SCH_1):PAGE226_I45@PURE_QUANTA.GTL2014PW(CHIPS)':
 'GND_0': CDS_PINID='GND_0';
NODE_NAME     U83 8
 '@S9S_MB_2U_LIB.S9S_MB_2U(SCH_1):PAGE226_I45@PURE_QUANTA.GTL2014PW(CHIPS)':
 'GND_1': CDS_PINID='GND_1';
NODE_NAME     U83 11
 '@S9S_MB_2U_LIB.S9S_MB_2U(SCH_1):PAGE226_I45@PURE_QUANTA.GTL2014PW(CHIPS)':
 'GND_2': CDS_PINID='GND_2';
NODE_NAME     R1369 2
 '@S9S_MB_2U_LIB.S9S_MB_2U(SCH_1):PAGE226_I47@PURE_QUANTA.Q_RES(CHIPS)':
 'B': CDS_PINID='B';
NODE_NAME     R1368 2
 '@S9S_MB_2U_LIB.S9S_MB_2U(SCH_1):PAGE226_I48@PURE_QUANTA.Q_RES(CHIPS)':
 'B': CDS_PINID='B';
NODE_NAME     C1321 2
 '@S9S_MB_2U_LIB.S9S_MB_2U(SCH_1):PAGE226_I55@PURE_QUANTA.Q_CAP(CHIPS)':
 'B': CDS_PINID='B';
NODE_NAME     U96 5
 '@S9S_MB_2U_LIB.S9S_MB_2U(SCH_1):PAGE226_I68@PURE_QUANTA.NX3L2267GM(CHIPS)':
 'GND': CDS_PINID='GND';
NODE_NAME     R1814 2
 '@S9S_MB_2U_LIB.S9S_MB_2U(SCH_1):PAGE226_I77@PURE_QUANTA.Q_RES(CHIPS)':
 'B': CDS_PINID='B';
NODE_NAME     U64 4
 '@S9S_MB_2U_LIB.S9S_MB_2U(SCH_1):PAGE231_I35@PURE_QUANTA.M24128BWMN6TP(CHIPS)':
 'VSS': CDS_PINID='VSS';
NODE_NAME     R718 2
 '@S9S_MB_2U_LIB.S9S_MB_2U(SCH_1):PAGE231_I50@PURE_QUANTA.Q_RES(CHIPS)':
 'B': CDS_PINID='B';
NODE_NAME     R714 2
 '@S9S_MB_2U_LIB.S9S_MB_2U(SCH_1):PAGE231_I52@PURE_QUANTA.Q_RES(CHIPS)':
 'B': CDS_PINID='B';
NODE_NAME     C629 2
 '@S9S_MB_2U_LIB.S9S_MB_2U(SCH_1):PAGE231_I55@PURE_QUANTA.Q_CAP(CHIPS)':
 'B': CDS_PINID='B';
NODE_NAME     R710 2
 '@S9S_MB_2U_LIB.S9S_MB_2U(SCH_1):PAGE231_I57@PURE_QUANTA.Q_RES(CHIPS)':
 'B': CDS_PINID='B';
NODE_NAME     R722 2
 '@S9S_MB_2U_LIB.S9S_MB_2U(SCH_1):PAGE231_I61@PURE_QUANTA.Q_RES(CHIPS)':
 'B': CDS_PINID='B';
NODE_NAME     C1319 2
 '@S9S_MB_2U_LIB.S9S_MB_2U(SCH_1):PAGE232_I35@PURE_QUANTA.Q_CAP(CHIPS)':
 'B': CDS_PINID='B';
NODE_NAME     C1316 2
 '@S9S_MB_2U_LIB.S9S_MB_2U(SCH_1):PAGE232_I47@PURE_QUANTA.Q_CAP(CHIPS)':
 'B': CDS_PINID='B';
NODE_NAME     U103 1
 '@S9S_MB_2U_LIB.S9S_MB_2U(SCH_1):PAGE240_I22@PURE_QUANTA.INA183A1IDBVR(CHIPS)':
 'GND0': CDS_PINID='GND0';
NODE_NAME     U103 2
 '@S9S_MB_2U_LIB.S9S_MB_2U(SCH_1):PAGE240_I22@PURE_QUANTA.INA183A1IDBVR(CHIPS)':
 'GND1': CDS_PINID='GND1';
NODE_NAME     C535 2
 '@S9S_MB_2U_LIB.S9S_MB_2U(SCH_1):PAGE243_I4@PURE_QUANTA.Q_CAP(CHIPS)':
 'B': CDS_PINID='B';
NODE_NAME     C513 2
 '@S9S_MB_2U_LIB.S9S_MB_2U(SCH_1):PAGE243_I5@PURE_QUANTA.Q_CAP(CHIPS)':
 'B': CDS_PINID='B';
NODE_NAME     R1764 2
 '@S9S_MB_2U_LIB.S9S_MB_2U(SCH_1):PAGE243_I8@PURE_QUANTA.Q_RES(CHIPS)':
 'B': CDS_PINID='B';
NODE_NAME     PR91 2
 '@S9S_MB_2U_LIB.S9S_MB_2U(SCH_1):PAGE244_I25@PURE_QUANTA.Q_RES(CHIPS)':
 'B': CDS_PINID='B';
NODE_NAME     PC1856 2
 '@S9S_MB_2U_LIB.S9S_MB_2U(SCH_1):PAGE244_I34@PURE_QUANTA.Q_CAP(CHIPS)':
 'B': CDS_PINID='B';
NODE_NAME     PC2286 2
 '@S9S_MB_2U_LIB.S9S_MB_2U(SCH_1):PAGE248_I8@PURE_QUANTA.Q_CAP(CHIPS)':
 'B': CDS_PINID='B';
NODE_NAME     PC1219 2
 '@S9S_MB_2U_LIB.S9S_MB_2U(SCH_1):PAGE248_I30@PURE_QUANTA.Q_CAP(CHIPS)':
 'B': CDS_PINID='B';
NODE_NAME     PC1227 2
 '@S9S_MB_2U_LIB.S9S_MB_2U(SCH_1):PAGE248_I41@PURE_QUANTA.Q_CAPP(CHIPS)':
 'B': CDS_PINID='B';
NODE_NAME     PU74 11
 '@S9S_MB_2U_LIB.S9S_MB_2U(SCH_1):PAGE249_I26@PURE_QUANTA.NB682GDZ(CHIPS)':
 'AGND': CDS_PINID='AGND';
NODE_NAME     PU74 4
 '@S9S_MB_2U_LIB.S9S_MB_2U(SCH_1):PAGE249_I26@PURE_QUANTA.NB682GDZ(CHIPS)':
 'C0': CDS_PINID='C0';
NODE_NAME     PU74 2
 '@S9S_MB_2U_LIB.S9S_MB_2U(SCH_1):PAGE249_I26@PURE_QUANTA.NB682GDZ(CHIPS)':
 'PGND': CDS_PINID='PGND';
NODE_NAME     PC1236 2
 '@S9S_MB_2U_LIB.S9S_MB_2U(SCH_1):PAGE249_I28@PURE_QUANTA.Q_CAP(CHIPS)':
 'B': CDS_PINID='B';
NODE_NAME     PC1240 2
 '@S9S_MB_2U_LIB.S9S_MB_2U(SCH_1):PAGE249_I39@PURE_QUANTA.Q_CAP(CHIPS)':
 'B': CDS_PINID='B';
NODE_NAME     PC1355 1
 '@S9S_MB_2U_LIB.S9S_MB_2U(SCH_1):PAGE253_I11@PURE_QUANTA.Q_CAP(CHIPS)':
 'A': CDS_PINID='A';
NODE_NAME     PC298_P0_2 2
 '@S9S_MB_2U_LIB.S9S_MB_2U(SCH_1):PAGE253_I22@PURE_QUANTA.Q_CAP(CHIPS)':
 'B': CDS_PINID='B';
NODE_NAME     PC304_P0_2 2
 '@S9S_MB_2U_LIB.S9S_MB_2U(SCH_1):PAGE253_I24@PURE_QUANTA.Q_CAP(CHIPS)':
 'B': CDS_PINID='B';
NODE_NAME     PC293 2
 '@S9S_MB_2U_LIB.S9S_MB_2U(SCH_1):PAGE253_I36@PURE_QUANTA.Q_CAP(CHIPS)':
 'B': CDS_PINID='B';
NODE_NAME     PC295_P0_1 2
 '@S9S_MB_2U_LIB.S9S_MB_2U(SCH_1):PAGE253_I39@PURE_QUANTA.Q_CAP(CHIPS)':
 'B': CDS_PINID='B';
NODE_NAME     PU13_P0_1 2
 '@S9S_MB_2U_LIB.S9S_MB_2U(SCH_1):PAGE253_I40@PURE_QUANTA.ISL99390FRZTR5935(CHIPS)':
 'AGND': CDS_PINID='AGND';
NODE_NAME     PU13_P0_1 5
 '@S9S_MB_2U_LIB.S9S_MB_2U(SCH_1):PAGE253_I40@PURE_QUANTA.ISL99390FRZTR5935(CHIPS)':
 'PGND1': CDS_PINID='PGND1';
NODE_NAME     PU13_P0_1 7_9-20_24
 '@S9S_MB_2U_LIB.S9S_MB_2U(SCH_1):PAGE253_I40@PURE_QUANTA.ISL99390FRZTR5935(CHIPS)':
 'PGND2': CDS_PINID='PGND2';
NODE_NAME     PU13_P0_1 40
 '@S9S_MB_2U_LIB.S9S_MB_2U(SCH_1):PAGE253_I40@PURE_QUANTA.ISL99390FRZTR5935(CHIPS)':
 'PGND3': CDS_PINID='PGND3';
NODE_NAME     PC306_P0_2 2
 '@S9S_MB_2U_LIB.S9S_MB_2U(SCH_1):PAGE253_I54@PURE_QUANTA.Q_CAP(CHIPS)':
 'B': CDS_PINID='B';
NODE_NAME     PC16 2
 '@S9S_MB_2U_LIB.S9S_MB_2U(SCH_1):PAGE253_I56@PURE_QUANTA.Q_CAPP(CHIPS)':
 'B': CDS_PINID='B';
NODE_NAME     PC319 2
 '@S9S_MB_2U_LIB.S9S_MB_2U(SCH_1):PAGE253_I62@PURE_QUANTA.Q_CAPP(CHIPS)':
 'B': CDS_PINID='B';
NODE_NAME     PC310_P0_1 2
 '@S9S_MB_2U_LIB.S9S_MB_2U(SCH_1):PAGE253_I84@PURE_QUANTA.Q_CAP(CHIPS)':
 'B': CDS_PINID='B';
NODE_NAME     PR144 2
 '@S9S_MB_2U_LIB.S9S_MB_2U(SCH_1):PAGE254_I2@PURE_QUANTA.Q_RES(CHIPS)':
 'B': CDS_PINID='B';
NODE_NAME     PU10_P0_4 2
 '@S9S_MB_2U_LIB.S9S_MB_2U(SCH_1):PAGE254_I13@PURE_QUANTA.ISL99390FRZTR5935(CHIPS)':
 'AGND': CDS_PINID='AGND';
NODE_NAME     PU10_P0_4 5
 '@S9S_MB_2U_LIB.S9S_MB_2U(SCH_1):PAGE254_I13@PURE_QUANTA.ISL99390FRZTR5935(CHIPS)':
 'PGND1': CDS_PINID='PGND1';
NODE_NAME     PU10_P0_4 7_9-20_24
 '@S9S_MB_2U_LIB.S9S_MB_2U(SCH_1):PAGE254_I13@PURE_QUANTA.ISL99390FRZTR5935(CHIPS)':
 'PGND2': CDS_PINID='PGND2';
NODE_NAME     PU10_P0_4 40
 '@S9S_MB_2U_LIB.S9S_MB_2U(SCH_1):PAGE254_I13@PURE_QUANTA.ISL99390FRZTR5935(CHIPS)':
 'PGND3': CDS_PINID='PGND3';
NODE_NAME     PC272_P0_4 2
 '@S9S_MB_2U_LIB.S9S_MB_2U(SCH_1):PAGE254_I17@PURE_QUANTA.Q_CAP(CHIPS)':
 'B': CDS_PINID='B';
NODE_NAME     PC1341 1
 '@S9S_MB_2U_LIB.S9S_MB_2U(SCH_1):PAGE254_I26@PURE_QUANTA.Q_CAP(CHIPS)':
 'A': CDS_PINID='A';
NODE_NAME     PC273_P0_3 2
 '@S9S_MB_2U_LIB.S9S_MB_2U(SCH_1):PAGE254_I30@PURE_QUANTA.Q_CAP(CHIPS)':
 'B': CDS_PINID='B';
NODE_NAME     PC274_P0_4 2
 '@S9S_MB_2U_LIB.S9S_MB_2U(SCH_1):PAGE254_I35@PURE_QUANTA.Q_CAP(CHIPS)':
 'B': CDS_PINID='B';
NODE_NAME     PC276_P0_4 2
 '@S9S_MB_2U_LIB.S9S_MB_2U(SCH_1):PAGE254_I38@PURE_QUANTA.Q_CAP(CHIPS)':
 'B': CDS_PINID='B';
NODE_NAME     PC280_P0_4 2
 '@S9S_MB_2U_LIB.S9S_MB_2U(SCH_1):PAGE254_I39@PURE_QUANTA.Q_CAP(CHIPS)':
 'B': CDS_PINID='B';
NODE_NAME     PC282_P0_4 2
 '@S9S_MB_2U_LIB.S9S_MB_2U(SCH_1):PAGE254_I40@PURE_QUANTA.Q_CAP(CHIPS)':
 'B': CDS_PINID='B';
NODE_NAME     PC275_P0_3 2
 '@S9S_MB_2U_LIB.S9S_MB_2U(SCH_1):PAGE254_I48@PURE_QUANTA.Q_CAP(CHIPS)':
 'B': CDS_PINID='B';
NODE_NAME     PC281_P0_3 2
 '@S9S_MB_2U_LIB.S9S_MB_2U(SCH_1):PAGE254_I53@PURE_QUANTA.Q_CAP(CHIPS)':
 'B': CDS_PINID='B';
NODE_NAME     PC285_P0_3 2
 '@S9S_MB_2U_LIB.S9S_MB_2U(SCH_1):PAGE254_I56@PURE_QUANTA.Q_CAP(CHIPS)':
 'B': CDS_PINID='B';
NODE_NAME     PR138 2
 '@S9S_MB_2U_LIB.S9S_MB_2U(SCH_1):PAGE255_I2@PURE_QUANTA.Q_RES(CHIPS)':
 'B': CDS_PINID='B';
NODE_NAME     PC1342 1
 '@S9S_MB_2U_LIB.S9S_MB_2U(SCH_1):PAGE255_I11@PURE_QUANTA.Q_CAP(CHIPS)':
 'A': CDS_PINID='A';
NODE_NAME     PU8_P0_6 2
 '@S9S_MB_2U_LIB.S9S_MB_2U(SCH_1):PAGE255_I12@PURE_QUANTA.ISL99390FRZTR5935(CHIPS)':
 'AGND': CDS_PINID='AGND';
NODE_NAME     PU8_P0_6 5
 '@S9S_MB_2U_LIB.S9S_MB_2U(SCH_1):PAGE255_I12@PURE_QUANTA.ISL99390FRZTR5935(CHIPS)':
 'PGND1': CDS_PINID='PGND1';
NODE_NAME     PU8_P0_6 7_9-20_24
 '@S9S_MB_2U_LIB.S9S_MB_2U(SCH_1):PAGE255_I12@PURE_QUANTA.ISL99390FRZTR5935(CHIPS)':
 'PGND2': CDS_PINID='PGND2';
NODE_NAME     PU8_P0_6 40
 '@S9S_MB_2U_LIB.S9S_MB_2U(SCH_1):PAGE255_I12@PURE_QUANTA.ISL99390FRZTR5935(CHIPS)':
 'PGND3': CDS_PINID='PGND3';
NODE_NAME     PC250_P0_6 2
 '@S9S_MB_2U_LIB.S9S_MB_2U(SCH_1):PAGE255_I17@PURE_QUANTA.Q_CAP(CHIPS)':
 'B': CDS_PINID='B';
NODE_NAME     PC252_P0_6 2
 '@S9S_MB_2U_LIB.S9S_MB_2U(SCH_1):PAGE255_I34@PURE_QUANTA.Q_CAP(CHIPS)':
 'B': CDS_PINID='B';
NODE_NAME     PC254_P0_6 2
 '@S9S_MB_2U_LIB.S9S_MB_2U(SCH_1):PAGE255_I37@PURE_QUANTA.Q_CAP(CHIPS)':
 'B': CDS_PINID='B';
NODE_NAME     PC258_P0_6 2
 '@S9S_MB_2U_LIB.S9S_MB_2U(SCH_1):PAGE255_I38@PURE_QUANTA.Q_CAP(CHIPS)':
 'B': CDS_PINID='B';
NODE_NAME     PC260_P0_6 2
 '@S9S_MB_2U_LIB.S9S_MB_2U(SCH_1):PAGE255_I39@PURE_QUANTA.Q_CAP(CHIPS)':
 'B': CDS_PINID='B';
NODE_NAME     PC266_P0_6 2
 '@S9S_MB_2U_LIB.S9S_MB_2U(SCH_1):PAGE255_I42@PURE_QUANTA.Q_CAP(CHIPS)':
 'B': CDS_PINID='B';
NODE_NAME     PC268_P0_6 2
 '@S9S_MB_2U_LIB.S9S_MB_2U(SCH_1):PAGE255_I59@PURE_QUANTA.Q_CAP(CHIPS)':
 'B': CDS_PINID='B';
NODE_NAME     PU6_P0_8 2
 '@S9S_MB_2U_LIB.S9S_MB_2U(SCH_1):PAGE256_I2@PURE_QUANTA.ISL99390FRZTR5935(CHIPS)':
 'AGND': CDS_PINID='AGND';
NODE_NAME     PU6_P0_8 5
 '@S9S_MB_2U_LIB.S9S_MB_2U(SCH_1):PAGE256_I2@PURE_QUANTA.ISL99390FRZTR5935(CHIPS)':
 'PGND1': CDS_PINID='PGND1';
NODE_NAME     PU6_P0_8 7_9-20_24
 '@S9S_MB_2U_LIB.S9S_MB_2U(SCH_1):PAGE256_I2@PURE_QUANTA.ISL99390FRZTR5935(CHIPS)':
 'PGND2': CDS_PINID='PGND2';
NODE_NAME     PU6_P0_8 40
 '@S9S_MB_2U_LIB.S9S_MB_2U(SCH_1):PAGE256_I2@PURE_QUANTA.ISL99390FRZTR5935(CHIPS)':
 'PGND3': CDS_PINID='PGND3';
NODE_NAME     PC232_P0_8 2
 '@S9S_MB_2U_LIB.S9S_MB_2U(SCH_1):PAGE256_I20@PURE_QUANTA.Q_CAP(CHIPS)':
 'B': CDS_PINID='B';
NODE_NAME     PC229_P0_7 2
 '@S9S_MB_2U_LIB.S9S_MB_2U(SCH_1):PAGE256_I36@PURE_QUANTA.Q_CAP(CHIPS)':
 'B': CDS_PINID='B';
NODE_NAME     PL105 2
 '@S9S_MB_2U_LIB.S9S_MB_2U(SCH_1):PAGE256_I39@PURE_QUANTA.Q_INDUCTOR(CHIPS)':
 '2': CDS_PINID='\2\';
NODE_NAME     PC242_P0_8 2
 '@S9S_MB_2U_LIB.S9S_MB_2U(SCH_1):PAGE256_I52@PURE_QUANTA.Q_CAP(CHIPS)':
 'B': CDS_PINID='B';
NODE_NAME     PC241_P0_7 2
 '@S9S_MB_2U_LIB.S9S_MB_2U(SCH_1):PAGE256_I64@PURE_QUANTA.Q_CAP(CHIPS)':
 'B': CDS_PINID='B';
NODE_NAME     PR353 2
 '@S9S_MB_2U_LIB.S9S_MB_2U(SCH_1):PAGE257_I2@PURE_QUANTA.Q_RES(CHIPS)':
 'B': CDS_PINID='B';
NODE_NAME     PC610_P0_1 2
 '@S9S_MB_2U_LIB.S9S_MB_2U(SCH_1):PAGE257_I48@PURE_QUANTA.Q_CAP(CHIPS)':
 'B': CDS_PINID='B';
NODE_NAME     PC618_P0_2 2
 '@S9S_MB_2U_LIB.S9S_MB_2U(SCH_1):PAGE257_I59@PURE_QUANTA.Q_CAP(CHIPS)':
 'B': CDS_PINID='B';
NODE_NAME     PC621 2
 '@S9S_MB_2U_LIB.S9S_MB_2U(SCH_1):PAGE257_I62@PURE_QUANTA.Q_CAPP(CHIPS)':
 'B': CDS_PINID='B';
NODE_NAME     PC1171 2
 '@S9S_MB_2U_LIB.S9S_MB_2U(SCH_1):PAGE258_I23@PURE_QUANTA.Q_CAP(CHIPS)':
 'B': CDS_PINID='B';
NODE_NAME     PC1182_P0_4 2
 '@S9S_MB_2U_LIB.S9S_MB_2U(SCH_1):PAGE258_I36@PURE_QUANTA.Q_CAP(CHIPS)':
 'B': CDS_PINID='B';
NODE_NAME     PC1183_P0_4 2
 '@S9S_MB_2U_LIB.S9S_MB_2U(SCH_1):PAGE258_I40@PURE_QUANTA.Q_CAP(CHIPS)':
 'B': CDS_PINID='B';
NODE_NAME     PC1173_P0_3 2
 '@S9S_MB_2U_LIB.S9S_MB_2U(SCH_1):PAGE258_I44@PURE_QUANTA.Q_CAP(CHIPS)':
 'B': CDS_PINID='B';
NODE_NAME     PC1175_P0_3 2
 '@S9S_MB_2U_LIB.S9S_MB_2U(SCH_1):PAGE258_I46@PURE_QUANTA.Q_CAP(CHIPS)':
 'B': CDS_PINID='B';
NODE_NAME     PC1183_P0_3 2
 '@S9S_MB_2U_LIB.S9S_MB_2U(SCH_1):PAGE258_I55@PURE_QUANTA.Q_CAP(CHIPS)':
 'B': CDS_PINID='B';
NODE_NAME     PC1188_P0_4 2
 '@S9S_MB_2U_LIB.S9S_MB_2U(SCH_1):PAGE258_I61@PURE_QUANTA.Q_CAP(CHIPS)':
 'B': CDS_PINID='B';
NODE_NAME     PC1186 2
 '@S9S_MB_2U_LIB.S9S_MB_2U(SCH_1):PAGE258_I68@PURE_QUANTA.Q_CAPP(CHIPS)':
 'B': CDS_PINID='B';
NODE_NAME     C3274 2
 '@S9S_MB_2U_LIB.S9S_MB_2U(SCH_1):PAGE260_I60@PURE_QUANTA.Q_CAP(CHIPS)':
 'B': CDS_PINID='B';
NODE_NAME     C3273 2
 '@S9S_MB_2U_LIB.S9S_MB_2U(SCH_1):PAGE260_I61@PURE_QUANTA.Q_CAP(CHIPS)':
 'B': CDS_PINID='B';
NODE_NAME     PU5 TH
 '@S9S_MB_2U_LIB.S9S_MB_2U(SCH_1):PAGE260_I65@PURE_QUANTA.ISL69260IRAZT(CHIPS)':
 'TH_GND': CDS_PINID='TH_GND';
NODE_NAME     PR4228 2
 '@S9S_MB_2U_LIB.S9S_MB_2U(SCH_1):PAGE262_I15@PURE_QUANTA.Q_RES(CHIPS)':
 'B': CDS_PINID='B';
NODE_NAME     PC176 2
 '@S9S_MB_2U_LIB.S9S_MB_2U(SCH_1):PAGE262_I24@PURE_QUANTA.Q_CAP(CHIPS)':
 'B': CDS_PINID='B';
NODE_NAME     PC177 2
 '@S9S_MB_2U_LIB.S9S_MB_2U(SCH_1):PAGE262_I25@PURE_QUANTA.Q_CAP(CHIPS)':
 'B': CDS_PINID='B';
NODE_NAME     PC180 2
 '@S9S_MB_2U_LIB.S9S_MB_2U(SCH_1):PAGE262_I27@PURE_QUANTA.Q_CAP(CHIPS)':
 'B': CDS_PINID='B';
NODE_NAME     PC181 2
 '@S9S_MB_2U_LIB.S9S_MB_2U(SCH_1):PAGE262_I28@PURE_QUANTA.Q_CAP(CHIPS)':
 'B': CDS_PINID='B';
NODE_NAME     PC184 2
 '@S9S_MB_2U_LIB.S9S_MB_2U(SCH_1):PAGE262_I31@PURE_QUANTA.Q_CAP(CHIPS)':
 'B': CDS_PINID='B';
NODE_NAME     PR373 2
 '@S9S_MB_2U_LIB.S9S_MB_2U(SCH_1):PAGE264_I48@PURE_QUANTA.Q_RES(CHIPS)':
 'B': CDS_PINID='B';
NODE_NAME     PC629 2
 '@S9S_MB_2U_LIB.S9S_MB_2U(SCH_1):PAGE264_I72@PURE_QUANTA.Q_CAP(CHIPS)':
 'B': CDS_PINID='B';
NODE_NAME     C1300 2
 '@S9S_MB_2U_LIB.S9S_MB_2U(SCH_1):PAGE267_I12@PURE_QUANTA.Q_CAP(CHIPS)':
 'B': CDS_PINID='B';
NODE_NAME     PC1248 2
 '@S9S_MB_2U_LIB.S9S_MB_2U(SCH_1):PAGE267_I16@PURE_QUANTA.Q_CAP(CHIPS)':
 'B': CDS_PINID='B';
NODE_NAME     PC1249 2
 '@S9S_MB_2U_LIB.S9S_MB_2U(SCH_1):PAGE267_I17@PURE_QUANTA.Q_CAP(CHIPS)':
 'B': CDS_PINID='B';
NODE_NAME     PR3335 2
 '@S9S_MB_2U_LIB.S9S_MB_2U(SCH_1):PAGE267_I18@PURE_QUANTA.Q_RES(CHIPS)':
 'B': CDS_PINID='B';
NODE_NAME     PC1254 2
 '@S9S_MB_2U_LIB.S9S_MB_2U(SCH_1):PAGE267_I38@PURE_QUANTA.Q_CAP(CHIPS)':
 'B': CDS_PINID='B';
NODE_NAME     PC1255 2
 '@S9S_MB_2U_LIB.S9S_MB_2U(SCH_1):PAGE267_I42@PURE_QUANTA.Q_CAP(CHIPS)':
 'B': CDS_PINID='B';
NODE_NAME     PC566_P1_2 2
 '@S9S_MB_2U_LIB.S9S_MB_2U(SCH_1):PAGE271_I22@PURE_QUANTA.Q_CAP(CHIPS)':
 'B': CDS_PINID='B';
NODE_NAME     PR326 2
 '@S9S_MB_2U_LIB.S9S_MB_2U(SCH_1):PAGE271_I29@PURE_QUANTA.Q_RES(CHIPS)':
 'B': CDS_PINID='B';
NODE_NAME     PC1990 2
 '@S9S_MB_2U_LIB.S9S_MB_2U(SCH_1):PAGE271_I61@PURE_QUANTA.Q_CAPP(CHIPS)':
 'B': CDS_PINID='B';
NODE_NAME     PC587 2
 '@S9S_MB_2U_LIB.S9S_MB_2U(SCH_1):PAGE271_I65@PURE_QUANTA.Q_CAPP(CHIPS)':
 'B': CDS_PINID='B';
NODE_NAME     PC586 2
 '@S9S_MB_2U_LIB.S9S_MB_2U(SCH_1):PAGE271_I69@PURE_QUANTA.Q_CAPP(CHIPS)':
 'B': CDS_PINID='B';
NODE_NAME     PC1656 2
 '@S9S_MB_2U_LIB.S9S_MB_2U(SCH_1):PAGE271_I79@PURE_QUANTA.Q_CAP(CHIPS)':
 'B': CDS_PINID='B';
NODE_NAME     PC572_P1_1 2
 '@S9S_MB_2U_LIB.S9S_MB_2U(SCH_1):PAGE271_I84@PURE_QUANTA.Q_CAP(CHIPS)':
 'B': CDS_PINID='B';
NODE_NAME     PC523 2
 '@S9S_MB_2U_LIB.S9S_MB_2U(SCH_1):PAGE272_I11@PURE_QUANTA.Q_CAP(CHIPS)':
 'B': CDS_PINID='B';
NODE_NAME     PC1359 1
 '@S9S_MB_2U_LIB.S9S_MB_2U(SCH_1):PAGE272_I27@PURE_QUANTA.Q_CAP(CHIPS)':
 'A': CDS_PINID='A';
NODE_NAME     PC529_P1_4 2
 '@S9S_MB_2U_LIB.S9S_MB_2U(SCH_1):PAGE272_I35@PURE_QUANTA.Q_CAP(CHIPS)':
 'B': CDS_PINID='B';
NODE_NAME     PC533_P1_4 2
 '@S9S_MB_2U_LIB.S9S_MB_2U(SCH_1):PAGE272_I36@PURE_QUANTA.Q_CAP(CHIPS)':
 'B': CDS_PINID='B';
NODE_NAME     PC535_P1_4 2
 '@S9S_MB_2U_LIB.S9S_MB_2U(SCH_1):PAGE272_I41@PURE_QUANTA.Q_CAP(CHIPS)':
 'B': CDS_PINID='B';
NODE_NAME     PC537_P1_4 2
 '@S9S_MB_2U_LIB.S9S_MB_2U(SCH_1):PAGE272_I42@PURE_QUANTA.Q_CAP(CHIPS)':
 'B': CDS_PINID='B';
NODE_NAME     PC528_P1_3 2
 '@S9S_MB_2U_LIB.S9S_MB_2U(SCH_1):PAGE272_I48@PURE_QUANTA.Q_CAP(CHIPS)':
 'B': CDS_PINID='B';
NODE_NAME     PC530_P1_3 2
 '@S9S_MB_2U_LIB.S9S_MB_2U(SCH_1):PAGE272_I49@PURE_QUANTA.Q_CAP(CHIPS)':
 'B': CDS_PINID='B';
NODE_NAME     PC536_P1_3 2
 '@S9S_MB_2U_LIB.S9S_MB_2U(SCH_1):PAGE272_I54@PURE_QUANTA.Q_CAP(CHIPS)':
 'B': CDS_PINID='B';
NODE_NAME     PR291 2
 '@S9S_MB_2U_LIB.S9S_MB_2U(SCH_1):PAGE273_I2@PURE_QUANTA.Q_RES(CHIPS)':
 'B': CDS_PINID='B';
NODE_NAME     PC503_P1_6 2
 '@S9S_MB_2U_LIB.S9S_MB_2U(SCH_1):PAGE273_I21@PURE_QUANTA.Q_CAP(CHIPS)':
 'B': CDS_PINID='B';
NODE_NAME     PU26_P1_5 2
 '@S9S_MB_2U_LIB.S9S_MB_2U(SCH_1):PAGE273_I23@PURE_QUANTA.ISL99390FRZTR5935(CHIPS)':
 'AGND': CDS_PINID='AGND';
NODE_NAME     PU26_P1_5 5
 '@S9S_MB_2U_LIB.S9S_MB_2U(SCH_1):PAGE273_I23@PURE_QUANTA.ISL99390FRZTR5935(CHIPS)':
 'PGND1': CDS_PINID='PGND1';
NODE_NAME     PU26_P1_5 7_9-20_24
 '@S9S_MB_2U_LIB.S9S_MB_2U(SCH_1):PAGE273_I23@PURE_QUANTA.ISL99390FRZTR5935(CHIPS)':
 'PGND2': CDS_PINID='PGND2';
NODE_NAME     PU26_P1_5 40
 '@S9S_MB_2U_LIB.S9S_MB_2U(SCH_1):PAGE273_I23@PURE_QUANTA.ISL99390FRZTR5935(CHIPS)':
 'PGND3': CDS_PINID='PGND3';
NODE_NAME     PC505_P1_6 2
 '@S9S_MB_2U_LIB.S9S_MB_2U(SCH_1):PAGE273_I29@PURE_QUANTA.Q_CAP(CHIPS)':
 'B': CDS_PINID='B';
NODE_NAME     PC507_P1_6 2
 '@S9S_MB_2U_LIB.S9S_MB_2U(SCH_1):PAGE273_I31@PURE_QUANTA.Q_CAP(CHIPS)':
 'B': CDS_PINID='B';
NODE_NAME     PC513_P1_6 2
 '@S9S_MB_2U_LIB.S9S_MB_2U(SCH_1):PAGE273_I34@PURE_QUANTA.Q_CAP(CHIPS)':
 'B': CDS_PINID='B';
NODE_NAME     PC1361 1
 '@S9S_MB_2U_LIB.S9S_MB_2U(SCH_1):PAGE273_I36@PURE_QUANTA.Q_CAP(CHIPS)':
 'A': CDS_PINID='A';
NODE_NAME     PC502 2
 '@S9S_MB_2U_LIB.S9S_MB_2U(SCH_1):PAGE273_I37@PURE_QUANTA.Q_CAP(CHIPS)':
 'B': CDS_PINID='B';
NODE_NAME     PC504_P1_5 2
 '@S9S_MB_2U_LIB.S9S_MB_2U(SCH_1):PAGE273_I41@PURE_QUANTA.Q_CAP(CHIPS)':
 'B': CDS_PINID='B';
NODE_NAME     PC506_P1_5 2
 '@S9S_MB_2U_LIB.S9S_MB_2U(SCH_1):PAGE273_I45@PURE_QUANTA.Q_CAP(CHIPS)':
 'B': CDS_PINID='B';
NODE_NAME     PC512_P1_5 2
 '@S9S_MB_2U_LIB.S9S_MB_2U(SCH_1):PAGE273_I50@PURE_QUANTA.Q_CAP(CHIPS)':
 'B': CDS_PINID='B';
NODE_NAME     PC519_P1_6 2
 '@S9S_MB_2U_LIB.S9S_MB_2U(SCH_1):PAGE273_I54@PURE_QUANTA.Q_CAP(CHIPS)':
 'B': CDS_PINID='B';
NODE_NAME     PC479 2
 '@S9S_MB_2U_LIB.S9S_MB_2U(SCH_1):PAGE274_I9@PURE_QUANTA.Q_CAP(CHIPS)':
 'B': CDS_PINID='B';
NODE_NAME     PC481_P1_8 2
 '@S9S_MB_2U_LIB.S9S_MB_2U(SCH_1):PAGE274_I18@PURE_QUANTA.Q_CAP(CHIPS)':
 'B': CDS_PINID='B';
NODE_NAME     PC489_P1_8 2
 '@S9S_MB_2U_LIB.S9S_MB_2U(SCH_1):PAGE274_I28@PURE_QUANTA.Q_CAP(CHIPS)':
 'B': CDS_PINID='B';
NODE_NAME     PC1363 1
 '@S9S_MB_2U_LIB.S9S_MB_2U(SCH_1):PAGE274_I32@PURE_QUANTA.Q_CAP(CHIPS)':
 'A': CDS_PINID='A';
NODE_NAME     PC480 2
 '@S9S_MB_2U_LIB.S9S_MB_2U(SCH_1):PAGE274_I34@PURE_QUANTA.Q_CAP(CHIPS)':
 'B': CDS_PINID='B';
NODE_NAME     PC484_P1_7 2
 '@S9S_MB_2U_LIB.S9S_MB_2U(SCH_1):PAGE274_I37@PURE_QUANTA.Q_CAP(CHIPS)':
 'B': CDS_PINID='B';
NODE_NAME     PC486_P1_7 2
 '@S9S_MB_2U_LIB.S9S_MB_2U(SCH_1):PAGE274_I40@PURE_QUANTA.Q_CAP(CHIPS)':
 'B': CDS_PINID='B';
NODE_NAME     PC490_P1_7 2
 '@S9S_MB_2U_LIB.S9S_MB_2U(SCH_1):PAGE274_I41@PURE_QUANTA.Q_CAP(CHIPS)':
 'B': CDS_PINID='B';
NODE_NAME     PC491_P1_8 2
 '@S9S_MB_2U_LIB.S9S_MB_2U(SCH_1):PAGE274_I46@PURE_QUANTA.Q_CAP(CHIPS)':
 'B': CDS_PINID='B';
NODE_NAME     PC493_P1_8 2
 '@S9S_MB_2U_LIB.S9S_MB_2U(SCH_1):PAGE274_I47@PURE_QUANTA.Q_CAP(CHIPS)':
 'B': CDS_PINID='B';
NODE_NAME     PC495_P1_8 2
 '@S9S_MB_2U_LIB.S9S_MB_2U(SCH_1):PAGE274_I52@PURE_QUANTA.Q_CAP(CHIPS)':
 'B': CDS_PINID='B';
NODE_NAME     PC497_P1_8 2
 '@S9S_MB_2U_LIB.S9S_MB_2U(SCH_1):PAGE274_I53@PURE_QUANTA.Q_CAP(CHIPS)':
 'B': CDS_PINID='B';
NODE_NAME     PC499_P1_8 2
 '@S9S_MB_2U_LIB.S9S_MB_2U(SCH_1):PAGE274_I54@PURE_QUANTA.Q_CAP(CHIPS)':
 'B': CDS_PINID='B';
NODE_NAME     PR1304 2
 '@S9S_MB_2U_LIB.S9S_MB_2U(SCH_1):PAGE276_I2@PURE_QUANTA.Q_RES(CHIPS)':
 'B': CDS_PINID='B';
NODE_NAME     PC1194_P1_4 2
 '@S9S_MB_2U_LIB.S9S_MB_2U(SCH_1):PAGE276_I33@PURE_QUANTA.Q_CAP(CHIPS)':
 'B': CDS_PINID='B';
NODE_NAME     PC1200_P1_4 2
 '@S9S_MB_2U_LIB.S9S_MB_2U(SCH_1):PAGE276_I36@PURE_QUANTA.Q_CAP(CHIPS)':
 'B': CDS_PINID='B';
NODE_NAME     PC1201 2
 '@S9S_MB_2U_LIB.S9S_MB_2U(SCH_1):PAGE276_I55@PURE_QUANTA.Q_CAPP(CHIPS)':
 'B': CDS_PINID='B';
NODE_NAME     PC1204_P1_3 2
 '@S9S_MB_2U_LIB.S9S_MB_2U(SCH_1):PAGE276_I56@PURE_QUANTA.Q_CAP(CHIPS)':
 'B': CDS_PINID='B';
NODE_NAME     PC1203 2
 '@S9S_MB_2U_LIB.S9S_MB_2U(SCH_1):PAGE276_I67@PURE_QUANTA.Q_CAPP(CHIPS)':
 'B': CDS_PINID='B';
NODE_NAME     PC1208_P1_3 2
 '@S9S_MB_2U_LIB.S9S_MB_2U(SCH_1):PAGE276_I68@PURE_QUANTA.Q_CAP(CHIPS)':
 'B': CDS_PINID='B';
NODE_NAME     PC1682 2
 '@S9S_MB_2U_LIB.S9S_MB_2U(SCH_1):PAGE276_I77@PURE_QUANTA.Q_CAP(CHIPS)':
 'B': CDS_PINID='B';
NODE_NAME     PR275 2
 '@S9S_MB_2U_LIB.S9S_MB_2U(SCH_1):PAGE278_I26@PURE_QUANTA.Q_RES(CHIPS)':
 'B': CDS_PINID='B';
NODE_NAME     PC458_P1_2 2
 '@S9S_MB_2U_LIB.S9S_MB_2U(SCH_1):PAGE279_I33@PURE_QUANTA.Q_CAP(CHIPS)':
 'B': CDS_PINID='B';
NODE_NAME     PR4247 2
 '@S9S_MB_2U_LIB.S9S_MB_2U(SCH_1):PAGE279_I34@PURE_QUANTA.Q_RES(CHIPS)':
 'B': CDS_PINID='B';
NODE_NAME     PC443_P1_2 2
 '@S9S_MB_2U_LIB.S9S_MB_2U(SCH_1):PAGE279_I36@PURE_QUANTA.Q_CAP(CHIPS)':
 'B': CDS_PINID='B';
NODE_NAME     PU50_P1_1 2
 '@S9S_MB_2U_LIB.S9S_MB_2U(SCH_1):PAGE279_I38@PURE_QUANTA.ISL99390FRZTR5935(CHIPS)':
 'AGND': CDS_PINID='AGND';
NODE_NAME     PU50_P1_1 5
 '@S9S_MB_2U_LIB.S9S_MB_2U(SCH_1):PAGE279_I38@PURE_QUANTA.ISL99390FRZTR5935(CHIPS)':
 'PGND1': CDS_PINID='PGND1';
NODE_NAME     PU50_P1_1 7_9-20_24
 '@S9S_MB_2U_LIB.S9S_MB_2U(SCH_1):PAGE279_I38@PURE_QUANTA.ISL99390FRZTR5935(CHIPS)':
 'PGND2': CDS_PINID='PGND2';
NODE_NAME     PU50_P1_1 40
 '@S9S_MB_2U_LIB.S9S_MB_2U(SCH_1):PAGE279_I38@PURE_QUANTA.ISL99390FRZTR5935(CHIPS)':
 'PGND3': CDS_PINID='PGND3';
NODE_NAME     PC444_P1_1 2
 '@S9S_MB_2U_LIB.S9S_MB_2U(SCH_1):PAGE279_I41@PURE_QUANTA.Q_CAP(CHIPS)':
 'B': CDS_PINID='B';
NODE_NAME     PC449_P1_2 2
 '@S9S_MB_2U_LIB.S9S_MB_2U(SCH_1):PAGE279_I43@PURE_QUANTA.Q_CAP(CHIPS)':
 'B': CDS_PINID='B';
NODE_NAME     PC448_P1_1 2
 '@S9S_MB_2U_LIB.S9S_MB_2U(SCH_1):PAGE279_I51@PURE_QUANTA.Q_CAP(CHIPS)':
 'B': CDS_PINID='B';
NODE_NAME     PC1593 2
 '@S9S_MB_2U_LIB.S9S_MB_2U(SCH_1):PAGE279_I59@PURE_QUANTA.Q_CAPP(CHIPS)':
 'B': CDS_PINID='B';
NODE_NAME     PC1594 2
 '@S9S_MB_2U_LIB.S9S_MB_2U(SCH_1):PAGE279_I62@PURE_QUANTA.Q_CAPP(CHIPS)':
 'B': CDS_PINID='B';
NODE_NAME     PC1659 2
 '@S9S_MB_2U_LIB.S9S_MB_2U(SCH_1):PAGE279_I68@PURE_QUANTA.Q_CAP(CHIPS)':
 'B': CDS_PINID='B';
NODE_NAME     PC460 2
 '@S9S_MB_2U_LIB.S9S_MB_2U(SCH_1):PAGE279_I69@PURE_QUANTA.Q_CAPP(CHIPS)':
 'B': CDS_PINID='B';
NODE_NAME     PU49 6_7-13_15-29
 '@S9S_MB_2U_LIB.S9S_MB_2U(SCH_1):PAGE280_I14@PURE_QUANTA.RAA2213404GNPHB0(CHIPS)':
 'GND1': CDS_PINID='GND1';
NODE_NAME     PU49 23
 '@S9S_MB_2U_LIB.S9S_MB_2U(SCH_1):PAGE280_I14@PURE_QUANTA.RAA2213404GNPHB0(CHIPS)':
 'GND2': CDS_PINID='GND2';
NODE_NAME     PU49 26
 '@S9S_MB_2U_LIB.S9S_MB_2U(SCH_1):PAGE280_I14@PURE_QUANTA.RAA2213404GNPHB0(CHIPS)':
 'GND3': CDS_PINID='GND3';
NODE_NAME     PC429 2
 '@S9S_MB_2U_LIB.S9S_MB_2U(SCH_1):PAGE280_I24@PURE_QUANTA.Q_CAP(CHIPS)':
 'B': CDS_PINID='B';
NODE_NAME     PC432 2
 '@S9S_MB_2U_LIB.S9S_MB_2U(SCH_1):PAGE280_I27@PURE_QUANTA.Q_CAP(CHIPS)':
 'B': CDS_PINID='B';
NODE_NAME     PC435 2
 '@S9S_MB_2U_LIB.S9S_MB_2U(SCH_1):PAGE280_I30@PURE_QUANTA.Q_CAP(CHIPS)':
 'B': CDS_PINID='B';
NODE_NAME     PC437 2
 '@S9S_MB_2U_LIB.S9S_MB_2U(SCH_1):PAGE280_I31@PURE_QUANTA.Q_CAP(CHIPS)':
 'B': CDS_PINID='B';
NODE_NAME     PC1371 1
 '@S9S_MB_2U_LIB.S9S_MB_2U(SCH_1):PAGE283_I8@PURE_QUANTA.Q_CAP(CHIPS)':
 'A': CDS_PINID='A';
NODE_NAME     PC2951 2
 '@S9S_MB_2U_LIB.S9S_MB_2U(SCH_1):PAGE283_I18@PURE_QUANTA.Q_CAP(CHIPS)':
 'B': CDS_PINID='B';
NODE_NAME     PC374 2
 '@S9S_MB_2U_LIB.S9S_MB_2U(SCH_1):PAGE283_I20@PURE_QUANTA.Q_CAP(CHIPS)':
 'B': CDS_PINID='B';
NODE_NAME     PC377 2
 '@S9S_MB_2U_LIB.S9S_MB_2U(SCH_1):PAGE283_I23@PURE_QUANTA.Q_CAP(CHIPS)':
 'B': CDS_PINID='B';
NODE_NAME     PC379 2
 '@S9S_MB_2U_LIB.S9S_MB_2U(SCH_1):PAGE283_I27@PURE_QUANTA.Q_CAP(CHIPS)':
 'B': CDS_PINID='B';
NODE_NAME     PC381 2
 '@S9S_MB_2U_LIB.S9S_MB_2U(SCH_1):PAGE283_I28@PURE_QUANTA.Q_CAP(CHIPS)':
 'B': CDS_PINID='B';
NODE_NAME     PC1260 2
 '@S9S_MB_2U_LIB.S9S_MB_2U(SCH_1):PAGE285_I15@PURE_QUANTA.Q_CAP(CHIPS)':
 'B': CDS_PINID='B';
NODE_NAME     PR3336 2
 '@S9S_MB_2U_LIB.S9S_MB_2U(SCH_1):PAGE285_I18@PURE_QUANTA.Q_RES(CHIPS)':
 'B': CDS_PINID='B';
NODE_NAME     C2460 2
 '@S9S_MB_2U_LIB.S9S_MB_2U(SCH_1):PAGE285_I36@PURE_QUANTA.Q_CAP(CHIPS)':
 'B': CDS_PINID='B';
NODE_NAME     H76 1
 '@S9S_MB_2U_LIB.S9S_MB_2U(SCH_1):PAGE289_I18@PURE_QUANTA.HOLE(CHIPS)':
 '1': CDS_PINID='\1\';
NODE_NAME     H32 1
 '@S9S_MB_2U_LIB.S9S_MB_2U(SCH_1):PAGE289_I54@PURE_QUANTA.HOLE(CHIPS)':
 '1': CDS_PINID='\1\';
NODE_NAME     H31 1
 '@S9S_MB_2U_LIB.S9S_MB_2U(SCH_1):PAGE289_I56@PURE_QUANTA.HOLE(CHIPS)':
 '1': CDS_PINID='\1\';
NODE_NAME     H77 1
 '@S9S_MB_2U_LIB.S9S_MB_2U(SCH_1):PAGE289_I87@PURE_QUANTA.HOLE(CHIPS)':
 '1': CDS_PINID='\1\';
NODE_NAME     R2514 2
 '@S9S_MB_2U_LIB.S9S_MB_2U(SCH_1):PAGE226_I89@PURE_QUANTA.Q_RES(CHIPS)':
 'B': CDS_PINID='B';
NODE_NAME     R2513 2
 '@S9S_MB_2U_LIB.S9S_MB_2U(SCH_1):PAGE226_I90@PURE_QUANTA.Q_RES(CHIPS)':
 'B': CDS_PINID='B';
NODE_NAME     C1664 2
 '@S9S_MB_2U_LIB.S9S_MB_2U(SCH_1):PAGE226_I93@PURE_QUANTA.Q_CAP(CHIPS)':
 'B': CDS_PINID='B';
NODE_NAME     R410 2
 '@S9S_MB_2U_LIB.S9S_MB_2U(SCH_1):PAGE150_I2@PURE_QUANTA.Q_RES(CHIPS)':
 'B': CDS_PINID='B';
NODE_NAME     R415 2
 '@S9S_MB_2U_LIB.S9S_MB_2U(SCH_1):PAGE150_I4@PURE_QUANTA.Q_RES(CHIPS)':
 'B': CDS_PINID='B';
NODE_NAME     R3132 1
 '@S9S_MB_2U_LIB.S9S_MB_2U(SCH_1):PAGE150_I35@PURE_QUANTA.Q_RES(CHIPS)':
 'A': CDS_PINID='A';
NODE_NAME     R1930 1
 '@S9S_MB_2U_LIB.S9S_MB_2U(SCH_1):PAGE150_I36@PURE_QUANTA.Q_RES(CHIPS)':
 'A': CDS_PINID='A';
NODE_NAME     R1929 1
 '@S9S_MB_2U_LIB.S9S_MB_2U(SCH_1):PAGE150_I37@PURE_QUANTA.Q_RES(CHIPS)':
 'A': CDS_PINID='A';
NODE_NAME     C1213 2
 '@S9S_MB_2U_LIB.S9S_MB_2U(SCH_1):PAGE150_I89@PURE_QUANTA.Q_CAP(CHIPS)':
 'B': CDS_PINID='B';
NODE_NAME     C1232 2
 '@S9S_MB_2U_LIB.S9S_MB_2U(SCH_1):PAGE150_I90@PURE_QUANTA.Q_CAP(CHIPS)':
 'B': CDS_PINID='B';
NODE_NAME     C1233 2
 '@S9S_MB_2U_LIB.S9S_MB_2U(SCH_1):PAGE150_I91@PURE_QUANTA.Q_CAP(CHIPS)':
 'B': CDS_PINID='B';
NODE_NAME     C1234 2
 '@S9S_MB_2U_LIB.S9S_MB_2U(SCH_1):PAGE150_I110@PURE_QUANTA.Q_CAP(CHIPS)':
 'B': CDS_PINID='B';
NODE_NAME     C1235 2
 '@S9S_MB_2U_LIB.S9S_MB_2U(SCH_1):PAGE150_I111@PURE_QUANTA.Q_CAP(CHIPS)':
 'B': CDS_PINID='B';
NODE_NAME     C1236 2
 '@S9S_MB_2U_LIB.S9S_MB_2U(SCH_1):PAGE150_I113@PURE_QUANTA.Q_CAP(CHIPS)':
 'B': CDS_PINID='B';
NODE_NAME     C1237 2
 '@S9S_MB_2U_LIB.S9S_MB_2U(SCH_1):PAGE150_I114@PURE_QUANTA.Q_CAP(CHIPS)':
 'B': CDS_PINID='B';
NODE_NAME     C1238 2
 '@S9S_MB_2U_LIB.S9S_MB_2U(SCH_1):PAGE150_I115@PURE_QUANTA.Q_CAP(CHIPS)':
 'B': CDS_PINID='B';
NODE_NAME     C1239 2
 '@S9S_MB_2U_LIB.S9S_MB_2U(SCH_1):PAGE150_I116@PURE_QUANTA.Q_CAP(CHIPS)':
 'B': CDS_PINID='B';
NODE_NAME     R1895 2
 '@S9S_MB_2U_LIB.S9S_MB_2U(SCH_1):PAGE150_I149@PURE_QUANTA.Q_RES(CHIPS)':
 'B': CDS_PINID='B';
NODE_NAME     C1240 2
 '@S9S_MB_2U_LIB.S9S_MB_2U(SCH_1):PAGE150_I168@PURE_QUANTA.Q_CAP(CHIPS)':
 'B': CDS_PINID='B';
NODE_NAME     J111 A6
 '@S9S_MB_2U_LIB.S9S_MB_2U(SCH_1):PAGE148_I74@PURE_QUANTA.CONN112_10137002101LF(CHIPS)':
 'A6': CDS_PINID='A6';
NODE_NAME     J111 A8
 '@S9S_MB_2U_LIB.S9S_MB_2U(SCH_1):PAGE148_I74@PURE_QUANTA.CONN112_10137002101LF(CHIPS)':
 'A8': CDS_PINID='A8';
NODE_NAME     J111 B5
 '@S9S_MB_2U_LIB.S9S_MB_2U(SCH_1):PAGE148_I74@PURE_QUANTA.CONN112_10137002101LF(CHIPS)':
 'B5': CDS_PINID='B5';
NODE_NAME     J111 B7
 '@S9S_MB_2U_LIB.S9S_MB_2U(SCH_1):PAGE148_I74@PURE_QUANTA.CONN112_10137002101LF(CHIPS)':
 'B7': CDS_PINID='B7';
NODE_NAME     J111 D6
 '@S9S_MB_2U_LIB.S9S_MB_2U(SCH_1):PAGE148_I74@PURE_QUANTA.CONN112_10137002101LF(CHIPS)':
 'D6': CDS_PINID='D6';
NODE_NAME     J111 D8
 '@S9S_MB_2U_LIB.S9S_MB_2U(SCH_1):PAGE148_I74@PURE_QUANTA.CONN112_10137002101LF(CHIPS)':
 'D8': CDS_PINID='D8';
NODE_NAME     J111 E5
 '@S9S_MB_2U_LIB.S9S_MB_2U(SCH_1):PAGE148_I74@PURE_QUANTA.CONN112_10137002101LF(CHIPS)':
 'E5': CDS_PINID='E5';
NODE_NAME     J111 E7
 '@S9S_MB_2U_LIB.S9S_MB_2U(SCH_1):PAGE148_I74@PURE_QUANTA.CONN112_10137002101LF(CHIPS)':
 'E7': CDS_PINID='E7';
NODE_NAME     J111 G6
 '@S9S_MB_2U_LIB.S9S_MB_2U(SCH_1):PAGE148_I74@PURE_QUANTA.CONN112_10137002101LF(CHIPS)':
 'G6': CDS_PINID='G6';
NODE_NAME     J111 G8
 '@S9S_MB_2U_LIB.S9S_MB_2U(SCH_1):PAGE148_I74@PURE_QUANTA.CONN112_10137002101LF(CHIPS)':
 'G8': CDS_PINID='G8';
NODE_NAME     J111 H5
 '@S9S_MB_2U_LIB.S9S_MB_2U(SCH_1):PAGE148_I74@PURE_QUANTA.CONN112_10137002101LF(CHIPS)':
 'H5': CDS_PINID='H5';
NODE_NAME     J111 H7
 '@S9S_MB_2U_LIB.S9S_MB_2U(SCH_1):PAGE148_I74@PURE_QUANTA.CONN112_10137002101LF(CHIPS)':
 'H7': CDS_PINID='H7';
NODE_NAME     J111 J6
 '@S9S_MB_2U_LIB.S9S_MB_2U(SCH_1):PAGE148_I74@PURE_QUANTA.CONN112_10137002101LF(CHIPS)':
 'J6': CDS_PINID='J6';
NODE_NAME     J111 J8
 '@S9S_MB_2U_LIB.S9S_MB_2U(SCH_1):PAGE148_I74@PURE_QUANTA.CONN112_10137002101LF(CHIPS)':
 'J8': CDS_PINID='J8';
NODE_NAME     J111 K5
 '@S9S_MB_2U_LIB.S9S_MB_2U(SCH_1):PAGE148_I74@PURE_QUANTA.CONN112_10137002101LF(CHIPS)':
 'K5': CDS_PINID='K5';
NODE_NAME     J111 K7
 '@S9S_MB_2U_LIB.S9S_MB_2U(SCH_1):PAGE148_I74@PURE_QUANTA.CONN112_10137002101LF(CHIPS)':
 'K7': CDS_PINID='K7';
NODE_NAME     J111 M6
 '@S9S_MB_2U_LIB.S9S_MB_2U(SCH_1):PAGE148_I74@PURE_QUANTA.CONN112_10137002101LF(CHIPS)':
 'M6': CDS_PINID='M6';
NODE_NAME     J111 M8
 '@S9S_MB_2U_LIB.S9S_MB_2U(SCH_1):PAGE148_I74@PURE_QUANTA.CONN112_10137002101LF(CHIPS)':
 'M8': CDS_PINID='M8';
NODE_NAME     J111 N5
 '@S9S_MB_2U_LIB.S9S_MB_2U(SCH_1):PAGE148_I74@PURE_QUANTA.CONN112_10137002101LF(CHIPS)':
 'N5': CDS_PINID='N5';
NODE_NAME     J111 N7
 '@S9S_MB_2U_LIB.S9S_MB_2U(SCH_1):PAGE148_I74@PURE_QUANTA.CONN112_10137002101LF(CHIPS)':
 'N7': CDS_PINID='N7';
NODE_NAME     J112 A6
 '@S9S_MB_2U_LIB.S9S_MB_2U(SCH_1):PAGE149_I75@PURE_QUANTA.CONN160_10131762101LF(CHIPS)':
 'A6': CDS_PINID='A6';
NODE_NAME     J112 A8
 '@S9S_MB_2U_LIB.S9S_MB_2U(SCH_1):PAGE149_I75@PURE_QUANTA.CONN160_10131762101LF(CHIPS)':
 'A8': CDS_PINID='A8';
NODE_NAME     J112 B5
 '@S9S_MB_2U_LIB.S9S_MB_2U(SCH_1):PAGE149_I75@PURE_QUANTA.CONN160_10131762101LF(CHIPS)':
 'B5': CDS_PINID='B5';
NODE_NAME     J112 B7
 '@S9S_MB_2U_LIB.S9S_MB_2U(SCH_1):PAGE149_I75@PURE_QUANTA.CONN160_10131762101LF(CHIPS)':
 'B7': CDS_PINID='B7';
NODE_NAME     J112 D6
 '@S9S_MB_2U_LIB.S9S_MB_2U(SCH_1):PAGE149_I75@PURE_QUANTA.CONN160_10131762101LF(CHIPS)':
 'D6': CDS_PINID='D6';
NODE_NAME     J112 D8
 '@S9S_MB_2U_LIB.S9S_MB_2U(SCH_1):PAGE149_I75@PURE_QUANTA.CONN160_10131762101LF(CHIPS)':
 'D8': CDS_PINID='D8';
NODE_NAME     J112 E5
 '@S9S_MB_2U_LIB.S9S_MB_2U(SCH_1):PAGE149_I75@PURE_QUANTA.CONN160_10131762101LF(CHIPS)':
 'E5': CDS_PINID='E5';
NODE_NAME     J112 E7
 '@S9S_MB_2U_LIB.S9S_MB_2U(SCH_1):PAGE149_I75@PURE_QUANTA.CONN160_10131762101LF(CHIPS)':
 'E7': CDS_PINID='E7';
NODE_NAME     J112 G6
 '@S9S_MB_2U_LIB.S9S_MB_2U(SCH_1):PAGE149_I75@PURE_QUANTA.CONN160_10131762101LF(CHIPS)':
 'G6': CDS_PINID='G6';
NODE_NAME     J112 G8
 '@S9S_MB_2U_LIB.S9S_MB_2U(SCH_1):PAGE149_I75@PURE_QUANTA.CONN160_10131762101LF(CHIPS)':
 'G8': CDS_PINID='G8';
NODE_NAME     J112 H5
 '@S9S_MB_2U_LIB.S9S_MB_2U(SCH_1):PAGE149_I75@PURE_QUANTA.CONN160_10131762101LF(CHIPS)':
 'H5': CDS_PINID='H5';
NODE_NAME     J112 H7
 '@S9S_MB_2U_LIB.S9S_MB_2U(SCH_1):PAGE149_I75@PURE_QUANTA.CONN160_10131762101LF(CHIPS)':
 'H7': CDS_PINID='H7';
NODE_NAME     J112 J6
 '@S9S_MB_2U_LIB.S9S_MB_2U(SCH_1):PAGE149_I75@PURE_QUANTA.CONN160_10131762101LF(CHIPS)':
 'J6': CDS_PINID='J6';
NODE_NAME     J112 J8
 '@S9S_MB_2U_LIB.S9S_MB_2U(SCH_1):PAGE149_I75@PURE_QUANTA.CONN160_10131762101LF(CHIPS)':
 'J8': CDS_PINID='J8';
NODE_NAME     J112 K5
 '@S9S_MB_2U_LIB.S9S_MB_2U(SCH_1):PAGE149_I75@PURE_QUANTA.CONN160_10131762101LF(CHIPS)':
 'K5': CDS_PINID='K5';
NODE_NAME     J112 K7
 '@S9S_MB_2U_LIB.S9S_MB_2U(SCH_1):PAGE149_I75@PURE_QUANTA.CONN160_10131762101LF(CHIPS)':
 'K7': CDS_PINID='K7';
NODE_NAME     J112 M6
 '@S9S_MB_2U_LIB.S9S_MB_2U(SCH_1):PAGE149_I75@PURE_QUANTA.CONN160_10131762101LF(CHIPS)':
 'M6': CDS_PINID='M6';
NODE_NAME     J112 M8
 '@S9S_MB_2U_LIB.S9S_MB_2U(SCH_1):PAGE149_I75@PURE_QUANTA.CONN160_10131762101LF(CHIPS)':
 'M8': CDS_PINID='M8';
NODE_NAME     J112 N5
 '@S9S_MB_2U_LIB.S9S_MB_2U(SCH_1):PAGE149_I75@PURE_QUANTA.CONN160_10131762101LF(CHIPS)':
 'N5': CDS_PINID='N5';
NODE_NAME     J112 N7
 '@S9S_MB_2U_LIB.S9S_MB_2U(SCH_1):PAGE149_I75@PURE_QUANTA.CONN160_10131762101LF(CHIPS)':
 'N7': CDS_PINID='N7';
NODE_NAME     J112 P6
 '@S9S_MB_2U_LIB.S9S_MB_2U(SCH_1):PAGE149_I75@PURE_QUANTA.CONN160_10131762101LF(CHIPS)':
 'P6': CDS_PINID='P6';
NODE_NAME     J112 P8
 '@S9S_MB_2U_LIB.S9S_MB_2U(SCH_1):PAGE149_I75@PURE_QUANTA.CONN160_10131762101LF(CHIPS)':
 'P8': CDS_PINID='P8';
NODE_NAME     J112 Q5
 '@S9S_MB_2U_LIB.S9S_MB_2U(SCH_1):PAGE149_I75@PURE_QUANTA.CONN160_10131762101LF(CHIPS)':
 'Q5': CDS_PINID='Q5';
NODE_NAME     J112 Q7
 '@S9S_MB_2U_LIB.S9S_MB_2U(SCH_1):PAGE149_I75@PURE_QUANTA.CONN160_10131762101LF(CHIPS)':
 'Q7': CDS_PINID='Q7';
NODE_NAME     J112 S6
 '@S9S_MB_2U_LIB.S9S_MB_2U(SCH_1):PAGE149_I75@PURE_QUANTA.CONN160_10131762101LF(CHIPS)':
 'S6': CDS_PINID='S6';
NODE_NAME     J112 S8
 '@S9S_MB_2U_LIB.S9S_MB_2U(SCH_1):PAGE149_I75@PURE_QUANTA.CONN160_10131762101LF(CHIPS)':
 'S8': CDS_PINID='S8';
NODE_NAME     J112 T5
 '@S9S_MB_2U_LIB.S9S_MB_2U(SCH_1):PAGE149_I75@PURE_QUANTA.CONN160_10131762101LF(CHIPS)':
 'T5': CDS_PINID='T5';
NODE_NAME     J112 T7
 '@S9S_MB_2U_LIB.S9S_MB_2U(SCH_1):PAGE149_I75@PURE_QUANTA.CONN160_10131762101LF(CHIPS)':
 'T7': CDS_PINID='T7';
NODE_NAME     J112 A2
 '@S9S_MB_2U_LIB.S9S_MB_2U(SCH_1):PAGE149_I76@PURE_QUANTA.CONN160_10131762101LF(CHIPS)':
 'A2': CDS_PINID='A2';
NODE_NAME     J112 A4
 '@S9S_MB_2U_LIB.S9S_MB_2U(SCH_1):PAGE149_I76@PURE_QUANTA.CONN160_10131762101LF(CHIPS)':
 'A4': CDS_PINID='A4';
NODE_NAME     J112 B1
 '@S9S_MB_2U_LIB.S9S_MB_2U(SCH_1):PAGE149_I76@PURE_QUANTA.CONN160_10131762101LF(CHIPS)':
 'B1': CDS_PINID='B1';
NODE_NAME     J112 B3
 '@S9S_MB_2U_LIB.S9S_MB_2U(SCH_1):PAGE149_I76@PURE_QUANTA.CONN160_10131762101LF(CHIPS)':
 'B3': CDS_PINID='B3';
NODE_NAME     J112 D2
 '@S9S_MB_2U_LIB.S9S_MB_2U(SCH_1):PAGE149_I76@PURE_QUANTA.CONN160_10131762101LF(CHIPS)':
 'D2': CDS_PINID='D2';
NODE_NAME     J112 D4
 '@S9S_MB_2U_LIB.S9S_MB_2U(SCH_1):PAGE149_I76@PURE_QUANTA.CONN160_10131762101LF(CHIPS)':
 'D4': CDS_PINID='D4';
NODE_NAME     J112 E1
 '@S9S_MB_2U_LIB.S9S_MB_2U(SCH_1):PAGE149_I76@PURE_QUANTA.CONN160_10131762101LF(CHIPS)':
 'E1': CDS_PINID='E1';
NODE_NAME     J112 E3
 '@S9S_MB_2U_LIB.S9S_MB_2U(SCH_1):PAGE149_I76@PURE_QUANTA.CONN160_10131762101LF(CHIPS)':
 'E3': CDS_PINID='E3';
NODE_NAME     J112 G2
 '@S9S_MB_2U_LIB.S9S_MB_2U(SCH_1):PAGE149_I76@PURE_QUANTA.CONN160_10131762101LF(CHIPS)':
 'G2': CDS_PINID='G2';
NODE_NAME     J112 G4
 '@S9S_MB_2U_LIB.S9S_MB_2U(SCH_1):PAGE149_I76@PURE_QUANTA.CONN160_10131762101LF(CHIPS)':
 'G4': CDS_PINID='G4';
NODE_NAME     J112 H1
 '@S9S_MB_2U_LIB.S9S_MB_2U(SCH_1):PAGE149_I76@PURE_QUANTA.CONN160_10131762101LF(CHIPS)':
 'H1': CDS_PINID='H1';
NODE_NAME     J112 H3
 '@S9S_MB_2U_LIB.S9S_MB_2U(SCH_1):PAGE149_I76@PURE_QUANTA.CONN160_10131762101LF(CHIPS)':
 'H3': CDS_PINID='H3';
NODE_NAME     J112 J2
 '@S9S_MB_2U_LIB.S9S_MB_2U(SCH_1):PAGE149_I76@PURE_QUANTA.CONN160_10131762101LF(CHIPS)':
 'J2': CDS_PINID='J2';
NODE_NAME     J112 J4
 '@S9S_MB_2U_LIB.S9S_MB_2U(SCH_1):PAGE149_I76@PURE_QUANTA.CONN160_10131762101LF(CHIPS)':
 'J4': CDS_PINID='J4';
NODE_NAME     J112 K1
 '@S9S_MB_2U_LIB.S9S_MB_2U(SCH_1):PAGE149_I76@PURE_QUANTA.CONN160_10131762101LF(CHIPS)':
 'K1': CDS_PINID='K1';
NODE_NAME     J112 K3
 '@S9S_MB_2U_LIB.S9S_MB_2U(SCH_1):PAGE149_I76@PURE_QUANTA.CONN160_10131762101LF(CHIPS)':
 'K3': CDS_PINID='K3';
NODE_NAME     J112 M2
 '@S9S_MB_2U_LIB.S9S_MB_2U(SCH_1):PAGE149_I76@PURE_QUANTA.CONN160_10131762101LF(CHIPS)':
 'M2': CDS_PINID='M2';
NODE_NAME     J112 M4
 '@S9S_MB_2U_LIB.S9S_MB_2U(SCH_1):PAGE149_I76@PURE_QUANTA.CONN160_10131762101LF(CHIPS)':
 'M4': CDS_PINID='M4';
NODE_NAME     J112 N1
 '@S9S_MB_2U_LIB.S9S_MB_2U(SCH_1):PAGE149_I76@PURE_QUANTA.CONN160_10131762101LF(CHIPS)':
 'N1': CDS_PINID='N1';
NODE_NAME     J112 N3
 '@S9S_MB_2U_LIB.S9S_MB_2U(SCH_1):PAGE149_I76@PURE_QUANTA.CONN160_10131762101LF(CHIPS)':
 'N3': CDS_PINID='N3';
NODE_NAME     J112 P2
 '@S9S_MB_2U_LIB.S9S_MB_2U(SCH_1):PAGE149_I76@PURE_QUANTA.CONN160_10131762101LF(CHIPS)':
 'P2': CDS_PINID='P2';
NODE_NAME     J112 P4
 '@S9S_MB_2U_LIB.S9S_MB_2U(SCH_1):PAGE149_I76@PURE_QUANTA.CONN160_10131762101LF(CHIPS)':
 'P4': CDS_PINID='P4';
NODE_NAME     J112 Q1
 '@S9S_MB_2U_LIB.S9S_MB_2U(SCH_1):PAGE149_I76@PURE_QUANTA.CONN160_10131762101LF(CHIPS)':
 'Q1': CDS_PINID='Q1';
NODE_NAME     J112 Q3
 '@S9S_MB_2U_LIB.S9S_MB_2U(SCH_1):PAGE149_I76@PURE_QUANTA.CONN160_10131762101LF(CHIPS)':
 'Q3': CDS_PINID='Q3';
NODE_NAME     J112 S2
 '@S9S_MB_2U_LIB.S9S_MB_2U(SCH_1):PAGE149_I76@PURE_QUANTA.CONN160_10131762101LF(CHIPS)':
 'S2': CDS_PINID='S2';
NODE_NAME     J112 S4
 '@S9S_MB_2U_LIB.S9S_MB_2U(SCH_1):PAGE149_I76@PURE_QUANTA.CONN160_10131762101LF(CHIPS)':
 'S4': CDS_PINID='S4';
NODE_NAME     J112 T1
 '@S9S_MB_2U_LIB.S9S_MB_2U(SCH_1):PAGE149_I76@PURE_QUANTA.CONN160_10131762101LF(CHIPS)':
 'T1': CDS_PINID='T1';
NODE_NAME     J112 T3
 '@S9S_MB_2U_LIB.S9S_MB_2U(SCH_1):PAGE149_I76@PURE_QUANTA.CONN160_10131762101LF(CHIPS)':
 'T3': CDS_PINID='T3';
NODE_NAME     J111 A2
 '@S9S_MB_2U_LIB.S9S_MB_2U(SCH_1):PAGE148_I75@PURE_QUANTA.CONN112_10137002101LF(CHIPS)':
 'A2': CDS_PINID='A2';
NODE_NAME     J111 A4
 '@S9S_MB_2U_LIB.S9S_MB_2U(SCH_1):PAGE148_I75@PURE_QUANTA.CONN112_10137002101LF(CHIPS)':
 'A4': CDS_PINID='A4';
NODE_NAME     J111 B1
 '@S9S_MB_2U_LIB.S9S_MB_2U(SCH_1):PAGE148_I75@PURE_QUANTA.CONN112_10137002101LF(CHIPS)':
 'B1': CDS_PINID='B1';
NODE_NAME     J111 B3
 '@S9S_MB_2U_LIB.S9S_MB_2U(SCH_1):PAGE148_I75@PURE_QUANTA.CONN112_10137002101LF(CHIPS)':
 'B3': CDS_PINID='B3';
NODE_NAME     J111 D2
 '@S9S_MB_2U_LIB.S9S_MB_2U(SCH_1):PAGE148_I75@PURE_QUANTA.CONN112_10137002101LF(CHIPS)':
 'D2': CDS_PINID='D2';
NODE_NAME     J111 D4
 '@S9S_MB_2U_LIB.S9S_MB_2U(SCH_1):PAGE148_I75@PURE_QUANTA.CONN112_10137002101LF(CHIPS)':
 'D4': CDS_PINID='D4';
NODE_NAME     J111 E1
 '@S9S_MB_2U_LIB.S9S_MB_2U(SCH_1):PAGE148_I75@PURE_QUANTA.CONN112_10137002101LF(CHIPS)':
 'E1': CDS_PINID='E1';
NODE_NAME     J111 E3
 '@S9S_MB_2U_LIB.S9S_MB_2U(SCH_1):PAGE148_I75@PURE_QUANTA.CONN112_10137002101LF(CHIPS)':
 'E3': CDS_PINID='E3';
NODE_NAME     J111 G2
 '@S9S_MB_2U_LIB.S9S_MB_2U(SCH_1):PAGE148_I75@PURE_QUANTA.CONN112_10137002101LF(CHIPS)':
 'G2': CDS_PINID='G2';
NODE_NAME     J111 G4
 '@S9S_MB_2U_LIB.S9S_MB_2U(SCH_1):PAGE148_I75@PURE_QUANTA.CONN112_10137002101LF(CHIPS)':
 'G4': CDS_PINID='G4';
NODE_NAME     J111 H1
 '@S9S_MB_2U_LIB.S9S_MB_2U(SCH_1):PAGE148_I75@PURE_QUANTA.CONN112_10137002101LF(CHIPS)':
 'H1': CDS_PINID='H1';
NODE_NAME     J111 H3
 '@S9S_MB_2U_LIB.S9S_MB_2U(SCH_1):PAGE148_I75@PURE_QUANTA.CONN112_10137002101LF(CHIPS)':
 'H3': CDS_PINID='H3';
NODE_NAME     J111 J2
 '@S9S_MB_2U_LIB.S9S_MB_2U(SCH_1):PAGE148_I75@PURE_QUANTA.CONN112_10137002101LF(CHIPS)':
 'J2': CDS_PINID='J2';
NODE_NAME     J111 J4
 '@S9S_MB_2U_LIB.S9S_MB_2U(SCH_1):PAGE148_I75@PURE_QUANTA.CONN112_10137002101LF(CHIPS)':
 'J4': CDS_PINID='J4';
NODE_NAME     J111 K1
 '@S9S_MB_2U_LIB.S9S_MB_2U(SCH_1):PAGE148_I75@PURE_QUANTA.CONN112_10137002101LF(CHIPS)':
 'K1': CDS_PINID='K1';
NODE_NAME     J111 K3
 '@S9S_MB_2U_LIB.S9S_MB_2U(SCH_1):PAGE148_I75@PURE_QUANTA.CONN112_10137002101LF(CHIPS)':
 'K3': CDS_PINID='K3';
NODE_NAME     J111 M2
 '@S9S_MB_2U_LIB.S9S_MB_2U(SCH_1):PAGE148_I75@PURE_QUANTA.CONN112_10137002101LF(CHIPS)':
 'M2': CDS_PINID='M2';
NODE_NAME     J111 M4
 '@S9S_MB_2U_LIB.S9S_MB_2U(SCH_1):PAGE148_I75@PURE_QUANTA.CONN112_10137002101LF(CHIPS)':
 'M4': CDS_PINID='M4';
NODE_NAME     J111 N1
 '@S9S_MB_2U_LIB.S9S_MB_2U(SCH_1):PAGE148_I75@PURE_QUANTA.CONN112_10137002101LF(CHIPS)':
 'N1': CDS_PINID='N1';
NODE_NAME     J111 N3
 '@S9S_MB_2U_LIB.S9S_MB_2U(SCH_1):PAGE148_I75@PURE_QUANTA.CONN112_10137002101LF(CHIPS)':
 'N3': CDS_PINID='N3';
NODE_NAME     J105 A2
 '@S9S_MB_2U_LIB.S9S_MB_2U(SCH_1):PAGE142_I65@PURE_QUANTA.CONN112_10137002101LF(CHIPS)':
 'A2': CDS_PINID='A2';
NODE_NAME     J105 A4
 '@S9S_MB_2U_LIB.S9S_MB_2U(SCH_1):PAGE142_I65@PURE_QUANTA.CONN112_10137002101LF(CHIPS)':
 'A4': CDS_PINID='A4';
NODE_NAME     J105 B1
 '@S9S_MB_2U_LIB.S9S_MB_2U(SCH_1):PAGE142_I65@PURE_QUANTA.CONN112_10137002101LF(CHIPS)':
 'B1': CDS_PINID='B1';
NODE_NAME     J105 B3
 '@S9S_MB_2U_LIB.S9S_MB_2U(SCH_1):PAGE142_I65@PURE_QUANTA.CONN112_10137002101LF(CHIPS)':
 'B3': CDS_PINID='B3';
NODE_NAME     J105 D2
 '@S9S_MB_2U_LIB.S9S_MB_2U(SCH_1):PAGE142_I65@PURE_QUANTA.CONN112_10137002101LF(CHIPS)':
 'D2': CDS_PINID='D2';
NODE_NAME     J105 D4
 '@S9S_MB_2U_LIB.S9S_MB_2U(SCH_1):PAGE142_I65@PURE_QUANTA.CONN112_10137002101LF(CHIPS)':
 'D4': CDS_PINID='D4';
NODE_NAME     J105 E1
 '@S9S_MB_2U_LIB.S9S_MB_2U(SCH_1):PAGE142_I65@PURE_QUANTA.CONN112_10137002101LF(CHIPS)':
 'E1': CDS_PINID='E1';
NODE_NAME     J105 E3
 '@S9S_MB_2U_LIB.S9S_MB_2U(SCH_1):PAGE142_I65@PURE_QUANTA.CONN112_10137002101LF(CHIPS)':
 'E3': CDS_PINID='E3';
NODE_NAME     J105 G2
 '@S9S_MB_2U_LIB.S9S_MB_2U(SCH_1):PAGE142_I65@PURE_QUANTA.CONN112_10137002101LF(CHIPS)':
 'G2': CDS_PINID='G2';
NODE_NAME     J105 G4
 '@S9S_MB_2U_LIB.S9S_MB_2U(SCH_1):PAGE142_I65@PURE_QUANTA.CONN112_10137002101LF(CHIPS)':
 'G4': CDS_PINID='G4';
NODE_NAME     J105 H1
 '@S9S_MB_2U_LIB.S9S_MB_2U(SCH_1):PAGE142_I65@PURE_QUANTA.CONN112_10137002101LF(CHIPS)':
 'H1': CDS_PINID='H1';
NODE_NAME     J105 H3
 '@S9S_MB_2U_LIB.S9S_MB_2U(SCH_1):PAGE142_I65@PURE_QUANTA.CONN112_10137002101LF(CHIPS)':
 'H3': CDS_PINID='H3';
NODE_NAME     J105 J2
 '@S9S_MB_2U_LIB.S9S_MB_2U(SCH_1):PAGE142_I65@PURE_QUANTA.CONN112_10137002101LF(CHIPS)':
 'J2': CDS_PINID='J2';
NODE_NAME     J105 J4
 '@S9S_MB_2U_LIB.S9S_MB_2U(SCH_1):PAGE142_I65@PURE_QUANTA.CONN112_10137002101LF(CHIPS)':
 'J4': CDS_PINID='J4';
NODE_NAME     J105 K1
 '@S9S_MB_2U_LIB.S9S_MB_2U(SCH_1):PAGE142_I65@PURE_QUANTA.CONN112_10137002101LF(CHIPS)':
 'K1': CDS_PINID='K1';
NODE_NAME     J105 K3
 '@S9S_MB_2U_LIB.S9S_MB_2U(SCH_1):PAGE142_I65@PURE_QUANTA.CONN112_10137002101LF(CHIPS)':
 'K3': CDS_PINID='K3';
NODE_NAME     J105 M2
 '@S9S_MB_2U_LIB.S9S_MB_2U(SCH_1):PAGE142_I65@PURE_QUANTA.CONN112_10137002101LF(CHIPS)':
 'M2': CDS_PINID='M2';
NODE_NAME     J105 M4
 '@S9S_MB_2U_LIB.S9S_MB_2U(SCH_1):PAGE142_I65@PURE_QUANTA.CONN112_10137002101LF(CHIPS)':
 'M4': CDS_PINID='M4';
NODE_NAME     J105 N1
 '@S9S_MB_2U_LIB.S9S_MB_2U(SCH_1):PAGE142_I65@PURE_QUANTA.CONN112_10137002101LF(CHIPS)':
 'N1': CDS_PINID='N1';
NODE_NAME     J105 N3
 '@S9S_MB_2U_LIB.S9S_MB_2U(SCH_1):PAGE142_I65@PURE_QUANTA.CONN112_10137002101LF(CHIPS)':
 'N3': CDS_PINID='N3';
NODE_NAME     J105 A6
 '@S9S_MB_2U_LIB.S9S_MB_2U(SCH_1):PAGE142_I68@PURE_QUANTA.CONN112_10137002101LF(CHIPS)':
 'A6': CDS_PINID='A6';
NODE_NAME     J105 A8
 '@S9S_MB_2U_LIB.S9S_MB_2U(SCH_1):PAGE142_I68@PURE_QUANTA.CONN112_10137002101LF(CHIPS)':
 'A8': CDS_PINID='A8';
NODE_NAME     J105 B5
 '@S9S_MB_2U_LIB.S9S_MB_2U(SCH_1):PAGE142_I68@PURE_QUANTA.CONN112_10137002101LF(CHIPS)':
 'B5': CDS_PINID='B5';
NODE_NAME     J105 B7
 '@S9S_MB_2U_LIB.S9S_MB_2U(SCH_1):PAGE142_I68@PURE_QUANTA.CONN112_10137002101LF(CHIPS)':
 'B7': CDS_PINID='B7';
NODE_NAME     J105 D6
 '@S9S_MB_2U_LIB.S9S_MB_2U(SCH_1):PAGE142_I68@PURE_QUANTA.CONN112_10137002101LF(CHIPS)':
 'D6': CDS_PINID='D6';
NODE_NAME     J105 D8
 '@S9S_MB_2U_LIB.S9S_MB_2U(SCH_1):PAGE142_I68@PURE_QUANTA.CONN112_10137002101LF(CHIPS)':
 'D8': CDS_PINID='D8';
NODE_NAME     J105 E5
 '@S9S_MB_2U_LIB.S9S_MB_2U(SCH_1):PAGE142_I68@PURE_QUANTA.CONN112_10137002101LF(CHIPS)':
 'E5': CDS_PINID='E5';
NODE_NAME     J105 E7
 '@S9S_MB_2U_LIB.S9S_MB_2U(SCH_1):PAGE142_I68@PURE_QUANTA.CONN112_10137002101LF(CHIPS)':
 'E7': CDS_PINID='E7';
NODE_NAME     J105 G6
 '@S9S_MB_2U_LIB.S9S_MB_2U(SCH_1):PAGE142_I68@PURE_QUANTA.CONN112_10137002101LF(CHIPS)':
 'G6': CDS_PINID='G6';
NODE_NAME     J105 G8
 '@S9S_MB_2U_LIB.S9S_MB_2U(SCH_1):PAGE142_I68@PURE_QUANTA.CONN112_10137002101LF(CHIPS)':
 'G8': CDS_PINID='G8';
NODE_NAME     J105 H5
 '@S9S_MB_2U_LIB.S9S_MB_2U(SCH_1):PAGE142_I68@PURE_QUANTA.CONN112_10137002101LF(CHIPS)':
 'H5': CDS_PINID='H5';
NODE_NAME     J105 H7
 '@S9S_MB_2U_LIB.S9S_MB_2U(SCH_1):PAGE142_I68@PURE_QUANTA.CONN112_10137002101LF(CHIPS)':
 'H7': CDS_PINID='H7';
NODE_NAME     J105 J6
 '@S9S_MB_2U_LIB.S9S_MB_2U(SCH_1):PAGE142_I68@PURE_QUANTA.CONN112_10137002101LF(CHIPS)':
 'J6': CDS_PINID='J6';
NODE_NAME     J105 J8
 '@S9S_MB_2U_LIB.S9S_MB_2U(SCH_1):PAGE142_I68@PURE_QUANTA.CONN112_10137002101LF(CHIPS)':
 'J8': CDS_PINID='J8';
NODE_NAME     J105 K5
 '@S9S_MB_2U_LIB.S9S_MB_2U(SCH_1):PAGE142_I68@PURE_QUANTA.CONN112_10137002101LF(CHIPS)':
 'K5': CDS_PINID='K5';
NODE_NAME     J105 K7
 '@S9S_MB_2U_LIB.S9S_MB_2U(SCH_1):PAGE142_I68@PURE_QUANTA.CONN112_10137002101LF(CHIPS)':
 'K7': CDS_PINID='K7';
NODE_NAME     J105 M6
 '@S9S_MB_2U_LIB.S9S_MB_2U(SCH_1):PAGE142_I68@PURE_QUANTA.CONN112_10137002101LF(CHIPS)':
 'M6': CDS_PINID='M6';
NODE_NAME     J105 M8
 '@S9S_MB_2U_LIB.S9S_MB_2U(SCH_1):PAGE142_I68@PURE_QUANTA.CONN112_10137002101LF(CHIPS)':
 'M8': CDS_PINID='M8';
NODE_NAME     J105 N5
 '@S9S_MB_2U_LIB.S9S_MB_2U(SCH_1):PAGE142_I68@PURE_QUANTA.CONN112_10137002101LF(CHIPS)':
 'N5': CDS_PINID='N5';
NODE_NAME     J105 N7
 '@S9S_MB_2U_LIB.S9S_MB_2U(SCH_1):PAGE142_I68@PURE_QUANTA.CONN112_10137002101LF(CHIPS)':
 'N7': CDS_PINID='N7';
NODE_NAME     J106 A2
 '@S9S_MB_2U_LIB.S9S_MB_2U(SCH_1):PAGE144_I65@PURE_QUANTA.CONN112_10137002101LF(CHIPS)':
 'A2': CDS_PINID='A2';
NODE_NAME     J106 A4
 '@S9S_MB_2U_LIB.S9S_MB_2U(SCH_1):PAGE144_I65@PURE_QUANTA.CONN112_10137002101LF(CHIPS)':
 'A4': CDS_PINID='A4';
NODE_NAME     J106 B1
 '@S9S_MB_2U_LIB.S9S_MB_2U(SCH_1):PAGE144_I65@PURE_QUANTA.CONN112_10137002101LF(CHIPS)':
 'B1': CDS_PINID='B1';
NODE_NAME     J106 B3
 '@S9S_MB_2U_LIB.S9S_MB_2U(SCH_1):PAGE144_I65@PURE_QUANTA.CONN112_10137002101LF(CHIPS)':
 'B3': CDS_PINID='B3';
NODE_NAME     J106 D2
 '@S9S_MB_2U_LIB.S9S_MB_2U(SCH_1):PAGE144_I65@PURE_QUANTA.CONN112_10137002101LF(CHIPS)':
 'D2': CDS_PINID='D2';
NODE_NAME     J106 D4
 '@S9S_MB_2U_LIB.S9S_MB_2U(SCH_1):PAGE144_I65@PURE_QUANTA.CONN112_10137002101LF(CHIPS)':
 'D4': CDS_PINID='D4';
NODE_NAME     J106 E1
 '@S9S_MB_2U_LIB.S9S_MB_2U(SCH_1):PAGE144_I65@PURE_QUANTA.CONN112_10137002101LF(CHIPS)':
 'E1': CDS_PINID='E1';
NODE_NAME     J106 E3
 '@S9S_MB_2U_LIB.S9S_MB_2U(SCH_1):PAGE144_I65@PURE_QUANTA.CONN112_10137002101LF(CHIPS)':
 'E3': CDS_PINID='E3';
NODE_NAME     J106 G2
 '@S9S_MB_2U_LIB.S9S_MB_2U(SCH_1):PAGE144_I65@PURE_QUANTA.CONN112_10137002101LF(CHIPS)':
 'G2': CDS_PINID='G2';
NODE_NAME     J106 G4
 '@S9S_MB_2U_LIB.S9S_MB_2U(SCH_1):PAGE144_I65@PURE_QUANTA.CONN112_10137002101LF(CHIPS)':
 'G4': CDS_PINID='G4';
NODE_NAME     J106 H1
 '@S9S_MB_2U_LIB.S9S_MB_2U(SCH_1):PAGE144_I65@PURE_QUANTA.CONN112_10137002101LF(CHIPS)':
 'H1': CDS_PINID='H1';
NODE_NAME     J106 H3
 '@S9S_MB_2U_LIB.S9S_MB_2U(SCH_1):PAGE144_I65@PURE_QUANTA.CONN112_10137002101LF(CHIPS)':
 'H3': CDS_PINID='H3';
NODE_NAME     J106 J2
 '@S9S_MB_2U_LIB.S9S_MB_2U(SCH_1):PAGE144_I65@PURE_QUANTA.CONN112_10137002101LF(CHIPS)':
 'J2': CDS_PINID='J2';
NODE_NAME     J106 J4
 '@S9S_MB_2U_LIB.S9S_MB_2U(SCH_1):PAGE144_I65@PURE_QUANTA.CONN112_10137002101LF(CHIPS)':
 'J4': CDS_PINID='J4';
NODE_NAME     J106 K1
 '@S9S_MB_2U_LIB.S9S_MB_2U(SCH_1):PAGE144_I65@PURE_QUANTA.CONN112_10137002101LF(CHIPS)':
 'K1': CDS_PINID='K1';
NODE_NAME     J106 K3
 '@S9S_MB_2U_LIB.S9S_MB_2U(SCH_1):PAGE144_I65@PURE_QUANTA.CONN112_10137002101LF(CHIPS)':
 'K3': CDS_PINID='K3';
NODE_NAME     J106 M2
 '@S9S_MB_2U_LIB.S9S_MB_2U(SCH_1):PAGE144_I65@PURE_QUANTA.CONN112_10137002101LF(CHIPS)':
 'M2': CDS_PINID='M2';
NODE_NAME     J106 M4
 '@S9S_MB_2U_LIB.S9S_MB_2U(SCH_1):PAGE144_I65@PURE_QUANTA.CONN112_10137002101LF(CHIPS)':
 'M4': CDS_PINID='M4';
NODE_NAME     J106 N1
 '@S9S_MB_2U_LIB.S9S_MB_2U(SCH_1):PAGE144_I65@PURE_QUANTA.CONN112_10137002101LF(CHIPS)':
 'N1': CDS_PINID='N1';
NODE_NAME     J106 N3
 '@S9S_MB_2U_LIB.S9S_MB_2U(SCH_1):PAGE144_I65@PURE_QUANTA.CONN112_10137002101LF(CHIPS)':
 'N3': CDS_PINID='N3';
NODE_NAME     J106 A6
 '@S9S_MB_2U_LIB.S9S_MB_2U(SCH_1):PAGE144_I68@PURE_QUANTA.CONN112_10137002101LF(CHIPS)':
 'A6': CDS_PINID='A6';
NODE_NAME     J106 A8
 '@S9S_MB_2U_LIB.S9S_MB_2U(SCH_1):PAGE144_I68@PURE_QUANTA.CONN112_10137002101LF(CHIPS)':
 'A8': CDS_PINID='A8';
NODE_NAME     J106 B5
 '@S9S_MB_2U_LIB.S9S_MB_2U(SCH_1):PAGE144_I68@PURE_QUANTA.CONN112_10137002101LF(CHIPS)':
 'B5': CDS_PINID='B5';
NODE_NAME     J106 B7
 '@S9S_MB_2U_LIB.S9S_MB_2U(SCH_1):PAGE144_I68@PURE_QUANTA.CONN112_10137002101LF(CHIPS)':
 'B7': CDS_PINID='B7';
NODE_NAME     J106 D6
 '@S9S_MB_2U_LIB.S9S_MB_2U(SCH_1):PAGE144_I68@PURE_QUANTA.CONN112_10137002101LF(CHIPS)':
 'D6': CDS_PINID='D6';
NODE_NAME     J106 D8
 '@S9S_MB_2U_LIB.S9S_MB_2U(SCH_1):PAGE144_I68@PURE_QUANTA.CONN112_10137002101LF(CHIPS)':
 'D8': CDS_PINID='D8';
NODE_NAME     J106 E5
 '@S9S_MB_2U_LIB.S9S_MB_2U(SCH_1):PAGE144_I68@PURE_QUANTA.CONN112_10137002101LF(CHIPS)':
 'E5': CDS_PINID='E5';
NODE_NAME     J106 E7
 '@S9S_MB_2U_LIB.S9S_MB_2U(SCH_1):PAGE144_I68@PURE_QUANTA.CONN112_10137002101LF(CHIPS)':
 'E7': CDS_PINID='E7';
NODE_NAME     J106 G6
 '@S9S_MB_2U_LIB.S9S_MB_2U(SCH_1):PAGE144_I68@PURE_QUANTA.CONN112_10137002101LF(CHIPS)':
 'G6': CDS_PINID='G6';
NODE_NAME     J106 G8
 '@S9S_MB_2U_LIB.S9S_MB_2U(SCH_1):PAGE144_I68@PURE_QUANTA.CONN112_10137002101LF(CHIPS)':
 'G8': CDS_PINID='G8';
NODE_NAME     J106 H5
 '@S9S_MB_2U_LIB.S9S_MB_2U(SCH_1):PAGE144_I68@PURE_QUANTA.CONN112_10137002101LF(CHIPS)':
 'H5': CDS_PINID='H5';
NODE_NAME     J106 H7
 '@S9S_MB_2U_LIB.S9S_MB_2U(SCH_1):PAGE144_I68@PURE_QUANTA.CONN112_10137002101LF(CHIPS)':
 'H7': CDS_PINID='H7';
NODE_NAME     J106 J6
 '@S9S_MB_2U_LIB.S9S_MB_2U(SCH_1):PAGE144_I68@PURE_QUANTA.CONN112_10137002101LF(CHIPS)':
 'J6': CDS_PINID='J6';
NODE_NAME     J106 J8
 '@S9S_MB_2U_LIB.S9S_MB_2U(SCH_1):PAGE144_I68@PURE_QUANTA.CONN112_10137002101LF(CHIPS)':
 'J8': CDS_PINID='J8';
NODE_NAME     J106 K5
 '@S9S_MB_2U_LIB.S9S_MB_2U(SCH_1):PAGE144_I68@PURE_QUANTA.CONN112_10137002101LF(CHIPS)':
 'K5': CDS_PINID='K5';
NODE_NAME     J106 K7
 '@S9S_MB_2U_LIB.S9S_MB_2U(SCH_1):PAGE144_I68@PURE_QUANTA.CONN112_10137002101LF(CHIPS)':
 'K7': CDS_PINID='K7';
NODE_NAME     J106 M6
 '@S9S_MB_2U_LIB.S9S_MB_2U(SCH_1):PAGE144_I68@PURE_QUANTA.CONN112_10137002101LF(CHIPS)':
 'M6': CDS_PINID='M6';
NODE_NAME     J106 M8
 '@S9S_MB_2U_LIB.S9S_MB_2U(SCH_1):PAGE144_I68@PURE_QUANTA.CONN112_10137002101LF(CHIPS)':
 'M8': CDS_PINID='M8';
NODE_NAME     J106 N5
 '@S9S_MB_2U_LIB.S9S_MB_2U(SCH_1):PAGE144_I68@PURE_QUANTA.CONN112_10137002101LF(CHIPS)':
 'N5': CDS_PINID='N5';
NODE_NAME     J106 N7
 '@S9S_MB_2U_LIB.S9S_MB_2U(SCH_1):PAGE144_I68@PURE_QUANTA.CONN112_10137002101LF(CHIPS)':
 'N7': CDS_PINID='N7';
NODE_NAME     R2666 2
 '@S9S_MB_2U_LIB.S9S_MB_2U(SCH_1):PAGE222_I16@PURE_QUANTA.Q_RES(CHIPS)':
 'B': CDS_PINID='B';
NODE_NAME     C1708 2
 '@S9S_MB_2U_LIB.S9S_MB_2U(SCH_1):PAGE222_I34@PURE_QUANTA.Q_CAP(CHIPS)':
 'B': CDS_PINID='B';
NODE_NAME     Q67 1
 '@S9S_MB_2U_LIB.S9S_MB_2U(SCH_1):PAGE145_I33@PURE_QUANTA.MOSFET_NCH_DUAL(CHIPS)':
 'S1': CDS_PINID='S1';
NODE_NAME     Q70 1
 '@S9S_MB_2U_LIB.S9S_MB_2U(SCH_1):PAGE145_I35@PURE_QUANTA.MOSFET_NCH_DUAL(CHIPS)':
 'S1': CDS_PINID='S1';
NODE_NAME     Q72 1
 '@S9S_MB_2U_LIB.S9S_MB_2U(SCH_1):PAGE145_I37@PURE_QUANTA.MOSFET_NCH_DUAL(CHIPS)':
 'S1': CDS_PINID='S1';
NODE_NAME     R2831 2
 '@S9S_MB_2U_LIB.S9S_MB_2U(SCH_1):PAGE145_I56@PURE_QUANTA.Q_RES(CHIPS)':
 'B': CDS_PINID='B';
NODE_NAME     R2829 2
 '@S9S_MB_2U_LIB.S9S_MB_2U(SCH_1):PAGE145_I58@PURE_QUANTA.Q_RES(CHIPS)':
 'B': CDS_PINID='B';
NODE_NAME     R2833 2
 '@S9S_MB_2U_LIB.S9S_MB_2U(SCH_1):PAGE145_I60@PURE_QUANTA.Q_RES(CHIPS)':
 'B': CDS_PINID='B';
NODE_NAME     R2838 2
 '@S9S_MB_2U_LIB.S9S_MB_2U(SCH_1):PAGE145_I62@PURE_QUANTA.Q_RES(CHIPS)':
 'B': CDS_PINID='B';
NODE_NAME     C1766 2
 '@S9S_MB_2U_LIB.S9S_MB_2U(SCH_1):PAGE222_I66@PURE_QUANTA.Q_CAP(CHIPS)':
 'B': CDS_PINID='B';
NODE_NAME     U193 4
 '@S9S_MB_2U_LIB.S9S_MB_2U(SCH_1):PAGE239_I57@PURE_QUANTA.MAX11617EEET(CHIPS)':
 'AIN8': CDS_PINID='AIN8';
NODE_NAME     U193 3
 '@S9S_MB_2U_LIB.S9S_MB_2U(SCH_1):PAGE239_I57@PURE_QUANTA.MAX11617EEET(CHIPS)':
 'AIN9': CDS_PINID='AIN9';
NODE_NAME     U193 2
 '@S9S_MB_2U_LIB.S9S_MB_2U(SCH_1):PAGE239_I57@PURE_QUANTA.MAX11617EEET(CHIPS)':
 'AIN10': CDS_PINID='AIN10';
NODE_NAME     U193 15
 '@S9S_MB_2U_LIB.S9S_MB_2U(SCH_1):PAGE239_I57@PURE_QUANTA.MAX11617EEET(CHIPS)':
 'GND': CDS_PINID='GND';
NODE_NAME     C1757 2
 '@S9S_MB_2U_LIB.S9S_MB_2U(SCH_1):PAGE239_I58@PURE_QUANTA.Q_CAP(CHIPS)':
 'B': CDS_PINID='B';
NODE_NAME     C1768 2
 '@S9S_MB_2U_LIB.S9S_MB_2U(SCH_1):PAGE239_I61@PURE_QUANTA.Q_CAP(CHIPS)':
 'B': CDS_PINID='B';
NODE_NAME     C1767 2
 '@S9S_MB_2U_LIB.S9S_MB_2U(SCH_1):PAGE239_I68@PURE_QUANTA.Q_CAP(CHIPS)':
 'B': CDS_PINID='B';
NODE_NAME     C1347 2
 '@S9S_MB_2U_LIB.S9S_MB_2U(SCH_1):PAGE239_I70@PURE_QUANTA.Q_CAP(CHIPS)':
 'B': CDS_PINID='B';
NODE_NAME     U210 3
 '@S9S_MB_2U_LIB.S9S_MB_2U(SCH_1):PAGE154_I189@PURE_QUANTA.74LVC1G08W57(CHIPS)':
 'GND': CDS_PINID='GND';
NODE_NAME     U208 3
 '@S9S_MB_2U_LIB.S9S_MB_2U(SCH_1):PAGE154_I190@PURE_QUANTA.74LVC1G08W57(CHIPS)':
 'GND': CDS_PINID='GND';
NODE_NAME     U181 12
 '@S9S_MB_2U_LIB.S9S_MB_2U(SCH_1):PAGE214_I66@PURE_QUANTA.PCA9539RPW(CHIPS)':
 'VSS': CDS_PINID='VSS';
NODE_NAME     R2696 2
 '@S9S_MB_2U_LIB.S9S_MB_2U(SCH_1):PAGE214_I75@PURE_QUANTA.Q_RES(CHIPS)':
 'B': CDS_PINID='B';
NODE_NAME     R2694 2
 '@S9S_MB_2U_LIB.S9S_MB_2U(SCH_1):PAGE214_I77@PURE_QUANTA.Q_RES(CHIPS)':
 'B': CDS_PINID='B';
NODE_NAME     C1713 2
 '@S9S_MB_2U_LIB.S9S_MB_2U(SCH_1):PAGE214_I87@PURE_QUANTA.Q_CAP(CHIPS)':
 'B': CDS_PINID='B';
NODE_NAME     U195 2
 '@S9S_MB_2U_LIB.S9S_MB_2U(SCH_1):PAGE140_I65@PURE_QUANTA.74LVC2G17GW(CHIPS)':
 'GND': CDS_PINID='GND';
NODE_NAME     C1769 2
 '@S9S_MB_2U_LIB.S9S_MB_2U(SCH_1):PAGE140_I89@PURE_QUANTA.Q_CAP(CHIPS)':
 'B': CDS_PINID='B';
NODE_NAME     R2915 2
 '@S9S_MB_2U_LIB.S9S_MB_2U(SCH_1):PAGE140_I92@PURE_QUANTA.Q_RES(CHIPS)':
 'B': CDS_PINID='B';
NODE_NAME     R2916 2
 '@S9S_MB_2U_LIB.S9S_MB_2U(SCH_1):PAGE140_I93@PURE_QUANTA.Q_RES(CHIPS)':
 'B': CDS_PINID='B';
NODE_NAME     R2926 2
 '@S9S_MB_2U_LIB.S9S_MB_2U(SCH_1):PAGE140_I121@PURE_QUANTA.Q_RES(CHIPS)':
 'B': CDS_PINID='B';
NODE_NAME     U196 2
 '@S9S_MB_2U_LIB.S9S_MB_2U(SCH_1):PAGE140_I127@PURE_QUANTA.74LVC2G17GW(CHIPS)':
 'GND': CDS_PINID='GND';
NODE_NAME     C1770 2
 '@S9S_MB_2U_LIB.S9S_MB_2U(SCH_1):PAGE140_I140@PURE_QUANTA.Q_CAP(CHIPS)':
 'B': CDS_PINID='B';
NODE_NAME     Q67 4
 '@S9S_MB_2U_LIB.S9S_MB_2U(SCH_1):PAGE145_I82@PURE_QUANTA.MOSFET_NCH_DUAL(CHIPS)':
 'S2': CDS_PINID='S2';
NODE_NAME     Q69 4
 '@S9S_MB_2U_LIB.S9S_MB_2U(SCH_1):PAGE145_I88@PURE_QUANTA.MOSFET_NCH_DUAL(CHIPS)':
 'S2': CDS_PINID='S2';
NODE_NAME     C1754 2
 '@S9S_MB_2U_LIB.S9S_MB_2U(SCH_1):PAGE145_I92@PURE_QUANTA.Q_CAP(CHIPS)':
 'B': CDS_PINID='B';
NODE_NAME     Q71 4
 '@S9S_MB_2U_LIB.S9S_MB_2U(SCH_1):PAGE145_I100@PURE_QUANTA.MOSFET_NCH_DUAL(CHIPS)':
 'S2': CDS_PINID='S2';
NODE_NAME     C1756 2
 '@S9S_MB_2U_LIB.S9S_MB_2U(SCH_1):PAGE145_I105@PURE_QUANTA.Q_CAP(CHIPS)':
 'B': CDS_PINID='B';
NODE_NAME     C1774 2
 '@S9S_MB_2U_LIB.S9S_MB_2U(SCH_1):PAGE145_I111@PURE_QUANTA.Q_CAP(CHIPS)':
 'B': CDS_PINID='B';
NODE_NAME     C1773 2
 '@S9S_MB_2U_LIB.S9S_MB_2U(SCH_1):PAGE145_I114@PURE_QUANTA.Q_CAP(CHIPS)':
 'B': CDS_PINID='B';
NODE_NAME     C1772 2
 '@S9S_MB_2U_LIB.S9S_MB_2U(SCH_1):PAGE145_I116@PURE_QUANTA.Q_CAP(CHIPS)':
 'B': CDS_PINID='B';
NODE_NAME     Q69 1
 '@S9S_MB_2U_LIB.S9S_MB_2U(SCH_1):PAGE145_I117@PURE_QUANTA.MOSFET_NCH_DUAL(CHIPS)':
 'S1': CDS_PINID='S1';
NODE_NAME     Q71 1
 '@S9S_MB_2U_LIB.S9S_MB_2U(SCH_1):PAGE145_I118@PURE_QUANTA.MOSFET_NCH_DUAL(CHIPS)':
 'S1': CDS_PINID='S1';
NODE_NAME     Q72 4
 '@S9S_MB_2U_LIB.S9S_MB_2U(SCH_1):PAGE145_I119@PURE_QUANTA.MOSFET_NCH_DUAL(CHIPS)':
 'S2': CDS_PINID='S2';
NODE_NAME     Q70 4
 '@S9S_MB_2U_LIB.S9S_MB_2U(SCH_1):PAGE145_I120@PURE_QUANTA.MOSFET_NCH_DUAL(CHIPS)':
 'S2': CDS_PINID='S2';
NODE_NAME     R2937 2
 '@S9S_MB_2U_LIB.S9S_MB_2U(SCH_1):PAGE140_I160@PURE_QUANTA.Q_RES(CHIPS)':
 'B': CDS_PINID='B';
NODE_NAME     C1775 2
 '@S9S_MB_2U_LIB.S9S_MB_2U(SCH_1):PAGE230_I14@PURE_QUANTA.Q_CAP(CHIPS)':
 'B': CDS_PINID='B';
NODE_NAME     R2941 2
 '@S9S_MB_2U_LIB.S9S_MB_2U(SCH_1):PAGE230_I29@PURE_QUANTA.Q_RES(CHIPS)':
 'B': CDS_PINID='B';
NODE_NAME     R2948 2
 '@S9S_MB_2U_LIB.S9S_MB_2U(SCH_1):PAGE230_I30@PURE_QUANTA.Q_RES(CHIPS)':
 'B': CDS_PINID='B';
NODE_NAME     C5232 2
 '@S9S_MB_2U_LIB.S9S_MB_2U(SCH_1):PAGE155_I81@PURE_QUANTA.Q_CAP(CHIPS)':
 'B': CDS_PINID='B';
NODE_NAME     R5238 2
 '@S9S_MB_2U_LIB.S9S_MB_2U(SCH_1):PAGE155_I83@PURE_QUANTA.Q_RES(CHIPS)':
 'B': CDS_PINID='B';
NODE_NAME     U5201 10
 '@S9S_MB_2U_LIB.S9S_MB_2U(SCH_1):PAGE155_I84@PURE_QUANTA.TUSB211IRWBR(CHIPS)':
 'GND': CDS_PINID='GND';
NODE_NAME     C5236 2
 '@S9S_MB_2U_LIB.S9S_MB_2U(SCH_1):PAGE155_I87@PURE_QUANTA.Q_CAP(CHIPS)':
 'B': CDS_PINID='B';
NODE_NAME     C5229 2
 '@S9S_MB_2U_LIB.S9S_MB_2U(SCH_1):PAGE155_I88@PURE_QUANTA.Q_CAP(CHIPS)':
 'B': CDS_PINID='B';
NODE_NAME     C5234 2
 '@S9S_MB_2U_LIB.S9S_MB_2U(SCH_1):PAGE155_I92@PURE_QUANTA.Q_CAP(CHIPS)':
 'B': CDS_PINID='B';
NODE_NAME     Q74 1
 '@S9S_MB_2U_LIB.S9S_MB_2U(SCH_1):PAGE145_I121@PURE_QUANTA.MOSFET_NCH_DUAL(CHIPS)':
 'S1': CDS_PINID='S1';
NODE_NAME     Q74 4
 '@S9S_MB_2U_LIB.S9S_MB_2U(SCH_1):PAGE145_I122@PURE_QUANTA.MOSFET_NCH_DUAL(CHIPS)':
 'S2': CDS_PINID='S2';
NODE_NAME     C1804 2
 '@S9S_MB_2U_LIB.S9S_MB_2U(SCH_1):PAGE145_I125@PURE_QUANTA.Q_CAP(CHIPS)':
 'B': CDS_PINID='B';
NODE_NAME     R3032 2
 '@S9S_MB_2U_LIB.S9S_MB_2U(SCH_1):PAGE145_I134@PURE_QUANTA.Q_RES(CHIPS)':
 'B': CDS_PINID='B';
NODE_NAME     R3028 2
 '@S9S_MB_2U_LIB.S9S_MB_2U(SCH_1):PAGE145_I139@PURE_QUANTA.Q_RES(CHIPS)':
 'B': CDS_PINID='B';
NODE_NAME     C1802 2
 '@S9S_MB_2U_LIB.S9S_MB_2U(SCH_1):PAGE145_I148@PURE_QUANTA.Q_CAP(CHIPS)':
 'B': CDS_PINID='B';
NODE_NAME     Q75 4
 '@S9S_MB_2U_LIB.S9S_MB_2U(SCH_1):PAGE145_I151@PURE_QUANTA.MOSFET_NCH_DUAL(CHIPS)':
 'S2': CDS_PINID='S2';
NODE_NAME     Q75 1
 '@S9S_MB_2U_LIB.S9S_MB_2U(SCH_1):PAGE145_I152@PURE_QUANTA.MOSFET_NCH_DUAL(CHIPS)':
 'S1': CDS_PINID='S1';
NODE_NAME     Q80 4
 '@S9S_MB_2U_LIB.S9S_MB_2U(SCH_1):PAGE305_I2@PURE_QUANTA.MOSFET_NCH_DUAL(CHIPS)':
 'S2': CDS_PINID='S2';
NODE_NAME     Q80 1
 '@S9S_MB_2U_LIB.S9S_MB_2U(SCH_1):PAGE305_I4@PURE_QUANTA.MOSFET_NCH_DUAL(CHIPS)':
 'S1': CDS_PINID='S1';
NODE_NAME     Q79 4
 '@S9S_MB_2U_LIB.S9S_MB_2U(SCH_1):PAGE305_I7@PURE_QUANTA.MOSFET_NCH_DUAL(CHIPS)':
 'S2': CDS_PINID='S2';
NODE_NAME     Q79 1
 '@S9S_MB_2U_LIB.S9S_MB_2U(SCH_1):PAGE305_I8@PURE_QUANTA.MOSFET_NCH_DUAL(CHIPS)':
 'S1': CDS_PINID='S1';
NODE_NAME     Q83 1
 '@S9S_MB_2U_LIB.S9S_MB_2U(SCH_1):PAGE305_I32@PURE_QUANTA.MOSFET_NCH_DUAL(CHIPS)':
 'S1': CDS_PINID='S1';
NODE_NAME     Q81 4
 '@S9S_MB_2U_LIB.S9S_MB_2U(SCH_1):PAGE305_I40@PURE_QUANTA.MOSFET_NCH_DUAL(CHIPS)':
 'S2': CDS_PINID='S2';
NODE_NAME     Q81 1
 '@S9S_MB_2U_LIB.S9S_MB_2U(SCH_1):PAGE305_I41@PURE_QUANTA.MOSFET_NCH_DUAL(CHIPS)':
 'S1': CDS_PINID='S1';
NODE_NAME     Q88 1
 '@S9S_MB_2U_LIB.S9S_MB_2U(SCH_1):PAGE241_I8@PURE_QUANTA.MOSFET_NCH_DUAL(CHIPS)':
 'S1': CDS_PINID='S1';
NODE_NAME     Q87 4
 '@S9S_MB_2U_LIB.S9S_MB_2U(SCH_1):PAGE241_I16@PURE_QUANTA.MOSFET_NCH_DUAL(CHIPS)':
 'S2': CDS_PINID='S2';
NODE_NAME     Q87 1
 '@S9S_MB_2U_LIB.S9S_MB_2U(SCH_1):PAGE241_I17@PURE_QUANTA.MOSFET_NCH_DUAL(CHIPS)':
 'S1': CDS_PINID='S1';
NODE_NAME     Q76 4
 '@S9S_MB_2U_LIB.S9S_MB_2U(SCH_1):PAGE242_I8@PURE_QUANTA.MOSFET_NCH_DUAL(CHIPS)':
 'S2': CDS_PINID='S2';
NODE_NAME     Q96 4
 '@S9S_MB_2U_LIB.S9S_MB_2U(SCH_1):PAGE145_I159@PURE_QUANTA.MOSFET_NCH_DUAL(CHIPS)':
 'S2': CDS_PINID='S2';
NODE_NAME     Q85 4
 '@S9S_MB_2U_LIB.S9S_MB_2U(SCH_1):PAGE306_I3@PURE_QUANTA.MOSFET_NCH_DUAL(CHIPS)':
 'S2': CDS_PINID='S2';
NODE_NAME     Q85 1
 '@S9S_MB_2U_LIB.S9S_MB_2U(SCH_1):PAGE306_I6@PURE_QUANTA.MOSFET_NCH_DUAL(CHIPS)':
 'S1': CDS_PINID='S1';
NODE_NAME     Q84 4
 '@S9S_MB_2U_LIB.S9S_MB_2U(SCH_1):PAGE306_I8@PURE_QUANTA.MOSFET_NCH_DUAL(CHIPS)':
 'S2': CDS_PINID='S2';
NODE_NAME     Q84 1
 '@S9S_MB_2U_LIB.S9S_MB_2U(SCH_1):PAGE306_I18@PURE_QUANTA.MOSFET_NCH_DUAL(CHIPS)':
 'S1': CDS_PINID='S1';
NODE_NAME     Q86 4
 '@S9S_MB_2U_LIB.S9S_MB_2U(SCH_1):PAGE306_I27@PURE_QUANTA.MOSFET_NCH_DUAL(CHIPS)':
 'S2': CDS_PINID='S2';
NODE_NAME     Q86 1
 '@S9S_MB_2U_LIB.S9S_MB_2U(SCH_1):PAGE306_I35@PURE_QUANTA.MOSFET_NCH_DUAL(CHIPS)':
 'S1': CDS_PINID='S1';
NODE_NAME     Q77 4
 '@S9S_MB_2U_LIB.S9S_MB_2U(SCH_1):PAGE242_I3@PURE_QUANTA.MOSFET_NCH_DUAL(CHIPS)':
 'S2': CDS_PINID='S2';
NODE_NAME     Q77 1
 '@S9S_MB_2U_LIB.S9S_MB_2U(SCH_1):PAGE242_I6@PURE_QUANTA.MOSFET_NCH_DUAL(CHIPS)':
 'S1': CDS_PINID='S1';
NODE_NAME     Q76 1
 '@S9S_MB_2U_LIB.S9S_MB_2U(SCH_1):PAGE242_I17@PURE_QUANTA.MOSFET_NCH_DUAL(CHIPS)':
 'S1': CDS_PINID='S1';
NODE_NAME     Q78 4
 '@S9S_MB_2U_LIB.S9S_MB_2U(SCH_1):PAGE242_I26@PURE_QUANTA.MOSFET_NCH_DUAL(CHIPS)':
 'S2': CDS_PINID='S2';
NODE_NAME     Q78 1
 '@S9S_MB_2U_LIB.S9S_MB_2U(SCH_1):PAGE242_I34@PURE_QUANTA.MOSFET_NCH_DUAL(CHIPS)':
 'S1': CDS_PINID='S1';
NODE_NAME     D97 C
 '@S9S_MB_2U_LIB.S9S_MB_2U(SCH_1):PAGE242_I52@PURE_QUANTA.Q_LED(CHIPS)':
 'C': CDS_PINID='C';
NODE_NAME     D98 C
 '@S9S_MB_2U_LIB.S9S_MB_2U(SCH_1):PAGE242_I53@PURE_QUANTA.Q_LED(CHIPS)':
 'C': CDS_PINID='C';
NODE_NAME     D99 C
 '@S9S_MB_2U_LIB.S9S_MB_2U(SCH_1):PAGE242_I60@PURE_QUANTA.Q_LED(CHIPS)':
 'C': CDS_PINID='C';
NODE_NAME     U158 S
 '@S9S_MB_2U_LIB.S9S_MB_2U(SCH_1):PAGE234_I6@PURE_QUANTA.MOSFET_NCH_GDS_ESD_PROTECTED(CHIPS)':
 'S': CDS_PINID='S';
NODE_NAME     Q83 4
 '@S9S_MB_2U_LIB.S9S_MB_2U(SCH_1):PAGE306_I43@PURE_QUANTA.MOSFET_NCH_DUAL(CHIPS)':
 'S2': CDS_PINID='S2';
NODE_NAME     Q88 4
 '@S9S_MB_2U_LIB.S9S_MB_2U(SCH_1):PAGE241_I42@PURE_QUANTA.MOSFET_NCH_DUAL(CHIPS)':
 'S2': CDS_PINID='S2';
NODE_NAME     J100 2
 '@S9S_MB_2U_LIB.S9S_MB_2U(SCH_1):PAGE215_I32@PURE_QUANTA.SCONN20_513860200CV01(CHIPS)':
 '2': CDS_PINID='\2\';
NODE_NAME     J100 6
 '@S9S_MB_2U_LIB.S9S_MB_2U(SCH_1):PAGE215_I32@PURE_QUANTA.SCONN20_513860200CV01(CHIPS)':
 '6': CDS_PINID='\6\';
NODE_NAME     J100 10
 '@S9S_MB_2U_LIB.S9S_MB_2U(SCH_1):PAGE215_I32@PURE_QUANTA.SCONN20_513860200CV01(CHIPS)':
 '10': CDS_PINID='\10\';
NODE_NAME     J100 12
 '@S9S_MB_2U_LIB.S9S_MB_2U(SCH_1):PAGE215_I32@PURE_QUANTA.SCONN20_513860200CV01(CHIPS)':
 '12': CDS_PINID='\12\';
NODE_NAME     J100 15
 '@S9S_MB_2U_LIB.S9S_MB_2U(SCH_1):PAGE215_I32@PURE_QUANTA.SCONN20_513860200CV01(CHIPS)':
 '15': CDS_PINID='\15\';
NODE_NAME     J100 17
 '@S9S_MB_2U_LIB.S9S_MB_2U(SCH_1):PAGE215_I32@PURE_QUANTA.SCONN20_513860200CV01(CHIPS)':
 '17': CDS_PINID='\17\';
NODE_NAME     OSC1 2
 '@S9S_MB_2U_LIB.S9S_MB_2U(SCH_1):PAGE152_I76@PURE_QUANTA.Q_OSC4P(CHIPS)':
 'GND': CDS_PINID='GND';
NODE_NAME     J1 G1
 '@S9S_MB_2U_LIB.S9S_MB_2U(SCH_1):PAGE82_I203@PURE_QUANTA.SCONN288_ADR50017P130CC(CHIPS)':
 'G1': CDS_PINID='G1';
NODE_NAME     J1 G2
 '@S9S_MB_2U_LIB.S9S_MB_2U(SCH_1):PAGE82_I203@PURE_QUANTA.SCONN288_ADR50017P130CC(CHIPS)':
 'G2': CDS_PINID='G2';
NODE_NAME     J1 G3
 '@S9S_MB_2U_LIB.S9S_MB_2U(SCH_1):PAGE82_I203@PURE_QUANTA.SCONN288_ADR50017P130CC(CHIPS)':
 'G3': CDS_PINID='G3';
NODE_NAME     J1 6
 '@S9S_MB_2U_LIB.S9S_MB_2U(SCH_1):PAGE82_I203@PURE_QUANTA.SCONN288_ADR50017P130CC(CHIPS)':
 'VSS0': CDS_PINID='VSS0';
NODE_NAME     J1 8
 '@S9S_MB_2U_LIB.S9S_MB_2U(SCH_1):PAGE82_I203@PURE_QUANTA.SCONN288_ADR50017P130CC(CHIPS)':
 'VSS1': CDS_PINID='VSS1';
NODE_NAME     J1 10
 '@S9S_MB_2U_LIB.S9S_MB_2U(SCH_1):PAGE82_I203@PURE_QUANTA.SCONN288_ADR50017P130CC(CHIPS)':
 'VSS2': CDS_PINID='VSS2';
NODE_NAME     J1 13
 '@S9S_MB_2U_LIB.S9S_MB_2U(SCH_1):PAGE82_I203@PURE_QUANTA.SCONN288_ADR50017P130CC(CHIPS)':
 'VSS3': CDS_PINID='VSS3';
NODE_NAME     J1 15
 '@S9S_MB_2U_LIB.S9S_MB_2U(SCH_1):PAGE82_I203@PURE_QUANTA.SCONN288_ADR50017P130CC(CHIPS)':
 'VSS4': CDS_PINID='VSS4';
NODE_NAME     J1 17
 '@S9S_MB_2U_LIB.S9S_MB_2U(SCH_1):PAGE82_I203@PURE_QUANTA.SCONN288_ADR50017P130CC(CHIPS)':
 'VSS5': CDS_PINID='VSS5';
NODE_NAME     J1 19
 '@S9S_MB_2U_LIB.S9S_MB_2U(SCH_1):PAGE82_I203@PURE_QUANTA.SCONN288_ADR50017P130CC(CHIPS)':
 'VSS6': CDS_PINID='VSS6';
NODE_NAME     J1 21
 '@S9S_MB_2U_LIB.S9S_MB_2U(SCH_1):PAGE82_I203@PURE_QUANTA.SCONN288_ADR50017P130CC(CHIPS)':
 'VSS7': CDS_PINID='VSS7';
NODE_NAME     J1 24
 '@S9S_MB_2U_LIB.S9S_MB_2U(SCH_1):PAGE82_I203@PURE_QUANTA.SCONN288_ADR50017P130CC(CHIPS)':
 'VSS8': CDS_PINID='VSS8';
NODE_NAME     J1 26
 '@S9S_MB_2U_LIB.S9S_MB_2U(SCH_1):PAGE82_I203@PURE_QUANTA.SCONN288_ADR50017P130CC(CHIPS)':
 'VSS9': CDS_PINID='VSS9';
NODE_NAME     J1 28
 '@S9S_MB_2U_LIB.S9S_MB_2U(SCH_1):PAGE82_I203@PURE_QUANTA.SCONN288_ADR50017P130CC(CHIPS)':
 'VSS10': CDS_PINID='VSS10';
NODE_NAME     J1 30
 '@S9S_MB_2U_LIB.S9S_MB_2U(SCH_1):PAGE82_I203@PURE_QUANTA.SCONN288_ADR50017P130CC(CHIPS)':
 'VSS11': CDS_PINID='VSS11';
NODE_NAME     J1 32
 '@S9S_MB_2U_LIB.S9S_MB_2U(SCH_1):PAGE82_I203@PURE_QUANTA.SCONN288_ADR50017P130CC(CHIPS)':
 'VSS12': CDS_PINID='VSS12';
NODE_NAME     J1 35
 '@S9S_MB_2U_LIB.S9S_MB_2U(SCH_1):PAGE82_I203@PURE_QUANTA.SCONN288_ADR50017P130CC(CHIPS)':
 'VSS13': CDS_PINID='VSS13';
NODE_NAME     J1 37
 '@S9S_MB_2U_LIB.S9S_MB_2U(SCH_1):PAGE82_I203@PURE_QUANTA.SCONN288_ADR50017P130CC(CHIPS)':
 'VSS14': CDS_PINID='VSS14';
NODE_NAME     J1 39
 '@S9S_MB_2U_LIB.S9S_MB_2U(SCH_1):PAGE82_I203@PURE_QUANTA.SCONN288_ADR50017P130CC(CHIPS)':
 'VSS15': CDS_PINID='VSS15';
NODE_NAME     J1 41
 '@S9S_MB_2U_LIB.S9S_MB_2U(SCH_1):PAGE82_I203@PURE_QUANTA.SCONN288_ADR50017P130CC(CHIPS)':
 'VSS16': CDS_PINID='VSS16';
NODE_NAME     J1 43
 '@S9S_MB_2U_LIB.S9S_MB_2U(SCH_1):PAGE82_I203@PURE_QUANTA.SCONN288_ADR50017P130CC(CHIPS)':
 'VSS17': CDS_PINID='VSS17';
NODE_NAME     J1 46
 '@S9S_MB_2U_LIB.S9S_MB_2U(SCH_1):PAGE82_I203@PURE_QUANTA.SCONN288_ADR50017P130CC(CHIPS)':
 'VSS18': CDS_PINID='VSS18';
NODE_NAME     J1 48
 '@S9S_MB_2U_LIB.S9S_MB_2U(SCH_1):PAGE82_I203@PURE_QUANTA.SCONN288_ADR50017P130CC(CHIPS)':
 'VSS19': CDS_PINID='VSS19';
NODE_NAME     J1 50
 '@S9S_MB_2U_LIB.S9S_MB_2U(SCH_1):PAGE82_I203@PURE_QUANTA.SCONN288_ADR50017P130CC(CHIPS)':
 'VSS20': CDS_PINID='VSS20';
NODE_NAME     J1 52
 '@S9S_MB_2U_LIB.S9S_MB_2U(SCH_1):PAGE82_I203@PURE_QUANTA.SCONN288_ADR50017P130CC(CHIPS)':
 'VSS21': CDS_PINID='VSS21';
NODE_NAME     J1 54
 '@S9S_MB_2U_LIB.S9S_MB_2U(SCH_1):PAGE82_I203@PURE_QUANTA.SCONN288_ADR50017P130CC(CHIPS)':
 'VSS22': CDS_PINID='VSS22';
NODE_NAME     J1 57
 '@S9S_MB_2U_LIB.S9S_MB_2U(SCH_1):PAGE82_I203@PURE_QUANTA.SCONN288_ADR50017P130CC(CHIPS)':
 'VSS23': CDS_PINID='VSS23';
NODE_NAME     J1 59
 '@S9S_MB_2U_LIB.S9S_MB_2U(SCH_1):PAGE82_I203@PURE_QUANTA.SCONN288_ADR50017P130CC(CHIPS)':
 'VSS24': CDS_PINID='VSS24';
NODE_NAME     J1 61
 '@S9S_MB_2U_LIB.S9S_MB_2U(SCH_1):PAGE82_I203@PURE_QUANTA.SCONN288_ADR50017P130CC(CHIPS)':
 'VSS25': CDS_PINID='VSS25';
NODE_NAME     J1 63
 '@S9S_MB_2U_LIB.S9S_MB_2U(SCH_1):PAGE82_I203@PURE_QUANTA.SCONN288_ADR50017P130CC(CHIPS)':
 'VSS26': CDS_PINID='VSS26';
NODE_NAME     J1 65
 '@S9S_MB_2U_LIB.S9S_MB_2U(SCH_1):PAGE82_I203@PURE_QUANTA.SCONN288_ADR50017P130CC(CHIPS)':
 'VSS27': CDS_PINID='VSS27';
NODE_NAME     J1 67
 '@S9S_MB_2U_LIB.S9S_MB_2U(SCH_1):PAGE82_I203@PURE_QUANTA.SCONN288_ADR50017P130CC(CHIPS)':
 'VSS28': CDS_PINID='VSS28';
NODE_NAME     J1 69
 '@S9S_MB_2U_LIB.S9S_MB_2U(SCH_1):PAGE82_I203@PURE_QUANTA.SCONN288_ADR50017P130CC(CHIPS)':
 'VSS29': CDS_PINID='VSS29';
NODE_NAME     J1 71
 '@S9S_MB_2U_LIB.S9S_MB_2U(SCH_1):PAGE82_I203@PURE_QUANTA.SCONN288_ADR50017P130CC(CHIPS)':
 'VSS30': CDS_PINID='VSS30';
NODE_NAME     J1 73
 '@S9S_MB_2U_LIB.S9S_MB_2U(SCH_1):PAGE82_I203@PURE_QUANTA.SCONN288_ADR50017P130CC(CHIPS)':
 'VSS31': CDS_PINID='VSS31';
NODE_NAME     J1 75
 '@S9S_MB_2U_LIB.S9S_MB_2U(SCH_1):PAGE82_I203@PURE_QUANTA.SCONN288_ADR50017P130CC(CHIPS)':
 'VSS32': CDS_PINID='VSS32';
NODE_NAME     J1 77
 '@S9S_MB_2U_LIB.S9S_MB_2U(SCH_1):PAGE82_I203@PURE_QUANTA.SCONN288_ADR50017P130CC(CHIPS)':
 'VSS33': CDS_PINID='VSS33';
NODE_NAME     J1 79
 '@S9S_MB_2U_LIB.S9S_MB_2U(SCH_1):PAGE82_I203@PURE_QUANTA.SCONN288_ADR50017P130CC(CHIPS)':
 'VSS34': CDS_PINID='VSS34';
NODE_NAME     J1 81
 '@S9S_MB_2U_LIB.S9S_MB_2U(SCH_1):PAGE82_I203@PURE_QUANTA.SCONN288_ADR50017P130CC(CHIPS)':
 'VSS35': CDS_PINID='VSS35';
NODE_NAME     J1 83
 '@S9S_MB_2U_LIB.S9S_MB_2U(SCH_1):PAGE82_I203@PURE_QUANTA.SCONN288_ADR50017P130CC(CHIPS)':
 'VSS36': CDS_PINID='VSS36';
NODE_NAME     J1 85
 '@S9S_MB_2U_LIB.S9S_MB_2U(SCH_1):PAGE82_I203@PURE_QUANTA.SCONN288_ADR50017P130CC(CHIPS)':
 'VSS37': CDS_PINID='VSS37';
NODE_NAME     J1 88
 '@S9S_MB_2U_LIB.S9S_MB_2U(SCH_1):PAGE82_I203@PURE_QUANTA.SCONN288_ADR50017P130CC(CHIPS)':
 'VSS38': CDS_PINID='VSS38';
NODE_NAME     J1 90
 '@S9S_MB_2U_LIB.S9S_MB_2U(SCH_1):PAGE82_I203@PURE_QUANTA.SCONN288_ADR50017P130CC(CHIPS)':
 'VSS39': CDS_PINID='VSS39';
NODE_NAME     J1 92
 '@S9S_MB_2U_LIB.S9S_MB_2U(SCH_1):PAGE82_I203@PURE_QUANTA.SCONN288_ADR50017P130CC(CHIPS)':
 'VSS40': CDS_PINID='VSS40';
NODE_NAME     J1 95
 '@S9S_MB_2U_LIB.S9S_MB_2U(SCH_1):PAGE82_I203@PURE_QUANTA.SCONN288_ADR50017P130CC(CHIPS)':
 'VSS41': CDS_PINID='VSS41';
NODE_NAME     J1 97
 '@S9S_MB_2U_LIB.S9S_MB_2U(SCH_1):PAGE82_I203@PURE_QUANTA.SCONN288_ADR50017P130CC(CHIPS)':
 'VSS42': CDS_PINID='VSS42';
NODE_NAME     J1 99
 '@S9S_MB_2U_LIB.S9S_MB_2U(SCH_1):PAGE82_I203@PURE_QUANTA.SCONN288_ADR50017P130CC(CHIPS)':
 'VSS43': CDS_PINID='VSS43';
NODE_NAME     J1 101
 '@S9S_MB_2U_LIB.S9S_MB_2U(SCH_1):PAGE82_I203@PURE_QUANTA.SCONN288_ADR50017P130CC(CHIPS)':
 'VSS44': CDS_PINID='VSS44';
NODE_NAME     J1 103
 '@S9S_MB_2U_LIB.S9S_MB_2U(SCH_1):PAGE82_I203@PURE_QUANTA.SCONN288_ADR50017P130CC(CHIPS)':
 'VSS45': CDS_PINID='VSS45';
NODE_NAME     J1 106
 '@S9S_MB_2U_LIB.S9S_MB_2U(SCH_1):PAGE82_I203@PURE_QUANTA.SCONN288_ADR50017P130CC(CHIPS)':
 'VSS46': CDS_PINID='VSS46';
NODE_NAME     J1 108
 '@S9S_MB_2U_LIB.S9S_MB_2U(SCH_1):PAGE82_I203@PURE_QUANTA.SCONN288_ADR50017P130CC(CHIPS)':
 'VSS47': CDS_PINID='VSS47';
NODE_NAME     J1 110
 '@S9S_MB_2U_LIB.S9S_MB_2U(SCH_1):PAGE82_I203@PURE_QUANTA.SCONN288_ADR50017P130CC(CHIPS)':
 'VSS48': CDS_PINID='VSS48';
NODE_NAME     J1 112
 '@S9S_MB_2U_LIB.S9S_MB_2U(SCH_1):PAGE82_I203@PURE_QUANTA.SCONN288_ADR50017P130CC(CHIPS)':
 'VSS49': CDS_PINID='VSS49';
NODE_NAME     J1 114
 '@S9S_MB_2U_LIB.S9S_MB_2U(SCH_1):PAGE82_I203@PURE_QUANTA.SCONN288_ADR50017P130CC(CHIPS)':
 'VSS50': CDS_PINID='VSS50';
NODE_NAME     J1 117
 '@S9S_MB_2U_LIB.S9S_MB_2U(SCH_1):PAGE82_I203@PURE_QUANTA.SCONN288_ADR50017P130CC(CHIPS)':
 'VSS51': CDS_PINID='VSS51';
NODE_NAME     J1 119
 '@S9S_MB_2U_LIB.S9S_MB_2U(SCH_1):PAGE82_I203@PURE_QUANTA.SCONN288_ADR50017P130CC(CHIPS)':
 'VSS52': CDS_PINID='VSS52';
NODE_NAME     J1 121
 '@S9S_MB_2U_LIB.S9S_MB_2U(SCH_1):PAGE82_I203@PURE_QUANTA.SCONN288_ADR50017P130CC(CHIPS)':
 'VSS53': CDS_PINID='VSS53';
NODE_NAME     J1 123
 '@S9S_MB_2U_LIB.S9S_MB_2U(SCH_1):PAGE82_I203@PURE_QUANTA.SCONN288_ADR50017P130CC(CHIPS)':
 'VSS54': CDS_PINID='VSS54';
NODE_NAME     J1 125
 '@S9S_MB_2U_LIB.S9S_MB_2U(SCH_1):PAGE82_I203@PURE_QUANTA.SCONN288_ADR50017P130CC(CHIPS)':
 'VSS55': CDS_PINID='VSS55';
NODE_NAME     J1 128
 '@S9S_MB_2U_LIB.S9S_MB_2U(SCH_1):PAGE82_I203@PURE_QUANTA.SCONN288_ADR50017P130CC(CHIPS)':
 'VSS56': CDS_PINID='VSS56';
NODE_NAME     J1 130
 '@S9S_MB_2U_LIB.S9S_MB_2U(SCH_1):PAGE82_I203@PURE_QUANTA.SCONN288_ADR50017P130CC(CHIPS)':
 'VSS57': CDS_PINID='VSS57';
NODE_NAME     J1 132
 '@S9S_MB_2U_LIB.S9S_MB_2U(SCH_1):PAGE82_I203@PURE_QUANTA.SCONN288_ADR50017P130CC(CHIPS)':
 'VSS58': CDS_PINID='VSS58';
NODE_NAME     J1 134
 '@S9S_MB_2U_LIB.S9S_MB_2U(SCH_1):PAGE82_I203@PURE_QUANTA.SCONN288_ADR50017P130CC(CHIPS)':
 'VSS59': CDS_PINID='VSS59';
NODE_NAME     J1 136
 '@S9S_MB_2U_LIB.S9S_MB_2U(SCH_1):PAGE82_I203@PURE_QUANTA.SCONN288_ADR50017P130CC(CHIPS)':
 'VSS60': CDS_PINID='VSS60';
NODE_NAME     J1 139
 '@S9S_MB_2U_LIB.S9S_MB_2U(SCH_1):PAGE82_I203@PURE_QUANTA.SCONN288_ADR50017P130CC(CHIPS)':
 'VSS61': CDS_PINID='VSS61';
NODE_NAME     J1 141
 '@S9S_MB_2U_LIB.S9S_MB_2U(SCH_1):PAGE82_I203@PURE_QUANTA.SCONN288_ADR50017P130CC(CHIPS)':
 'VSS62': CDS_PINID='VSS62';
NODE_NAME     J1 143
 '@S9S_MB_2U_LIB.S9S_MB_2U(SCH_1):PAGE82_I203@PURE_QUANTA.SCONN288_ADR50017P130CC(CHIPS)':
 'VSS63': CDS_PINID='VSS63';
NODE_NAME     J1 151
 '@S9S_MB_2U_LIB.S9S_MB_2U(SCH_1):PAGE82_I203@PURE_QUANTA.SCONN288_ADR50017P130CC(CHIPS)':
 'VSS64': CDS_PINID='VSS64';
NODE_NAME     J1 153
 '@S9S_MB_2U_LIB.S9S_MB_2U(SCH_1):PAGE82_I203@PURE_QUANTA.SCONN288_ADR50017P130CC(CHIPS)':
 'VSS65': CDS_PINID='VSS65';
NODE_NAME     J1 155
 '@S9S_MB_2U_LIB.S9S_MB_2U(SCH_1):PAGE82_I203@PURE_QUANTA.SCONN288_ADR50017P130CC(CHIPS)':
 'VSS66': CDS_PINID='VSS66';
NODE_NAME     J1 158
 '@S9S_MB_2U_LIB.S9S_MB_2U(SCH_1):PAGE82_I203@PURE_QUANTA.SCONN288_ADR50017P130CC(CHIPS)':
 'VSS67': CDS_PINID='VSS67';
NODE_NAME     J1 160
 '@S9S_MB_2U_LIB.S9S_MB_2U(SCH_1):PAGE82_I203@PURE_QUANTA.SCONN288_ADR50017P130CC(CHIPS)':
 'VSS68': CDS_PINID='VSS68';
NODE_NAME     J1 162
 '@S9S_MB_2U_LIB.S9S_MB_2U(SCH_1):PAGE82_I203@PURE_QUANTA.SCONN288_ADR50017P130CC(CHIPS)':
 'VSS69': CDS_PINID='VSS69';
NODE_NAME     J1 164
 '@S9S_MB_2U_LIB.S9S_MB_2U(SCH_1):PAGE82_I203@PURE_QUANTA.SCONN288_ADR50017P130CC(CHIPS)':
 'VSS70': CDS_PINID='VSS70';
NODE_NAME     J1 166
 '@S9S_MB_2U_LIB.S9S_MB_2U(SCH_1):PAGE82_I203@PURE_QUANTA.SCONN288_ADR50017P130CC(CHIPS)':
 'VSS71': CDS_PINID='VSS71';
NODE_NAME     J1 169
 '@S9S_MB_2U_LIB.S9S_MB_2U(SCH_1):PAGE82_I203@PURE_QUANTA.SCONN288_ADR50017P130CC(CHIPS)':
 'VSS72': CDS_PINID='VSS72';
NODE_NAME     J1 171
 '@S9S_MB_2U_LIB.S9S_MB_2U(SCH_1):PAGE82_I203@PURE_QUANTA.SCONN288_ADR50017P130CC(CHIPS)':
 'VSS73': CDS_PINID='VSS73';
NODE_NAME     J1 173
 '@S9S_MB_2U_LIB.S9S_MB_2U(SCH_1):PAGE82_I203@PURE_QUANTA.SCONN288_ADR50017P130CC(CHIPS)':
 'VSS74': CDS_PINID='VSS74';
NODE_NAME     J1 175
 '@S9S_MB_2U_LIB.S9S_MB_2U(SCH_1):PAGE82_I203@PURE_QUANTA.SCONN288_ADR50017P130CC(CHIPS)':
 'VSS75': CDS_PINID='VSS75';
NODE_NAME     J1 177
 '@S9S_MB_2U_LIB.S9S_MB_2U(SCH_1):PAGE82_I203@PURE_QUANTA.SCONN288_ADR50017P130CC(CHIPS)':
 'VSS76': CDS_PINID='VSS76';
NODE_NAME     J1 180
 '@S9S_MB_2U_LIB.S9S_MB_2U(SCH_1):PAGE82_I203@PURE_QUANTA.SCONN288_ADR50017P130CC(CHIPS)':
 'VSS77': CDS_PINID='VSS77';
NODE_NAME     J1 182
 '@S9S_MB_2U_LIB.S9S_MB_2U(SCH_1):PAGE82_I203@PURE_QUANTA.SCONN288_ADR50017P130CC(CHIPS)':
 'VSS78': CDS_PINID='VSS78';
NODE_NAME     J1 184
 '@S9S_MB_2U_LIB.S9S_MB_2U(SCH_1):PAGE82_I203@PURE_QUANTA.SCONN288_ADR50017P130CC(CHIPS)':
 'VSS79': CDS_PINID='VSS79';
NODE_NAME     J1 186
 '@S9S_MB_2U_LIB.S9S_MB_2U(SCH_1):PAGE82_I203@PURE_QUANTA.SCONN288_ADR50017P130CC(CHIPS)':
 'VSS80': CDS_PINID='VSS80';
NODE_NAME     J1 188
 '@S9S_MB_2U_LIB.S9S_MB_2U(SCH_1):PAGE82_I203@PURE_QUANTA.SCONN288_ADR50017P130CC(CHIPS)':
 'VSS81': CDS_PINID='VSS81';
NODE_NAME     J1 191
 '@S9S_MB_2U_LIB.S9S_MB_2U(SCH_1):PAGE82_I203@PURE_QUANTA.SCONN288_ADR50017P130CC(CHIPS)':
 'VSS82': CDS_PINID='VSS82';
NODE_NAME     J1 193
 '@S9S_MB_2U_LIB.S9S_MB_2U(SCH_1):PAGE82_I203@PURE_QUANTA.SCONN288_ADR50017P130CC(CHIPS)':
 'VSS83': CDS_PINID='VSS83';
NODE_NAME     J1 195
 '@S9S_MB_2U_LIB.S9S_MB_2U(SCH_1):PAGE82_I203@PURE_QUANTA.SCONN288_ADR50017P130CC(CHIPS)':
 'VSS84': CDS_PINID='VSS84';
NODE_NAME     J1 197
 '@S9S_MB_2U_LIB.S9S_MB_2U(SCH_1):PAGE82_I203@PURE_QUANTA.SCONN288_ADR50017P130CC(CHIPS)':
 'VSS85': CDS_PINID='VSS85';
NODE_NAME     J1 199
 '@S9S_MB_2U_LIB.S9S_MB_2U(SCH_1):PAGE82_I203@PURE_QUANTA.SCONN288_ADR50017P130CC(CHIPS)':
 'VSS86': CDS_PINID='VSS86';
NODE_NAME     J1 202
 '@S9S_MB_2U_LIB.S9S_MB_2U(SCH_1):PAGE82_I203@PURE_QUANTA.SCONN288_ADR50017P130CC(CHIPS)':
 'VSS87': CDS_PINID='VSS87';
NODE_NAME     J1 204
 '@S9S_MB_2U_LIB.S9S_MB_2U(SCH_1):PAGE82_I203@PURE_QUANTA.SCONN288_ADR50017P130CC(CHIPS)':
 'VSS88': CDS_PINID='VSS88';
NODE_NAME     J1 206
 '@S9S_MB_2U_LIB.S9S_MB_2U(SCH_1):PAGE82_I203@PURE_QUANTA.SCONN288_ADR50017P130CC(CHIPS)':
 'VSS89': CDS_PINID='VSS89';
NODE_NAME     J1 208
 '@S9S_MB_2U_LIB.S9S_MB_2U(SCH_1):PAGE82_I203@PURE_QUANTA.SCONN288_ADR50017P130CC(CHIPS)':
 'VSS90': CDS_PINID='VSS90';
NODE_NAME     J1 210
 '@S9S_MB_2U_LIB.S9S_MB_2U(SCH_1):PAGE82_I203@PURE_QUANTA.SCONN288_ADR50017P130CC(CHIPS)':
 'VSS91': CDS_PINID='VSS91';
NODE_NAME     J1 212
 '@S9S_MB_2U_LIB.S9S_MB_2U(SCH_1):PAGE82_I203@PURE_QUANTA.SCONN288_ADR50017P130CC(CHIPS)':
 'VSS92': CDS_PINID='VSS92';
NODE_NAME     J1 214
 '@S9S_MB_2U_LIB.S9S_MB_2U(SCH_1):PAGE82_I203@PURE_QUANTA.SCONN288_ADR50017P130CC(CHIPS)':
 'VSS93': CDS_PINID='VSS93';
NODE_NAME     J1 216
 '@S9S_MB_2U_LIB.S9S_MB_2U(SCH_1):PAGE82_I203@PURE_QUANTA.SCONN288_ADR50017P130CC(CHIPS)':
 'VSS94': CDS_PINID='VSS94';
NODE_NAME     J1 219
 '@S9S_MB_2U_LIB.S9S_MB_2U(SCH_1):PAGE82_I203@PURE_QUANTA.SCONN288_ADR50017P130CC(CHIPS)':
 'VSS95': CDS_PINID='VSS95';
NODE_NAME     J1 222
 '@S9S_MB_2U_LIB.S9S_MB_2U(SCH_1):PAGE82_I203@PURE_QUANTA.SCONN288_ADR50017P130CC(CHIPS)':
 'VSS96': CDS_PINID='VSS96';
NODE_NAME     J1 224
 '@S9S_MB_2U_LIB.S9S_MB_2U(SCH_1):PAGE82_I203@PURE_QUANTA.SCONN288_ADR50017P130CC(CHIPS)':
 'VSS97': CDS_PINID='VSS97';
NODE_NAME     J1 226
 '@S9S_MB_2U_LIB.S9S_MB_2U(SCH_1):PAGE82_I203@PURE_QUANTA.SCONN288_ADR50017P130CC(CHIPS)':
 'VSS98': CDS_PINID='VSS98';
NODE_NAME     J1 228
 '@S9S_MB_2U_LIB.S9S_MB_2U(SCH_1):PAGE82_I203@PURE_QUANTA.SCONN288_ADR50017P130CC(CHIPS)':
 'VSS99': CDS_PINID='VSS99';
NODE_NAME     J1 230
 '@S9S_MB_2U_LIB.S9S_MB_2U(SCH_1):PAGE82_I203@PURE_QUANTA.SCONN288_ADR50017P130CC(CHIPS)':
 'VSS100': CDS_PINID='VSS100';
NODE_NAME     J1 233
 '@S9S_MB_2U_LIB.S9S_MB_2U(SCH_1):PAGE82_I203@PURE_QUANTA.SCONN288_ADR50017P130CC(CHIPS)':
 'VSS101': CDS_PINID='VSS101';
NODE_NAME     J1 235
 '@S9S_MB_2U_LIB.S9S_MB_2U(SCH_1):PAGE82_I203@PURE_QUANTA.SCONN288_ADR50017P130CC(CHIPS)':
 'VSS102': CDS_PINID='VSS102';
NODE_NAME     J1 237
 '@S9S_MB_2U_LIB.S9S_MB_2U(SCH_1):PAGE82_I203@PURE_QUANTA.SCONN288_ADR50017P130CC(CHIPS)':
 'VSS103': CDS_PINID='VSS103';
NODE_NAME     J1 240
 '@S9S_MB_2U_LIB.S9S_MB_2U(SCH_1):PAGE82_I203@PURE_QUANTA.SCONN288_ADR50017P130CC(CHIPS)':
 'VSS104': CDS_PINID='VSS104';
NODE_NAME     J1 242
 '@S9S_MB_2U_LIB.S9S_MB_2U(SCH_1):PAGE82_I203@PURE_QUANTA.SCONN288_ADR50017P130CC(CHIPS)':
 'VSS105': CDS_PINID='VSS105';
NODE_NAME     J1 244
 '@S9S_MB_2U_LIB.S9S_MB_2U(SCH_1):PAGE82_I203@PURE_QUANTA.SCONN288_ADR50017P130CC(CHIPS)':
 'VSS106': CDS_PINID='VSS106';
NODE_NAME     J1 246
 '@S9S_MB_2U_LIB.S9S_MB_2U(SCH_1):PAGE82_I203@PURE_QUANTA.SCONN288_ADR50017P130CC(CHIPS)':
 'VSS107': CDS_PINID='VSS107';
NODE_NAME     J1 248
 '@S9S_MB_2U_LIB.S9S_MB_2U(SCH_1):PAGE82_I203@PURE_QUANTA.SCONN288_ADR50017P130CC(CHIPS)':
 'VSS108': CDS_PINID='VSS108';
NODE_NAME     J1 251
 '@S9S_MB_2U_LIB.S9S_MB_2U(SCH_1):PAGE82_I203@PURE_QUANTA.SCONN288_ADR50017P130CC(CHIPS)':
 'VSS109': CDS_PINID='VSS109';
NODE_NAME     J1 253
 '@S9S_MB_2U_LIB.S9S_MB_2U(SCH_1):PAGE82_I203@PURE_QUANTA.SCONN288_ADR50017P130CC(CHIPS)':
 'VSS110': CDS_PINID='VSS110';
NODE_NAME     J1 255
 '@S9S_MB_2U_LIB.S9S_MB_2U(SCH_1):PAGE82_I203@PURE_QUANTA.SCONN288_ADR50017P130CC(CHIPS)':
 'VSS111': CDS_PINID='VSS111';
NODE_NAME     J1 257
 '@S9S_MB_2U_LIB.S9S_MB_2U(SCH_1):PAGE82_I203@PURE_QUANTA.SCONN288_ADR50017P130CC(CHIPS)':
 'VSS112': CDS_PINID='VSS112';
NODE_NAME     J1 259
 '@S9S_MB_2U_LIB.S9S_MB_2U(SCH_1):PAGE82_I203@PURE_QUANTA.SCONN288_ADR50017P130CC(CHIPS)':
 'VSS113': CDS_PINID='VSS113';
NODE_NAME     J1 262
 '@S9S_MB_2U_LIB.S9S_MB_2U(SCH_1):PAGE82_I203@PURE_QUANTA.SCONN288_ADR50017P130CC(CHIPS)':
 'VSS114': CDS_PINID='VSS114';
NODE_NAME     J1 264
 '@S9S_MB_2U_LIB.S9S_MB_2U(SCH_1):PAGE82_I203@PURE_QUANTA.SCONN288_ADR50017P130CC(CHIPS)':
 'VSS115': CDS_PINID='VSS115';
NODE_NAME     J1 266
 '@S9S_MB_2U_LIB.S9S_MB_2U(SCH_1):PAGE82_I203@PURE_QUANTA.SCONN288_ADR50017P130CC(CHIPS)':
 'VSS116': CDS_PINID='VSS116';
NODE_NAME     J1 268
 '@S9S_MB_2U_LIB.S9S_MB_2U(SCH_1):PAGE82_I203@PURE_QUANTA.SCONN288_ADR50017P130CC(CHIPS)':
 'VSS117': CDS_PINID='VSS117';
NODE_NAME     J1 270
 '@S9S_MB_2U_LIB.S9S_MB_2U(SCH_1):PAGE82_I203@PURE_QUANTA.SCONN288_ADR50017P130CC(CHIPS)':
 'VSS118': CDS_PINID='VSS118';
NODE_NAME     J1 273
 '@S9S_MB_2U_LIB.S9S_MB_2U(SCH_1):PAGE82_I203@PURE_QUANTA.SCONN288_ADR50017P130CC(CHIPS)':
 'VSS119': CDS_PINID='VSS119';
NODE_NAME     J1 275
 '@S9S_MB_2U_LIB.S9S_MB_2U(SCH_1):PAGE82_I203@PURE_QUANTA.SCONN288_ADR50017P130CC(CHIPS)':
 'VSS120': CDS_PINID='VSS120';
NODE_NAME     J1 277
 '@S9S_MB_2U_LIB.S9S_MB_2U(SCH_1):PAGE82_I203@PURE_QUANTA.SCONN288_ADR50017P130CC(CHIPS)':
 'VSS121': CDS_PINID='VSS121';
NODE_NAME     J1 279
 '@S9S_MB_2U_LIB.S9S_MB_2U(SCH_1):PAGE82_I203@PURE_QUANTA.SCONN288_ADR50017P130CC(CHIPS)':
 'VSS122': CDS_PINID='VSS122';
NODE_NAME     J1 281
 '@S9S_MB_2U_LIB.S9S_MB_2U(SCH_1):PAGE82_I203@PURE_QUANTA.SCONN288_ADR50017P130CC(CHIPS)':
 'VSS123': CDS_PINID='VSS123';
NODE_NAME     J1 284
 '@S9S_MB_2U_LIB.S9S_MB_2U(SCH_1):PAGE82_I203@PURE_QUANTA.SCONN288_ADR50017P130CC(CHIPS)':
 'VSS124': CDS_PINID='VSS124';
NODE_NAME     J1 286
 '@S9S_MB_2U_LIB.S9S_MB_2U(SCH_1):PAGE82_I203@PURE_QUANTA.SCONN288_ADR50017P130CC(CHIPS)':
 'VSS125': CDS_PINID='VSS125';
NODE_NAME     J1 288
 '@S9S_MB_2U_LIB.S9S_MB_2U(SCH_1):PAGE82_I203@PURE_QUANTA.SCONN288_ADR50017P130CC(CHIPS)':
 'VSS126': CDS_PINID='VSS126';
NODE_NAME     C579 2
 '@S9S_MB_2U_LIB.S9S_MB_2U(SCH_1):PAGE154_I192@PURE_QUANTA.Q_CAP(CHIPS)':
 'B': CDS_PINID='B';
NODE_NAME     U143 10
 '@S9S_MB_2U_LIB.S9S_MB_2U(SCH_1):PAGE224_I106@PURE_QUANTA.PCA9545APW(CHIPS)':
 'VSS': CDS_PINID='VSS';
NODE_NAME     C1809 2
 '@S9S_MB_2U_LIB.S9S_MB_2U(SCH_1):PAGE131_I26@PURE_QUANTA.Q_CAP(CHIPS)':
 'B': CDS_PINID='B';
NODE_NAME     Q119 1
 '@S9S_MB_2U_LIB.S9S_MB_2U(SCH_1):PAGE131_I38@PURE_QUANTA.MOSFET_NCH_DUAL(CHIPS)':
 'S1': CDS_PINID='S1';
NODE_NAME     U50 3
 '@S9S_MB_2U_LIB.S9S_MB_2U(SCH_1):PAGE132_I9@PURE_QUANTA.74LVC1G08W57(CHIPS)':
 'GND': CDS_PINID='GND';
NODE_NAME     C1818 2
 '@S9S_MB_2U_LIB.S9S_MB_2U(SCH_1):PAGE132_I15@PURE_QUANTA.Q_CAP(CHIPS)':
 'B': CDS_PINID='B';
NODE_NAME     U53 3
 '@S9S_MB_2U_LIB.S9S_MB_2U(SCH_1):PAGE132_I56@PURE_QUANTA.74LVC1G08W57(CHIPS)':
 'GND': CDS_PINID='GND';
NODE_NAME     R3154 2
 '@S9S_MB_2U_LIB.S9S_MB_2U(SCH_1):PAGE132_I65@PURE_QUANTA.Q_RES(CHIPS)':
 'B': CDS_PINID='B';
NODE_NAME     U215 S
 '@S9S_MB_2U_LIB.S9S_MB_2U(SCH_1):PAGE132_I3@PURE_QUANTA.MOSFET_N(CHIPS)':
 'SOURCE': CDS_PINID='SOURCE';
NODE_NAME     R3150 2
 '@S9S_MB_2U_LIB.S9S_MB_2U(SCH_1):PAGE132_I25@PURE_QUANTA.Q_RES(CHIPS)':
 'B': CDS_PINID='B';
NODE_NAME     R3152 2
 '@S9S_MB_2U_LIB.S9S_MB_2U(SCH_1):PAGE132_I27@PURE_QUANTA.Q_RES(CHIPS)':
 'B': CDS_PINID='B';
NODE_NAME     C1817 2
 '@S9S_MB_2U_LIB.S9S_MB_2U(SCH_1):PAGE132_I39@PURE_QUANTA.Q_CAP(CHIPS)':
 'B': CDS_PINID='B';
NODE_NAME     C1820 2
 '@S9S_MB_2U_LIB.S9S_MB_2U(SCH_1):PAGE132_I58@PURE_QUANTA.Q_CAP(CHIPS)':
 'B': CDS_PINID='B';
NODE_NAME     R3167 2
 '@S9S_MB_2U_LIB.S9S_MB_2U(SCH_1):PAGE146_I20@PURE_QUANTA.Q_RES(CHIPS)':
 'B': CDS_PINID='B';
NODE_NAME     R3163 2
 '@S9S_MB_2U_LIB.S9S_MB_2U(SCH_1):PAGE146_I25@PURE_QUANTA.Q_RES(CHIPS)':
 'B': CDS_PINID='B';
NODE_NAME     C1821 2
 '@S9S_MB_2U_LIB.S9S_MB_2U(SCH_1):PAGE156_I12@PURE_QUANTA.Q_CAP(CHIPS)':
 'B': CDS_PINID='B';
NODE_NAME     C1822 2
 '@S9S_MB_2U_LIB.S9S_MB_2U(SCH_1):PAGE156_I27@PURE_QUANTA.Q_CAP(CHIPS)':
 'B': CDS_PINID='B';
NODE_NAME     U218 3
 '@S9S_MB_2U_LIB.S9S_MB_2U(SCH_1):PAGE156_I31@PURE_QUANTA.74LVC1G07GV(CHIPS)':
 'GND': CDS_PINID='GND';
NODE_NAME     C1823 2
 '@S9S_MB_2U_LIB.S9S_MB_2U(SCH_1):PAGE156_I33@PURE_QUANTA.Q_CAP(CHIPS)':
 'B': CDS_PINID='B';
NODE_NAME     U207 3
 '@S9S_MB_2U_LIB.S9S_MB_2U(SCH_1):PAGE156_I35@PURE_QUANTA.74LVC1G17GW(CHIPS)':
 'GND': CDS_PINID='GND';
NODE_NAME     C1824 2
 '@S9S_MB_2U_LIB.S9S_MB_2U(SCH_1):PAGE156_I47@PURE_QUANTA.Q_CAP(CHIPS)':
 'B': CDS_PINID='B';
NODE_NAME     U219 3
 '@S9S_MB_2U_LIB.S9S_MB_2U(SCH_1):PAGE156_I61@PURE_QUANTA.74LVC1G07GV(CHIPS)':
 'GND': CDS_PINID='GND';
NODE_NAME     R3207 2
 '@S9S_MB_2U_LIB.S9S_MB_2U(SCH_1):PAGE307_I15@PURE_QUANTA.Q_RES(CHIPS)':
 'B': CDS_PINID='B';
NODE_NAME     C1825 2
 '@S9S_MB_2U_LIB.S9S_MB_2U(SCH_1):PAGE307_I17@PURE_QUANTA.Q_CAP(CHIPS)':
 'B': CDS_PINID='B';
NODE_NAME     U222 7
 '@S9S_MB_2U_LIB.S9S_MB_2U(SCH_1):PAGE307_I32@PURE_QUANTA.74CBTLV3126PW(CHIPS)':
 'GND': CDS_PINID='GND';
NODE_NAME     C1826 2
 '@S9S_MB_2U_LIB.S9S_MB_2U(SCH_1):PAGE307_I33@PURE_QUANTA.Q_CAP(CHIPS)':
 'B': CDS_PINID='B';
NODE_NAME     R3208 2
 '@S9S_MB_2U_LIB.S9S_MB_2U(SCH_1):PAGE307_I37@PURE_QUANTA.Q_RES(CHIPS)':
 'B': CDS_PINID='B';
NODE_NAME     R3216 2
 '@S9S_MB_2U_LIB.S9S_MB_2U(SCH_1):PAGE307_I38@PURE_QUANTA.Q_RES(CHIPS)':
 'B': CDS_PINID='B';
NODE_NAME     R3217 2
 '@S9S_MB_2U_LIB.S9S_MB_2U(SCH_1):PAGE307_I40@PURE_QUANTA.Q_RES(CHIPS)':
 'B': CDS_PINID='B';
NODE_NAME     C1827 2
 '@S9S_MB_2U_LIB.S9S_MB_2U(SCH_1):PAGE307_I77@PURE_QUANTA.Q_CAP(CHIPS)':
 'B': CDS_PINID='B';
NODE_NAME     U223 7
 '@S9S_MB_2U_LIB.S9S_MB_2U(SCH_1):PAGE307_I78@PURE_QUANTA.74CBTLV3126PW(CHIPS)':
 'GND': CDS_PINID='GND';
NODE_NAME     R3165 1
 '@S9S_MB_2U_LIB.S9S_MB_2U(SCH_1):PAGE146_I37@PURE_QUANTA.Q_RES(CHIPS)':
 'A': CDS_PINID='A';
NODE_NAME     R3164 1
 '@S9S_MB_2U_LIB.S9S_MB_2U(SCH_1):PAGE146_I38@PURE_QUANTA.Q_RES(CHIPS)':
 'A': CDS_PINID='A';
NODE_NAME     R413 1
 '@S9S_MB_2U_LIB.S9S_MB_2U(SCH_1):PAGE146_I43@PURE_QUANTA.Q_RES(CHIPS)':
 'A': CDS_PINID='A';
NODE_NAME     R3180 2
 '@S9S_MB_2U_LIB.S9S_MB_2U(SCH_1):PAGE146_I152@PURE_QUANTA.Q_RES(CHIPS)':
 'B': CDS_PINID='B';
NODE_NAME     C1829 2
 '@S9S_MB_2U_LIB.S9S_MB_2U(SCH_1):PAGE146_I166@PURE_QUANTA.Q_CAP(CHIPS)':
 'B': CDS_PINID='B';
NODE_NAME     C1830 2
 '@S9S_MB_2U_LIB.S9S_MB_2U(SCH_1):PAGE146_I167@PURE_QUANTA.Q_CAP(CHIPS)':
 'B': CDS_PINID='B';
NODE_NAME     C1831 2
 '@S9S_MB_2U_LIB.S9S_MB_2U(SCH_1):PAGE146_I168@PURE_QUANTA.Q_CAP(CHIPS)':
 'B': CDS_PINID='B';
NODE_NAME     C1833 2
 '@S9S_MB_2U_LIB.S9S_MB_2U(SCH_1):PAGE146_I169@PURE_QUANTA.Q_CAP(CHIPS)':
 'B': CDS_PINID='B';
NODE_NAME     C1834 2
 '@S9S_MB_2U_LIB.S9S_MB_2U(SCH_1):PAGE146_I171@PURE_QUANTA.Q_CAP(CHIPS)':
 'B': CDS_PINID='B';
NODE_NAME     C1835 2
 '@S9S_MB_2U_LIB.S9S_MB_2U(SCH_1):PAGE146_I173@PURE_QUANTA.Q_CAP(CHIPS)':
 'B': CDS_PINID='B';
NODE_NAME     C1836 2
 '@S9S_MB_2U_LIB.S9S_MB_2U(SCH_1):PAGE146_I174@PURE_QUANTA.Q_CAP(CHIPS)':
 'B': CDS_PINID='B';
NODE_NAME     C1837 2
 '@S9S_MB_2U_LIB.S9S_MB_2U(SCH_1):PAGE146_I175@PURE_QUANTA.Q_CAP(CHIPS)':
 'B': CDS_PINID='B';
NODE_NAME     C1838 2
 '@S9S_MB_2U_LIB.S9S_MB_2U(SCH_1):PAGE146_I177@PURE_QUANTA.Q_CAP(CHIPS)':
 'B': CDS_PINID='B';
NODE_NAME     C1832 2
 '@S9S_MB_2U_LIB.S9S_MB_2U(SCH_1):PAGE146_I179@PURE_QUANTA.Q_CAP(CHIPS)':
 'B': CDS_PINID='B';
NODE_NAME     C1839 2
 '@S9S_MB_2U_LIB.S9S_MB_2U(SCH_1):PAGE146_I180@PURE_QUANTA.Q_CAP(CHIPS)':
 'B': CDS_PINID='B';
NODE_NAME     C1841 2
 '@S9S_MB_2U_LIB.S9S_MB_2U(SCH_1):PAGE156_I65@PURE_QUANTA.Q_CAP(CHIPS)':
 'B': CDS_PINID='B';
NODE_NAME     R3235 2
 '@S9S_MB_2U_LIB.S9S_MB_2U(SCH_1):PAGE156_I72@PURE_QUANTA.Q_RES(CHIPS)':
 'B': CDS_PINID='B';
NODE_NAME     J43 7
 '@S9S_MB_2U_LIB.S9S_MB_2U(SCH_1):PAGE210_I79@PURE_QUANTA.CONN8_210HP1080BR1(CHIPS)':
 '7': CDS_PINID='\7\';
NODE_NAME     C554 2
 '@S9S_MB_2U_LIB.S9S_MB_2U(SCH_1):PAGE210_I86@PURE_QUANTA.Q_CAP(CHIPS)':
 'B': CDS_PINID='B';
NODE_NAME     C563 2
 '@S9S_MB_2U_LIB.S9S_MB_2U(SCH_1):PAGE210_I88@PURE_QUANTA.Q_CAP(CHIPS)':
 'B': CDS_PINID='B';
NODE_NAME     U235 4
 '@S9S_MB_2U_LIB.S9S_MB_2U(SCH_1):PAGE216_I5@PURE_QUANTA.PCA9617ADP(CHIPS)':
 'GND': CDS_PINID='GND';
NODE_NAME     C1859 2
 '@S9S_MB_2U_LIB.S9S_MB_2U(SCH_1):PAGE216_I10@PURE_QUANTA.Q_CAP(CHIPS)':
 'B': CDS_PINID='B';
NODE_NAME     C1861 2
 '@S9S_MB_2U_LIB.S9S_MB_2U(SCH_1):PAGE216_I11@PURE_QUANTA.Q_CAP(CHIPS)':
 'B': CDS_PINID='B';
NODE_NAME     C1860 2
 '@S9S_MB_2U_LIB.S9S_MB_2U(SCH_1):PAGE216_I17@PURE_QUANTA.Q_CAP(CHIPS)':
 'B': CDS_PINID='B';
NODE_NAME     C1862 2
 '@S9S_MB_2U_LIB.S9S_MB_2U(SCH_1):PAGE216_I23@PURE_QUANTA.Q_CAP(CHIPS)':
 'B': CDS_PINID='B';
NODE_NAME     U236 4
 '@S9S_MB_2U_LIB.S9S_MB_2U(SCH_1):PAGE216_I28@PURE_QUANTA.PCA9617ADP(CHIPS)':
 'GND': CDS_PINID='GND';
NODE_NAME     R3279 2
 '@S9S_MB_2U_LIB.S9S_MB_2U(SCH_1):PAGE136_I23@PURE_QUANTA.Q_RES(CHIPS)':
 'B': CDS_PINID='B';
NODE_NAME     R3281 2
 '@S9S_MB_2U_LIB.S9S_MB_2U(SCH_1):PAGE136_I25@PURE_QUANTA.Q_RES(CHIPS)':
 'B': CDS_PINID='B';
NODE_NAME     C1867 2
 '@S9S_MB_2U_LIB.S9S_MB_2U(SCH_1):PAGE136_I48@PURE_QUANTA.Q_CAP(CHIPS)':
 'B': CDS_PINID='B';
NODE_NAME     R3290 2
 '@S9S_MB_2U_LIB.S9S_MB_2U(SCH_1):PAGE136_I68@PURE_QUANTA.Q_RES(CHIPS)':
 'B': CDS_PINID='B';
NODE_NAME     R3293 2
 '@S9S_MB_2U_LIB.S9S_MB_2U(SCH_1):PAGE136_I88@PURE_QUANTA.Q_RES(CHIPS)':
 'B': CDS_PINID='B';
NODE_NAME     U241 4
 '@S9S_MB_2U_LIB.S9S_MB_2U(SCH_1):PAGE170_I1@PURE_QUANTA.74LVC2G08DP(CHIPS)':
 'GND': CDS_PINID='GND';
NODE_NAME     U240 4
 '@S9S_MB_2U_LIB.S9S_MB_2U(SCH_1):PAGE170_I11@PURE_QUANTA.74LVC2G08DP(CHIPS)':
 'GND': CDS_PINID='GND';
NODE_NAME     U242 4
 '@S9S_MB_2U_LIB.S9S_MB_2U(SCH_1):PAGE170_I13@PURE_QUANTA.74LVC2G08DP(CHIPS)':
 'GND': CDS_PINID='GND';
NODE_NAME     U243 2
 '@S9S_MB_2U_LIB.S9S_MB_2U(SCH_1):PAGE170_I15@PURE_QUANTA.NC7SB3157(CHIPS)':
 'GND': CDS_PINID='GND';
NODE_NAME     U244 2
 '@S9S_MB_2U_LIB.S9S_MB_2U(SCH_1):PAGE170_I16@PURE_QUANTA.NC7SB3157(CHIPS)':
 'GND': CDS_PINID='GND';
NODE_NAME     U246 2
 '@S9S_MB_2U_LIB.S9S_MB_2U(SCH_1):PAGE170_I17@PURE_QUANTA.NC7SB3157(CHIPS)':
 'GND': CDS_PINID='GND';
NODE_NAME     U245 2
 '@S9S_MB_2U_LIB.S9S_MB_2U(SCH_1):PAGE170_I18@PURE_QUANTA.NC7SB3157(CHIPS)':
 'GND': CDS_PINID='GND';
NODE_NAME     C1875 2
 '@S9S_MB_2U_LIB.S9S_MB_2U(SCH_1):PAGE170_I21@PURE_QUANTA.Q_CAP(CHIPS)':
 'B': CDS_PINID='B';
NODE_NAME     C1874 2
 '@S9S_MB_2U_LIB.S9S_MB_2U(SCH_1):PAGE170_I22@PURE_QUANTA.Q_CAP(CHIPS)':
 'B': CDS_PINID='B';
NODE_NAME     C1880 2
 '@S9S_MB_2U_LIB.S9S_MB_2U(SCH_1):PAGE170_I27@PURE_QUANTA.Q_CAP(CHIPS)':
 'B': CDS_PINID='B';
NODE_NAME     C1879 2
 '@S9S_MB_2U_LIB.S9S_MB_2U(SCH_1):PAGE170_I31@PURE_QUANTA.Q_CAP(CHIPS)':
 'B': CDS_PINID='B';
NODE_NAME     C1877 2
 '@S9S_MB_2U_LIB.S9S_MB_2U(SCH_1):PAGE170_I34@PURE_QUANTA.Q_CAP(CHIPS)':
 'B': CDS_PINID='B';
NODE_NAME     C1878 2
 '@S9S_MB_2U_LIB.S9S_MB_2U(SCH_1):PAGE170_I37@PURE_QUANTA.Q_CAP(CHIPS)':
 'B': CDS_PINID='B';
NODE_NAME     C1876 2
 '@S9S_MB_2U_LIB.S9S_MB_2U(SCH_1):PAGE170_I41@PURE_QUANTA.Q_CAP(CHIPS)':
 'B': CDS_PINID='B';
NODE_NAME     R1324 1
 '@S9S_MB_2U_LIB.S9S_MB_2U(SCH_1):PAGE189_I87@PURE_QUANTA.Q_RES(CHIPS)':
 'A': CDS_PINID='A';
NODE_NAME     R1341 2
 '@S9S_MB_2U_LIB.S9S_MB_2U(SCH_1):PAGE189_I106@PURE_QUANTA.Q_RES(CHIPS)':
 'B': CDS_PINID='B';
NODE_NAME     R1338 2
 '@S9S_MB_2U_LIB.S9S_MB_2U(SCH_1):PAGE189_I107@PURE_QUANTA.Q_RES(CHIPS)':
 'B': CDS_PINID='B';
NODE_NAME     R2134 2
 '@S9S_MB_2U_LIB.S9S_MB_2U(SCH_1):PAGE189_I109@PURE_QUANTA.Q_RES(CHIPS)':
 'B': CDS_PINID='B';
NODE_NAME     R1333 1
 '@S9S_MB_2U_LIB.S9S_MB_2U(SCH_1):PAGE189_I123@PURE_QUANTA.Q_RES(CHIPS)':
 'A': CDS_PINID='A';
NODE_NAME     C1177 2
 '@S9S_MB_2U_LIB.S9S_MB_2U(SCH_1):PAGE189_I128@PURE_QUANTA.Q_CAP(CHIPS)':
 'B': CDS_PINID='B';
NODE_NAME     R3039 1
 '@S9S_MB_2U_LIB.S9S_MB_2U(SCH_1):PAGE189_I132@PURE_QUANTA.Q_RES(CHIPS)':
 'A': CDS_PINID='A';
NODE_NAME     R1335 1
 '@S9S_MB_2U_LIB.S9S_MB_2U(SCH_1):PAGE189_I133@PURE_QUANTA.Q_RES(CHIPS)':
 'A': CDS_PINID='A';
NODE_NAME     Q98 1
 '@S9S_MB_2U_LIB.S9S_MB_2U(SCH_1):PAGE304_I68@PURE_QUANTA.MOSFET_NCH_DUAL(CHIPS)':
 'S1': CDS_PINID='S1';
NODE_NAME     Q98 4
 '@S9S_MB_2U_LIB.S9S_MB_2U(SCH_1):PAGE304_I69@PURE_QUANTA.MOSFET_NCH_DUAL(CHIPS)':
 'S2': CDS_PINID='S2';
NODE_NAME     Q97 4
 '@S9S_MB_2U_LIB.S9S_MB_2U(SCH_1):PAGE304_I70@PURE_QUANTA.MOSFET_NCH_DUAL(CHIPS)':
 'S2': CDS_PINID='S2';
NODE_NAME     Q97 1
 '@S9S_MB_2U_LIB.S9S_MB_2U(SCH_1):PAGE304_I71@PURE_QUANTA.MOSFET_NCH_DUAL(CHIPS)':
 'S1': CDS_PINID='S1';
NODE_NAME     Q99 1
 '@S9S_MB_2U_LIB.S9S_MB_2U(SCH_1):PAGE304_I72@PURE_QUANTA.MOSFET_NCH_DUAL(CHIPS)':
 'S1': CDS_PINID='S1';
NODE_NAME     Q100 1
 '@S9S_MB_2U_LIB.S9S_MB_2U(SCH_1):PAGE304_I74@PURE_QUANTA.MOSFET_NCH_DUAL(CHIPS)':
 'S1': CDS_PINID='S1';
NODE_NAME     Q100 4
 '@S9S_MB_2U_LIB.S9S_MB_2U(SCH_1):PAGE304_I75@PURE_QUANTA.MOSFET_NCH_DUAL(CHIPS)':
 'S2': CDS_PINID='S2';
NODE_NAME     R3325 2
 '@S9S_MB_2U_LIB.S9S_MB_2U(SCH_1):PAGE186_I92@PURE_QUANTA.Q_RES(CHIPS)':
 'B': CDS_PINID='B';
NODE_NAME     C1883 2
 '@S9S_MB_2U_LIB.S9S_MB_2U(SCH_1):PAGE201_I16@PURE_QUANTA.Q_CAP(CHIPS)':
 'B': CDS_PINID='B';
NODE_NAME     C1886 2
 '@S9S_MB_2U_LIB.S9S_MB_2U(SCH_1):PAGE201_I18@PURE_QUANTA.Q_CAP(CHIPS)':
 'B': CDS_PINID='B';
NODE_NAME     C1889 2
 '@S9S_MB_2U_LIB.S9S_MB_2U(SCH_1):PAGE201_I19@PURE_QUANTA.Q_CAP(CHIPS)':
 'B': CDS_PINID='B';
NODE_NAME     Q96 1
 '@S9S_MB_2U_LIB.S9S_MB_2U(SCH_1):PAGE145_I154@PURE_QUANTA.MOSFET_NCH_DUAL(CHIPS)':
 'S1': CDS_PINID='S1';
NODE_NAME     C1881 2
 '@S9S_MB_2U_LIB.S9S_MB_2U(SCH_1):PAGE145_I156@PURE_QUANTA.Q_CAP(CHIPS)':
 'B': CDS_PINID='B';
NODE_NAME     C1803 2
 '@S9S_MB_2U_LIB.S9S_MB_2U(SCH_1):PAGE140_I166@PURE_QUANTA.Q_CAP(CHIPS)':
 'B': CDS_PINID='B';
NODE_NAME     J107 A6
 '@S9S_MB_2U_LIB.S9S_MB_2U(SCH_1):PAGE317_I38@PURE_QUANTA.CONN112_10137002101LF(CHIPS)':
 'A6': CDS_PINID='A6';
NODE_NAME     J107 A8
 '@S9S_MB_2U_LIB.S9S_MB_2U(SCH_1):PAGE317_I38@PURE_QUANTA.CONN112_10137002101LF(CHIPS)':
 'A8': CDS_PINID='A8';
NODE_NAME     J107 B5
 '@S9S_MB_2U_LIB.S9S_MB_2U(SCH_1):PAGE317_I38@PURE_QUANTA.CONN112_10137002101LF(CHIPS)':
 'B5': CDS_PINID='B5';
NODE_NAME     J107 B7
 '@S9S_MB_2U_LIB.S9S_MB_2U(SCH_1):PAGE317_I38@PURE_QUANTA.CONN112_10137002101LF(CHIPS)':
 'B7': CDS_PINID='B7';
NODE_NAME     J107 D6
 '@S9S_MB_2U_LIB.S9S_MB_2U(SCH_1):PAGE317_I38@PURE_QUANTA.CONN112_10137002101LF(CHIPS)':
 'D6': CDS_PINID='D6';
NODE_NAME     J107 D8
 '@S9S_MB_2U_LIB.S9S_MB_2U(SCH_1):PAGE317_I38@PURE_QUANTA.CONN112_10137002101LF(CHIPS)':
 'D8': CDS_PINID='D8';
NODE_NAME     J107 E5
 '@S9S_MB_2U_LIB.S9S_MB_2U(SCH_1):PAGE317_I38@PURE_QUANTA.CONN112_10137002101LF(CHIPS)':
 'E5': CDS_PINID='E5';
NODE_NAME     J107 E7
 '@S9S_MB_2U_LIB.S9S_MB_2U(SCH_1):PAGE317_I38@PURE_QUANTA.CONN112_10137002101LF(CHIPS)':
 'E7': CDS_PINID='E7';
NODE_NAME     J107 G6
 '@S9S_MB_2U_LIB.S9S_MB_2U(SCH_1):PAGE317_I38@PURE_QUANTA.CONN112_10137002101LF(CHIPS)':
 'G6': CDS_PINID='G6';
NODE_NAME     J107 G8
 '@S9S_MB_2U_LIB.S9S_MB_2U(SCH_1):PAGE317_I38@PURE_QUANTA.CONN112_10137002101LF(CHIPS)':
 'G8': CDS_PINID='G8';
NODE_NAME     J107 H5
 '@S9S_MB_2U_LIB.S9S_MB_2U(SCH_1):PAGE317_I38@PURE_QUANTA.CONN112_10137002101LF(CHIPS)':
 'H5': CDS_PINID='H5';
NODE_NAME     J107 H7
 '@S9S_MB_2U_LIB.S9S_MB_2U(SCH_1):PAGE317_I38@PURE_QUANTA.CONN112_10137002101LF(CHIPS)':
 'H7': CDS_PINID='H7';
NODE_NAME     J107 J6
 '@S9S_MB_2U_LIB.S9S_MB_2U(SCH_1):PAGE317_I38@PURE_QUANTA.CONN112_10137002101LF(CHIPS)':
 'J6': CDS_PINID='J6';
NODE_NAME     J107 J8
 '@S9S_MB_2U_LIB.S9S_MB_2U(SCH_1):PAGE317_I38@PURE_QUANTA.CONN112_10137002101LF(CHIPS)':
 'J8': CDS_PINID='J8';
NODE_NAME     J107 K5
 '@S9S_MB_2U_LIB.S9S_MB_2U(SCH_1):PAGE317_I38@PURE_QUANTA.CONN112_10137002101LF(CHIPS)':
 'K5': CDS_PINID='K5';
NODE_NAME     J107 K7
 '@S9S_MB_2U_LIB.S9S_MB_2U(SCH_1):PAGE317_I38@PURE_QUANTA.CONN112_10137002101LF(CHIPS)':
 'K7': CDS_PINID='K7';
NODE_NAME     J107 M6
 '@S9S_MB_2U_LIB.S9S_MB_2U(SCH_1):PAGE317_I38@PURE_QUANTA.CONN112_10137002101LF(CHIPS)':
 'M6': CDS_PINID='M6';
NODE_NAME     J107 M8
 '@S9S_MB_2U_LIB.S9S_MB_2U(SCH_1):PAGE317_I38@PURE_QUANTA.CONN112_10137002101LF(CHIPS)':
 'M8': CDS_PINID='M8';
NODE_NAME     J107 N5
 '@S9S_MB_2U_LIB.S9S_MB_2U(SCH_1):PAGE317_I38@PURE_QUANTA.CONN112_10137002101LF(CHIPS)':
 'N5': CDS_PINID='N5';
NODE_NAME     J107 N7
 '@S9S_MB_2U_LIB.S9S_MB_2U(SCH_1):PAGE317_I38@PURE_QUANTA.CONN112_10137002101LF(CHIPS)':
 'N7': CDS_PINID='N7';
NODE_NAME     J107 A2
 '@S9S_MB_2U_LIB.S9S_MB_2U(SCH_1):PAGE317_I58@PURE_QUANTA.CONN112_10137002101LF(CHIPS)':
 'A2': CDS_PINID='A2';
NODE_NAME     J107 A4
 '@S9S_MB_2U_LIB.S9S_MB_2U(SCH_1):PAGE317_I58@PURE_QUANTA.CONN112_10137002101LF(CHIPS)':
 'A4': CDS_PINID='A4';
NODE_NAME     J107 B1
 '@S9S_MB_2U_LIB.S9S_MB_2U(SCH_1):PAGE317_I58@PURE_QUANTA.CONN112_10137002101LF(CHIPS)':
 'B1': CDS_PINID='B1';
NODE_NAME     J107 B3
 '@S9S_MB_2U_LIB.S9S_MB_2U(SCH_1):PAGE317_I58@PURE_QUANTA.CONN112_10137002101LF(CHIPS)':
 'B3': CDS_PINID='B3';
NODE_NAME     J107 D2
 '@S9S_MB_2U_LIB.S9S_MB_2U(SCH_1):PAGE317_I58@PURE_QUANTA.CONN112_10137002101LF(CHIPS)':
 'D2': CDS_PINID='D2';
NODE_NAME     J107 D4
 '@S9S_MB_2U_LIB.S9S_MB_2U(SCH_1):PAGE317_I58@PURE_QUANTA.CONN112_10137002101LF(CHIPS)':
 'D4': CDS_PINID='D4';
NODE_NAME     J107 E1
 '@S9S_MB_2U_LIB.S9S_MB_2U(SCH_1):PAGE317_I58@PURE_QUANTA.CONN112_10137002101LF(CHIPS)':
 'E1': CDS_PINID='E1';
NODE_NAME     J107 E3
 '@S9S_MB_2U_LIB.S9S_MB_2U(SCH_1):PAGE317_I58@PURE_QUANTA.CONN112_10137002101LF(CHIPS)':
 'E3': CDS_PINID='E3';
NODE_NAME     J107 G2
 '@S9S_MB_2U_LIB.S9S_MB_2U(SCH_1):PAGE317_I58@PURE_QUANTA.CONN112_10137002101LF(CHIPS)':
 'G2': CDS_PINID='G2';
NODE_NAME     J107 G4
 '@S9S_MB_2U_LIB.S9S_MB_2U(SCH_1):PAGE317_I58@PURE_QUANTA.CONN112_10137002101LF(CHIPS)':
 'G4': CDS_PINID='G4';
NODE_NAME     J107 H1
 '@S9S_MB_2U_LIB.S9S_MB_2U(SCH_1):PAGE317_I58@PURE_QUANTA.CONN112_10137002101LF(CHIPS)':
 'H1': CDS_PINID='H1';
NODE_NAME     J107 H3
 '@S9S_MB_2U_LIB.S9S_MB_2U(SCH_1):PAGE317_I58@PURE_QUANTA.CONN112_10137002101LF(CHIPS)':
 'H3': CDS_PINID='H3';
NODE_NAME     J107 J2
 '@S9S_MB_2U_LIB.S9S_MB_2U(SCH_1):PAGE317_I58@PURE_QUANTA.CONN112_10137002101LF(CHIPS)':
 'J2': CDS_PINID='J2';
NODE_NAME     J107 J4
 '@S9S_MB_2U_LIB.S9S_MB_2U(SCH_1):PAGE317_I58@PURE_QUANTA.CONN112_10137002101LF(CHIPS)':
 'J4': CDS_PINID='J4';
NODE_NAME     J107 K1
 '@S9S_MB_2U_LIB.S9S_MB_2U(SCH_1):PAGE317_I58@PURE_QUANTA.CONN112_10137002101LF(CHIPS)':
 'K1': CDS_PINID='K1';
NODE_NAME     J107 K3
 '@S9S_MB_2U_LIB.S9S_MB_2U(SCH_1):PAGE317_I58@PURE_QUANTA.CONN112_10137002101LF(CHIPS)':
 'K3': CDS_PINID='K3';
NODE_NAME     J107 M2
 '@S9S_MB_2U_LIB.S9S_MB_2U(SCH_1):PAGE317_I58@PURE_QUANTA.CONN112_10137002101LF(CHIPS)':
 'M2': CDS_PINID='M2';
NODE_NAME     J107 M4
 '@S9S_MB_2U_LIB.S9S_MB_2U(SCH_1):PAGE317_I58@PURE_QUANTA.CONN112_10137002101LF(CHIPS)':
 'M4': CDS_PINID='M4';
NODE_NAME     J107 N1
 '@S9S_MB_2U_LIB.S9S_MB_2U(SCH_1):PAGE317_I58@PURE_QUANTA.CONN112_10137002101LF(CHIPS)':
 'N1': CDS_PINID='N1';
NODE_NAME     J107 N3
 '@S9S_MB_2U_LIB.S9S_MB_2U(SCH_1):PAGE317_I58@PURE_QUANTA.CONN112_10137002101LF(CHIPS)':
 'N3': CDS_PINID='N3';
NODE_NAME     J108 A2
 '@S9S_MB_2U_LIB.S9S_MB_2U(SCH_1):PAGE320_I57@PURE_QUANTA.CONN112_10137002101LF(CHIPS)':
 'A2': CDS_PINID='A2';
NODE_NAME     J108 A4
 '@S9S_MB_2U_LIB.S9S_MB_2U(SCH_1):PAGE320_I57@PURE_QUANTA.CONN112_10137002101LF(CHIPS)':
 'A4': CDS_PINID='A4';
NODE_NAME     J108 B1
 '@S9S_MB_2U_LIB.S9S_MB_2U(SCH_1):PAGE320_I57@PURE_QUANTA.CONN112_10137002101LF(CHIPS)':
 'B1': CDS_PINID='B1';
NODE_NAME     J108 B3
 '@S9S_MB_2U_LIB.S9S_MB_2U(SCH_1):PAGE320_I57@PURE_QUANTA.CONN112_10137002101LF(CHIPS)':
 'B3': CDS_PINID='B3';
NODE_NAME     J108 D2
 '@S9S_MB_2U_LIB.S9S_MB_2U(SCH_1):PAGE320_I57@PURE_QUANTA.CONN112_10137002101LF(CHIPS)':
 'D2': CDS_PINID='D2';
NODE_NAME     J108 D4
 '@S9S_MB_2U_LIB.S9S_MB_2U(SCH_1):PAGE320_I57@PURE_QUANTA.CONN112_10137002101LF(CHIPS)':
 'D4': CDS_PINID='D4';
NODE_NAME     J108 E1
 '@S9S_MB_2U_LIB.S9S_MB_2U(SCH_1):PAGE320_I57@PURE_QUANTA.CONN112_10137002101LF(CHIPS)':
 'E1': CDS_PINID='E1';
NODE_NAME     J108 E3
 '@S9S_MB_2U_LIB.S9S_MB_2U(SCH_1):PAGE320_I57@PURE_QUANTA.CONN112_10137002101LF(CHIPS)':
 'E3': CDS_PINID='E3';
NODE_NAME     J108 G2
 '@S9S_MB_2U_LIB.S9S_MB_2U(SCH_1):PAGE320_I57@PURE_QUANTA.CONN112_10137002101LF(CHIPS)':
 'G2': CDS_PINID='G2';
NODE_NAME     J108 G4
 '@S9S_MB_2U_LIB.S9S_MB_2U(SCH_1):PAGE320_I57@PURE_QUANTA.CONN112_10137002101LF(CHIPS)':
 'G4': CDS_PINID='G4';
NODE_NAME     J108 H1
 '@S9S_MB_2U_LIB.S9S_MB_2U(SCH_1):PAGE320_I57@PURE_QUANTA.CONN112_10137002101LF(CHIPS)':
 'H1': CDS_PINID='H1';
NODE_NAME     J108 H3
 '@S9S_MB_2U_LIB.S9S_MB_2U(SCH_1):PAGE320_I57@PURE_QUANTA.CONN112_10137002101LF(CHIPS)':
 'H3': CDS_PINID='H3';
NODE_NAME     J108 J2
 '@S9S_MB_2U_LIB.S9S_MB_2U(SCH_1):PAGE320_I57@PURE_QUANTA.CONN112_10137002101LF(CHIPS)':
 'J2': CDS_PINID='J2';
NODE_NAME     J108 J4
 '@S9S_MB_2U_LIB.S9S_MB_2U(SCH_1):PAGE320_I57@PURE_QUANTA.CONN112_10137002101LF(CHIPS)':
 'J4': CDS_PINID='J4';
NODE_NAME     J108 K1
 '@S9S_MB_2U_LIB.S9S_MB_2U(SCH_1):PAGE320_I57@PURE_QUANTA.CONN112_10137002101LF(CHIPS)':
 'K1': CDS_PINID='K1';
NODE_NAME     J108 K3
 '@S9S_MB_2U_LIB.S9S_MB_2U(SCH_1):PAGE320_I57@PURE_QUANTA.CONN112_10137002101LF(CHIPS)':
 'K3': CDS_PINID='K3';
NODE_NAME     J108 M2
 '@S9S_MB_2U_LIB.S9S_MB_2U(SCH_1):PAGE320_I57@PURE_QUANTA.CONN112_10137002101LF(CHIPS)':
 'M2': CDS_PINID='M2';
NODE_NAME     J108 M4
 '@S9S_MB_2U_LIB.S9S_MB_2U(SCH_1):PAGE320_I57@PURE_QUANTA.CONN112_10137002101LF(CHIPS)':
 'M4': CDS_PINID='M4';
NODE_NAME     J108 N1
 '@S9S_MB_2U_LIB.S9S_MB_2U(SCH_1):PAGE320_I57@PURE_QUANTA.CONN112_10137002101LF(CHIPS)':
 'N1': CDS_PINID='N1';
NODE_NAME     J108 N3
 '@S9S_MB_2U_LIB.S9S_MB_2U(SCH_1):PAGE320_I57@PURE_QUANTA.CONN112_10137002101LF(CHIPS)':
 'N3': CDS_PINID='N3';
NODE_NAME     J108 A6
 '@S9S_MB_2U_LIB.S9S_MB_2U(SCH_1):PAGE320_I76@PURE_QUANTA.CONN112_10137002101LF(CHIPS)':
 'A6': CDS_PINID='A6';
NODE_NAME     J108 A8
 '@S9S_MB_2U_LIB.S9S_MB_2U(SCH_1):PAGE320_I76@PURE_QUANTA.CONN112_10137002101LF(CHIPS)':
 'A8': CDS_PINID='A8';
NODE_NAME     J108 B5
 '@S9S_MB_2U_LIB.S9S_MB_2U(SCH_1):PAGE320_I76@PURE_QUANTA.CONN112_10137002101LF(CHIPS)':
 'B5': CDS_PINID='B5';
NODE_NAME     J108 B7
 '@S9S_MB_2U_LIB.S9S_MB_2U(SCH_1):PAGE320_I76@PURE_QUANTA.CONN112_10137002101LF(CHIPS)':
 'B7': CDS_PINID='B7';
NODE_NAME     J108 D6
 '@S9S_MB_2U_LIB.S9S_MB_2U(SCH_1):PAGE320_I76@PURE_QUANTA.CONN112_10137002101LF(CHIPS)':
 'D6': CDS_PINID='D6';
NODE_NAME     J108 D8
 '@S9S_MB_2U_LIB.S9S_MB_2U(SCH_1):PAGE320_I76@PURE_QUANTA.CONN112_10137002101LF(CHIPS)':
 'D8': CDS_PINID='D8';
NODE_NAME     J108 E5
 '@S9S_MB_2U_LIB.S9S_MB_2U(SCH_1):PAGE320_I76@PURE_QUANTA.CONN112_10137002101LF(CHIPS)':
 'E5': CDS_PINID='E5';
NODE_NAME     J108 E7
 '@S9S_MB_2U_LIB.S9S_MB_2U(SCH_1):PAGE320_I76@PURE_QUANTA.CONN112_10137002101LF(CHIPS)':
 'E7': CDS_PINID='E7';
NODE_NAME     J108 G6
 '@S9S_MB_2U_LIB.S9S_MB_2U(SCH_1):PAGE320_I76@PURE_QUANTA.CONN112_10137002101LF(CHIPS)':
 'G6': CDS_PINID='G6';
NODE_NAME     J108 G8
 '@S9S_MB_2U_LIB.S9S_MB_2U(SCH_1):PAGE320_I76@PURE_QUANTA.CONN112_10137002101LF(CHIPS)':
 'G8': CDS_PINID='G8';
NODE_NAME     J108 H5
 '@S9S_MB_2U_LIB.S9S_MB_2U(SCH_1):PAGE320_I76@PURE_QUANTA.CONN112_10137002101LF(CHIPS)':
 'H5': CDS_PINID='H5';
NODE_NAME     J108 H7
 '@S9S_MB_2U_LIB.S9S_MB_2U(SCH_1):PAGE320_I76@PURE_QUANTA.CONN112_10137002101LF(CHIPS)':
 'H7': CDS_PINID='H7';
NODE_NAME     J108 J6
 '@S9S_MB_2U_LIB.S9S_MB_2U(SCH_1):PAGE320_I76@PURE_QUANTA.CONN112_10137002101LF(CHIPS)':
 'J6': CDS_PINID='J6';
NODE_NAME     J108 J8
 '@S9S_MB_2U_LIB.S9S_MB_2U(SCH_1):PAGE320_I76@PURE_QUANTA.CONN112_10137002101LF(CHIPS)':
 'J8': CDS_PINID='J8';
NODE_NAME     J108 K5
 '@S9S_MB_2U_LIB.S9S_MB_2U(SCH_1):PAGE320_I76@PURE_QUANTA.CONN112_10137002101LF(CHIPS)':
 'K5': CDS_PINID='K5';
NODE_NAME     J108 K7
 '@S9S_MB_2U_LIB.S9S_MB_2U(SCH_1):PAGE320_I76@PURE_QUANTA.CONN112_10137002101LF(CHIPS)':
 'K7': CDS_PINID='K7';
NODE_NAME     J108 M6
 '@S9S_MB_2U_LIB.S9S_MB_2U(SCH_1):PAGE320_I76@PURE_QUANTA.CONN112_10137002101LF(CHIPS)':
 'M6': CDS_PINID='M6';
NODE_NAME     J108 M8
 '@S9S_MB_2U_LIB.S9S_MB_2U(SCH_1):PAGE320_I76@PURE_QUANTA.CONN112_10137002101LF(CHIPS)':
 'M8': CDS_PINID='M8';
NODE_NAME     J108 N5
 '@S9S_MB_2U_LIB.S9S_MB_2U(SCH_1):PAGE320_I76@PURE_QUANTA.CONN112_10137002101LF(CHIPS)':
 'N5': CDS_PINID='N5';
NODE_NAME     J108 N7
 '@S9S_MB_2U_LIB.S9S_MB_2U(SCH_1):PAGE320_I76@PURE_QUANTA.CONN112_10137002101LF(CHIPS)':
 'N7': CDS_PINID='N7';
NODE_NAME     J110 A6
 '@S9S_MB_2U_LIB.S9S_MB_2U(SCH_1):PAGE318_I16@PURE_QUANTA.CONN112_10137002101LF(CHIPS)':
 'A6': CDS_PINID='A6';
NODE_NAME     J110 A8
 '@S9S_MB_2U_LIB.S9S_MB_2U(SCH_1):PAGE318_I16@PURE_QUANTA.CONN112_10137002101LF(CHIPS)':
 'A8': CDS_PINID='A8';
NODE_NAME     J110 B5
 '@S9S_MB_2U_LIB.S9S_MB_2U(SCH_1):PAGE318_I16@PURE_QUANTA.CONN112_10137002101LF(CHIPS)':
 'B5': CDS_PINID='B5';
NODE_NAME     J110 B7
 '@S9S_MB_2U_LIB.S9S_MB_2U(SCH_1):PAGE318_I16@PURE_QUANTA.CONN112_10137002101LF(CHIPS)':
 'B7': CDS_PINID='B7';
NODE_NAME     J110 D6
 '@S9S_MB_2U_LIB.S9S_MB_2U(SCH_1):PAGE318_I16@PURE_QUANTA.CONN112_10137002101LF(CHIPS)':
 'D6': CDS_PINID='D6';
NODE_NAME     J110 D8
 '@S9S_MB_2U_LIB.S9S_MB_2U(SCH_1):PAGE318_I16@PURE_QUANTA.CONN112_10137002101LF(CHIPS)':
 'D8': CDS_PINID='D8';
NODE_NAME     J110 E5
 '@S9S_MB_2U_LIB.S9S_MB_2U(SCH_1):PAGE318_I16@PURE_QUANTA.CONN112_10137002101LF(CHIPS)':
 'E5': CDS_PINID='E5';
NODE_NAME     J110 E7
 '@S9S_MB_2U_LIB.S9S_MB_2U(SCH_1):PAGE318_I16@PURE_QUANTA.CONN112_10137002101LF(CHIPS)':
 'E7': CDS_PINID='E7';
NODE_NAME     J110 G6
 '@S9S_MB_2U_LIB.S9S_MB_2U(SCH_1):PAGE318_I16@PURE_QUANTA.CONN112_10137002101LF(CHIPS)':
 'G6': CDS_PINID='G6';
NODE_NAME     J110 G8
 '@S9S_MB_2U_LIB.S9S_MB_2U(SCH_1):PAGE318_I16@PURE_QUANTA.CONN112_10137002101LF(CHIPS)':
 'G8': CDS_PINID='G8';
NODE_NAME     J110 H5
 '@S9S_MB_2U_LIB.S9S_MB_2U(SCH_1):PAGE318_I16@PURE_QUANTA.CONN112_10137002101LF(CHIPS)':
 'H5': CDS_PINID='H5';
NODE_NAME     J110 H7
 '@S9S_MB_2U_LIB.S9S_MB_2U(SCH_1):PAGE318_I16@PURE_QUANTA.CONN112_10137002101LF(CHIPS)':
 'H7': CDS_PINID='H7';
NODE_NAME     J110 J6
 '@S9S_MB_2U_LIB.S9S_MB_2U(SCH_1):PAGE318_I16@PURE_QUANTA.CONN112_10137002101LF(CHIPS)':
 'J6': CDS_PINID='J6';
NODE_NAME     J110 J8
 '@S9S_MB_2U_LIB.S9S_MB_2U(SCH_1):PAGE318_I16@PURE_QUANTA.CONN112_10137002101LF(CHIPS)':
 'J8': CDS_PINID='J8';
NODE_NAME     J110 K5
 '@S9S_MB_2U_LIB.S9S_MB_2U(SCH_1):PAGE318_I16@PURE_QUANTA.CONN112_10137002101LF(CHIPS)':
 'K5': CDS_PINID='K5';
NODE_NAME     J110 K7
 '@S9S_MB_2U_LIB.S9S_MB_2U(SCH_1):PAGE318_I16@PURE_QUANTA.CONN112_10137002101LF(CHIPS)':
 'K7': CDS_PINID='K7';
NODE_NAME     J110 M6
 '@S9S_MB_2U_LIB.S9S_MB_2U(SCH_1):PAGE318_I16@PURE_QUANTA.CONN112_10137002101LF(CHIPS)':
 'M6': CDS_PINID='M6';
NODE_NAME     J110 M8
 '@S9S_MB_2U_LIB.S9S_MB_2U(SCH_1):PAGE318_I16@PURE_QUANTA.CONN112_10137002101LF(CHIPS)':
 'M8': CDS_PINID='M8';
NODE_NAME     J110 N5
 '@S9S_MB_2U_LIB.S9S_MB_2U(SCH_1):PAGE318_I16@PURE_QUANTA.CONN112_10137002101LF(CHIPS)':
 'N5': CDS_PINID='N5';
NODE_NAME     J110 N7
 '@S9S_MB_2U_LIB.S9S_MB_2U(SCH_1):PAGE318_I16@PURE_QUANTA.CONN112_10137002101LF(CHIPS)':
 'N7': CDS_PINID='N7';
NODE_NAME     J110 A2
 '@S9S_MB_2U_LIB.S9S_MB_2U(SCH_1):PAGE318_I54@PURE_QUANTA.CONN112_10137002101LF(CHIPS)':
 'A2': CDS_PINID='A2';
NODE_NAME     J110 A4
 '@S9S_MB_2U_LIB.S9S_MB_2U(SCH_1):PAGE318_I54@PURE_QUANTA.CONN112_10137002101LF(CHIPS)':
 'A4': CDS_PINID='A4';
NODE_NAME     J110 B1
 '@S9S_MB_2U_LIB.S9S_MB_2U(SCH_1):PAGE318_I54@PURE_QUANTA.CONN112_10137002101LF(CHIPS)':
 'B1': CDS_PINID='B1';
NODE_NAME     J110 B3
 '@S9S_MB_2U_LIB.S9S_MB_2U(SCH_1):PAGE318_I54@PURE_QUANTA.CONN112_10137002101LF(CHIPS)':
 'B3': CDS_PINID='B3';
NODE_NAME     J110 D2
 '@S9S_MB_2U_LIB.S9S_MB_2U(SCH_1):PAGE318_I54@PURE_QUANTA.CONN112_10137002101LF(CHIPS)':
 'D2': CDS_PINID='D2';
NODE_NAME     J110 D4
 '@S9S_MB_2U_LIB.S9S_MB_2U(SCH_1):PAGE318_I54@PURE_QUANTA.CONN112_10137002101LF(CHIPS)':
 'D4': CDS_PINID='D4';
NODE_NAME     J110 E1
 '@S9S_MB_2U_LIB.S9S_MB_2U(SCH_1):PAGE318_I54@PURE_QUANTA.CONN112_10137002101LF(CHIPS)':
 'E1': CDS_PINID='E1';
NODE_NAME     J110 E3
 '@S9S_MB_2U_LIB.S9S_MB_2U(SCH_1):PAGE318_I54@PURE_QUANTA.CONN112_10137002101LF(CHIPS)':
 'E3': CDS_PINID='E3';
NODE_NAME     J110 G2
 '@S9S_MB_2U_LIB.S9S_MB_2U(SCH_1):PAGE318_I54@PURE_QUANTA.CONN112_10137002101LF(CHIPS)':
 'G2': CDS_PINID='G2';
NODE_NAME     J110 G4
 '@S9S_MB_2U_LIB.S9S_MB_2U(SCH_1):PAGE318_I54@PURE_QUANTA.CONN112_10137002101LF(CHIPS)':
 'G4': CDS_PINID='G4';
NODE_NAME     J110 H1
 '@S9S_MB_2U_LIB.S9S_MB_2U(SCH_1):PAGE318_I54@PURE_QUANTA.CONN112_10137002101LF(CHIPS)':
 'H1': CDS_PINID='H1';
NODE_NAME     J110 H3
 '@S9S_MB_2U_LIB.S9S_MB_2U(SCH_1):PAGE318_I54@PURE_QUANTA.CONN112_10137002101LF(CHIPS)':
 'H3': CDS_PINID='H3';
NODE_NAME     J110 J2
 '@S9S_MB_2U_LIB.S9S_MB_2U(SCH_1):PAGE318_I54@PURE_QUANTA.CONN112_10137002101LF(CHIPS)':
 'J2': CDS_PINID='J2';
NODE_NAME     J110 J4
 '@S9S_MB_2U_LIB.S9S_MB_2U(SCH_1):PAGE318_I54@PURE_QUANTA.CONN112_10137002101LF(CHIPS)':
 'J4': CDS_PINID='J4';
NODE_NAME     J110 K1
 '@S9S_MB_2U_LIB.S9S_MB_2U(SCH_1):PAGE318_I54@PURE_QUANTA.CONN112_10137002101LF(CHIPS)':
 'K1': CDS_PINID='K1';
NODE_NAME     J110 K3
 '@S9S_MB_2U_LIB.S9S_MB_2U(SCH_1):PAGE318_I54@PURE_QUANTA.CONN112_10137002101LF(CHIPS)':
 'K3': CDS_PINID='K3';
NODE_NAME     J110 M2
 '@S9S_MB_2U_LIB.S9S_MB_2U(SCH_1):PAGE318_I54@PURE_QUANTA.CONN112_10137002101LF(CHIPS)':
 'M2': CDS_PINID='M2';
NODE_NAME     J110 M4
 '@S9S_MB_2U_LIB.S9S_MB_2U(SCH_1):PAGE318_I54@PURE_QUANTA.CONN112_10137002101LF(CHIPS)':
 'M4': CDS_PINID='M4';
NODE_NAME     J110 N1
 '@S9S_MB_2U_LIB.S9S_MB_2U(SCH_1):PAGE318_I54@PURE_QUANTA.CONN112_10137002101LF(CHIPS)':
 'N1': CDS_PINID='N1';
NODE_NAME     J110 N3
 '@S9S_MB_2U_LIB.S9S_MB_2U(SCH_1):PAGE318_I54@PURE_QUANTA.CONN112_10137002101LF(CHIPS)':
 'N3': CDS_PINID='N3';
NODE_NAME     J109 A2
 '@S9S_MB_2U_LIB.S9S_MB_2U(SCH_1):PAGE319_I53@PURE_QUANTA.CONN112_10137002101LF(CHIPS)':
 'A2': CDS_PINID='A2';
NODE_NAME     J109 A4
 '@S9S_MB_2U_LIB.S9S_MB_2U(SCH_1):PAGE319_I53@PURE_QUANTA.CONN112_10137002101LF(CHIPS)':
 'A4': CDS_PINID='A4';
NODE_NAME     J109 B1
 '@S9S_MB_2U_LIB.S9S_MB_2U(SCH_1):PAGE319_I53@PURE_QUANTA.CONN112_10137002101LF(CHIPS)':
 'B1': CDS_PINID='B1';
NODE_NAME     J109 B3
 '@S9S_MB_2U_LIB.S9S_MB_2U(SCH_1):PAGE319_I53@PURE_QUANTA.CONN112_10137002101LF(CHIPS)':
 'B3': CDS_PINID='B3';
NODE_NAME     J109 D2
 '@S9S_MB_2U_LIB.S9S_MB_2U(SCH_1):PAGE319_I53@PURE_QUANTA.CONN112_10137002101LF(CHIPS)':
 'D2': CDS_PINID='D2';
NODE_NAME     J109 D4
 '@S9S_MB_2U_LIB.S9S_MB_2U(SCH_1):PAGE319_I53@PURE_QUANTA.CONN112_10137002101LF(CHIPS)':
 'D4': CDS_PINID='D4';
NODE_NAME     J109 E1
 '@S9S_MB_2U_LIB.S9S_MB_2U(SCH_1):PAGE319_I53@PURE_QUANTA.CONN112_10137002101LF(CHIPS)':
 'E1': CDS_PINID='E1';
NODE_NAME     J109 E3
 '@S9S_MB_2U_LIB.S9S_MB_2U(SCH_1):PAGE319_I53@PURE_QUANTA.CONN112_10137002101LF(CHIPS)':
 'E3': CDS_PINID='E3';
NODE_NAME     J109 G2
 '@S9S_MB_2U_LIB.S9S_MB_2U(SCH_1):PAGE319_I53@PURE_QUANTA.CONN112_10137002101LF(CHIPS)':
 'G2': CDS_PINID='G2';
NODE_NAME     J109 G4
 '@S9S_MB_2U_LIB.S9S_MB_2U(SCH_1):PAGE319_I53@PURE_QUANTA.CONN112_10137002101LF(CHIPS)':
 'G4': CDS_PINID='G4';
NODE_NAME     J109 H1
 '@S9S_MB_2U_LIB.S9S_MB_2U(SCH_1):PAGE319_I53@PURE_QUANTA.CONN112_10137002101LF(CHIPS)':
 'H1': CDS_PINID='H1';
NODE_NAME     J109 H3
 '@S9S_MB_2U_LIB.S9S_MB_2U(SCH_1):PAGE319_I53@PURE_QUANTA.CONN112_10137002101LF(CHIPS)':
 'H3': CDS_PINID='H3';
NODE_NAME     J109 J2
 '@S9S_MB_2U_LIB.S9S_MB_2U(SCH_1):PAGE319_I53@PURE_QUANTA.CONN112_10137002101LF(CHIPS)':
 'J2': CDS_PINID='J2';
NODE_NAME     J109 J4
 '@S9S_MB_2U_LIB.S9S_MB_2U(SCH_1):PAGE319_I53@PURE_QUANTA.CONN112_10137002101LF(CHIPS)':
 'J4': CDS_PINID='J4';
NODE_NAME     J109 K1
 '@S9S_MB_2U_LIB.S9S_MB_2U(SCH_1):PAGE319_I53@PURE_QUANTA.CONN112_10137002101LF(CHIPS)':
 'K1': CDS_PINID='K1';
NODE_NAME     J109 K3
 '@S9S_MB_2U_LIB.S9S_MB_2U(SCH_1):PAGE319_I53@PURE_QUANTA.CONN112_10137002101LF(CHIPS)':
 'K3': CDS_PINID='K3';
NODE_NAME     J109 M2
 '@S9S_MB_2U_LIB.S9S_MB_2U(SCH_1):PAGE319_I53@PURE_QUANTA.CONN112_10137002101LF(CHIPS)':
 'M2': CDS_PINID='M2';
NODE_NAME     J109 M4
 '@S9S_MB_2U_LIB.S9S_MB_2U(SCH_1):PAGE319_I53@PURE_QUANTA.CONN112_10137002101LF(CHIPS)':
 'M4': CDS_PINID='M4';
NODE_NAME     J109 N1
 '@S9S_MB_2U_LIB.S9S_MB_2U(SCH_1):PAGE319_I53@PURE_QUANTA.CONN112_10137002101LF(CHIPS)':
 'N1': CDS_PINID='N1';
NODE_NAME     J109 N3
 '@S9S_MB_2U_LIB.S9S_MB_2U(SCH_1):PAGE319_I53@PURE_QUANTA.CONN112_10137002101LF(CHIPS)':
 'N3': CDS_PINID='N3';
NODE_NAME     J109 A6
 '@S9S_MB_2U_LIB.S9S_MB_2U(SCH_1):PAGE319_I76@PURE_QUANTA.CONN112_10137002101LF(CHIPS)':
 'A6': CDS_PINID='A6';
NODE_NAME     J109 A8
 '@S9S_MB_2U_LIB.S9S_MB_2U(SCH_1):PAGE319_I76@PURE_QUANTA.CONN112_10137002101LF(CHIPS)':
 'A8': CDS_PINID='A8';
NODE_NAME     J109 B5
 '@S9S_MB_2U_LIB.S9S_MB_2U(SCH_1):PAGE319_I76@PURE_QUANTA.CONN112_10137002101LF(CHIPS)':
 'B5': CDS_PINID='B5';
NODE_NAME     J109 B7
 '@S9S_MB_2U_LIB.S9S_MB_2U(SCH_1):PAGE319_I76@PURE_QUANTA.CONN112_10137002101LF(CHIPS)':
 'B7': CDS_PINID='B7';
NODE_NAME     J109 D6
 '@S9S_MB_2U_LIB.S9S_MB_2U(SCH_1):PAGE319_I76@PURE_QUANTA.CONN112_10137002101LF(CHIPS)':
 'D6': CDS_PINID='D6';
NODE_NAME     J109 D8
 '@S9S_MB_2U_LIB.S9S_MB_2U(SCH_1):PAGE319_I76@PURE_QUANTA.CONN112_10137002101LF(CHIPS)':
 'D8': CDS_PINID='D8';
NODE_NAME     J109 E5
 '@S9S_MB_2U_LIB.S9S_MB_2U(SCH_1):PAGE319_I76@PURE_QUANTA.CONN112_10137002101LF(CHIPS)':
 'E5': CDS_PINID='E5';
NODE_NAME     J109 E7
 '@S9S_MB_2U_LIB.S9S_MB_2U(SCH_1):PAGE319_I76@PURE_QUANTA.CONN112_10137002101LF(CHIPS)':
 'E7': CDS_PINID='E7';
NODE_NAME     J109 G6
 '@S9S_MB_2U_LIB.S9S_MB_2U(SCH_1):PAGE319_I76@PURE_QUANTA.CONN112_10137002101LF(CHIPS)':
 'G6': CDS_PINID='G6';
NODE_NAME     J109 G8
 '@S9S_MB_2U_LIB.S9S_MB_2U(SCH_1):PAGE319_I76@PURE_QUANTA.CONN112_10137002101LF(CHIPS)':
 'G8': CDS_PINID='G8';
NODE_NAME     J109 H5
 '@S9S_MB_2U_LIB.S9S_MB_2U(SCH_1):PAGE319_I76@PURE_QUANTA.CONN112_10137002101LF(CHIPS)':
 'H5': CDS_PINID='H5';
NODE_NAME     J109 H7
 '@S9S_MB_2U_LIB.S9S_MB_2U(SCH_1):PAGE319_I76@PURE_QUANTA.CONN112_10137002101LF(CHIPS)':
 'H7': CDS_PINID='H7';
NODE_NAME     J109 J6
 '@S9S_MB_2U_LIB.S9S_MB_2U(SCH_1):PAGE319_I76@PURE_QUANTA.CONN112_10137002101LF(CHIPS)':
 'J6': CDS_PINID='J6';
NODE_NAME     J109 J8
 '@S9S_MB_2U_LIB.S9S_MB_2U(SCH_1):PAGE319_I76@PURE_QUANTA.CONN112_10137002101LF(CHIPS)':
 'J8': CDS_PINID='J8';
NODE_NAME     J109 K5
 '@S9S_MB_2U_LIB.S9S_MB_2U(SCH_1):PAGE319_I76@PURE_QUANTA.CONN112_10137002101LF(CHIPS)':
 'K5': CDS_PINID='K5';
NODE_NAME     J109 K7
 '@S9S_MB_2U_LIB.S9S_MB_2U(SCH_1):PAGE319_I76@PURE_QUANTA.CONN112_10137002101LF(CHIPS)':
 'K7': CDS_PINID='K7';
NODE_NAME     J109 M6
 '@S9S_MB_2U_LIB.S9S_MB_2U(SCH_1):PAGE319_I76@PURE_QUANTA.CONN112_10137002101LF(CHIPS)':
 'M6': CDS_PINID='M6';
NODE_NAME     J109 M8
 '@S9S_MB_2U_LIB.S9S_MB_2U(SCH_1):PAGE319_I76@PURE_QUANTA.CONN112_10137002101LF(CHIPS)':
 'M8': CDS_PINID='M8';
NODE_NAME     J109 N5
 '@S9S_MB_2U_LIB.S9S_MB_2U(SCH_1):PAGE319_I76@PURE_QUANTA.CONN112_10137002101LF(CHIPS)':
 'N5': CDS_PINID='N5';
NODE_NAME     J109 N7
 '@S9S_MB_2U_LIB.S9S_MB_2U(SCH_1):PAGE319_I76@PURE_QUANTA.CONN112_10137002101LF(CHIPS)':
 'N7': CDS_PINID='N7';
NODE_NAME     C1882 2
 '@S9S_MB_2U_LIB.S9S_MB_2U(SCH_1):PAGE201_I80@PURE_QUANTA.Q_CAP(CHIPS)':
 'B': CDS_PINID='B';
NODE_NAME     C1320 2
 '@S9S_MB_2U_LIB.S9S_MB_2U(SCH_1):PAGE313_I126@PURE_QUANTA.Q_CAP(CHIPS)':
 'B': CDS_PINID='B';
NODE_NAME     OSC2 2
 '@S9S_MB_2U_LIB.S9S_MB_2U(SCH_1):PAGE313_I127@PURE_QUANTA.Q_OSC4P(CHIPS)':
 'GND': CDS_PINID='GND';
NODE_NAME     Q50 4
 '@S9S_MB_2U_LIB.S9S_MB_2U(SCH_1):PAGE314_I49@PURE_QUANTA.MOSFET_NCH_DUAL(CHIPS)':
 'S2': CDS_PINID='S2';
NODE_NAME     C1325 2
 '@S9S_MB_2U_LIB.S9S_MB_2U(SCH_1):PAGE312_I39@PURE_QUANTA.Q_CAP(CHIPS)':
 'B': CDS_PINID='B';
NODE_NAME     U249 A1
 '@S9S_MB_2U_LIB.S9S_MB_2U(SCH_1):PAGE202_I1@PURE_QUANTA.LCMXO3LF9400C5BG484C(CHIPS)':
 'GND1': CDS_PINID='GND1';
NODE_NAME     U249 A22
 '@S9S_MB_2U_LIB.S9S_MB_2U(SCH_1):PAGE202_I1@PURE_QUANTA.LCMXO3LF9400C5BG484C(CHIPS)':
 'GND2': CDS_PINID='GND2';
NODE_NAME     U249 B7
 '@S9S_MB_2U_LIB.S9S_MB_2U(SCH_1):PAGE202_I1@PURE_QUANTA.LCMXO3LF9400C5BG484C(CHIPS)':
 'GND3': CDS_PINID='GND3';
NODE_NAME     U249 B16
 '@S9S_MB_2U_LIB.S9S_MB_2U(SCH_1):PAGE202_I1@PURE_QUANTA.LCMXO3LF9400C5BG484C(CHIPS)':
 'GND4': CDS_PINID='GND4';
NODE_NAME     U249 C2
 '@S9S_MB_2U_LIB.S9S_MB_2U(SCH_1):PAGE202_I1@PURE_QUANTA.LCMXO3LF9400C5BG484C(CHIPS)':
 'GND5': CDS_PINID='GND5';
NODE_NAME     U249 C11
 '@S9S_MB_2U_LIB.S9S_MB_2U(SCH_1):PAGE202_I1@PURE_QUANTA.LCMXO3LF9400C5BG484C(CHIPS)':
 'GND6': CDS_PINID='GND6';
NODE_NAME     U249 E5
 '@S9S_MB_2U_LIB.S9S_MB_2U(SCH_1):PAGE202_I1@PURE_QUANTA.LCMXO3LF9400C5BG484C(CHIPS)':
 'GND7': CDS_PINID='GND7';
NODE_NAME     U249 E18
 '@S9S_MB_2U_LIB.S9S_MB_2U(SCH_1):PAGE202_I1@PURE_QUANTA.LCMXO3LF9400C5BG484C(CHIPS)':
 'GND8': CDS_PINID='GND8';
NODE_NAME     U249 F2
 '@S9S_MB_2U_LIB.S9S_MB_2U(SCH_1):PAGE202_I1@PURE_QUANTA.LCMXO3LF9400C5BG484C(CHIPS)':
 'GND9': CDS_PINID='GND9';
NODE_NAME     U249 F21
 '@S9S_MB_2U_LIB.S9S_MB_2U(SCH_1):PAGE202_I1@PURE_QUANTA.LCMXO3LF9400C5BG484C(CHIPS)':
 'GND10': CDS_PINID='GND10';
NODE_NAME     U249 H8
 '@S9S_MB_2U_LIB.S9S_MB_2U(SCH_1):PAGE202_I1@PURE_QUANTA.LCMXO3LF9400C5BG484C(CHIPS)':
 'GND11': CDS_PINID='GND11';
NODE_NAME     U249 H10
 '@S9S_MB_2U_LIB.S9S_MB_2U(SCH_1):PAGE202_I1@PURE_QUANTA.LCMXO3LF9400C5BG484C(CHIPS)':
 'GND12': CDS_PINID='GND12';
NODE_NAME     U249 H13
 '@S9S_MB_2U_LIB.S9S_MB_2U(SCH_1):PAGE202_I1@PURE_QUANTA.LCMXO3LF9400C5BG484C(CHIPS)':
 'GND13': CDS_PINID='GND13';
NODE_NAME     U249 H15
 '@S9S_MB_2U_LIB.S9S_MB_2U(SCH_1):PAGE202_I1@PURE_QUANTA.LCMXO3LF9400C5BG484C(CHIPS)':
 'GND14': CDS_PINID='GND14';
NODE_NAME     U249 J9
 '@S9S_MB_2U_LIB.S9S_MB_2U(SCH_1):PAGE202_I1@PURE_QUANTA.LCMXO3LF9400C5BG484C(CHIPS)':
 'GND15': CDS_PINID='GND15';
NODE_NAME     U249 J10
 '@S9S_MB_2U_LIB.S9S_MB_2U(SCH_1):PAGE202_I1@PURE_QUANTA.LCMXO3LF9400C5BG484C(CHIPS)':
 'GND16': CDS_PINID='GND16';
NODE_NAME     U249 J11
 '@S9S_MB_2U_LIB.S9S_MB_2U(SCH_1):PAGE202_I1@PURE_QUANTA.LCMXO3LF9400C5BG484C(CHIPS)':
 'GND17': CDS_PINID='GND17';
NODE_NAME     U249 J12
 '@S9S_MB_2U_LIB.S9S_MB_2U(SCH_1):PAGE202_I1@PURE_QUANTA.LCMXO3LF9400C5BG484C(CHIPS)':
 'GND18': CDS_PINID='GND18';
NODE_NAME     U249 J13
 '@S9S_MB_2U_LIB.S9S_MB_2U(SCH_1):PAGE202_I1@PURE_QUANTA.LCMXO3LF9400C5BG484C(CHIPS)':
 'GND19': CDS_PINID='GND19';
NODE_NAME     U249 J14
 '@S9S_MB_2U_LIB.S9S_MB_2U(SCH_1):PAGE202_I1@PURE_QUANTA.LCMXO3LF9400C5BG484C(CHIPS)':
 'GND20': CDS_PINID='GND20';
NODE_NAME     U249 K9
 '@S9S_MB_2U_LIB.S9S_MB_2U(SCH_1):PAGE202_I1@PURE_QUANTA.LCMXO3LF9400C5BG484C(CHIPS)':
 'GND21': CDS_PINID='GND21';
NODE_NAME     U249 K14
 '@S9S_MB_2U_LIB.S9S_MB_2U(SCH_1):PAGE202_I1@PURE_QUANTA.LCMXO3LF9400C5BG484C(CHIPS)':
 'GND22': CDS_PINID='GND22';
NODE_NAME     U249 K21
 '@S9S_MB_2U_LIB.S9S_MB_2U(SCH_1):PAGE202_I1@PURE_QUANTA.LCMXO3LF9400C5BG484C(CHIPS)':
 'GND23': CDS_PINID='GND23';
NODE_NAME     U249 L2
 '@S9S_MB_2U_LIB.S9S_MB_2U(SCH_1):PAGE202_I1@PURE_QUANTA.LCMXO3LF9400C5BG484C(CHIPS)':
 'GND24': CDS_PINID='GND24';
NODE_NAME     U249 L9
 '@S9S_MB_2U_LIB.S9S_MB_2U(SCH_1):PAGE202_I1@PURE_QUANTA.LCMXO3LF9400C5BG484C(CHIPS)':
 'GND25': CDS_PINID='GND25';
NODE_NAME     U249 L10
 '@S9S_MB_2U_LIB.S9S_MB_2U(SCH_1):PAGE202_I1@PURE_QUANTA.LCMXO3LF9400C5BG484C(CHIPS)':
 'GND26': CDS_PINID='GND26';
NODE_NAME     U249 L13
 '@S9S_MB_2U_LIB.S9S_MB_2U(SCH_1):PAGE202_I1@PURE_QUANTA.LCMXO3LF9400C5BG484C(CHIPS)':
 'GND27': CDS_PINID='GND27';
NODE_NAME     U249 L14
 '@S9S_MB_2U_LIB.S9S_MB_2U(SCH_1):PAGE202_I1@PURE_QUANTA.LCMXO3LF9400C5BG484C(CHIPS)':
 'GND28': CDS_PINID='GND28';
NODE_NAME     U249 L18
 '@S9S_MB_2U_LIB.S9S_MB_2U(SCH_1):PAGE202_I1@PURE_QUANTA.LCMXO3LF9400C5BG484C(CHIPS)':
 'GND29': CDS_PINID='GND29';
NODE_NAME     U249 M4
 '@S9S_MB_2U_LIB.S9S_MB_2U(SCH_1):PAGE202_I1@PURE_QUANTA.LCMXO3LF9400C5BG484C(CHIPS)':
 'GND30': CDS_PINID='GND30';
NODE_NAME     U249 M9
 '@S9S_MB_2U_LIB.S9S_MB_2U(SCH_1):PAGE202_I1@PURE_QUANTA.LCMXO3LF9400C5BG484C(CHIPS)':
 'GND31': CDS_PINID='GND31';
NODE_NAME     U249 M10
 '@S9S_MB_2U_LIB.S9S_MB_2U(SCH_1):PAGE202_I1@PURE_QUANTA.LCMXO3LF9400C5BG484C(CHIPS)':
 'GND32': CDS_PINID='GND32';
NODE_NAME     U249 M13
 '@S9S_MB_2U_LIB.S9S_MB_2U(SCH_1):PAGE202_I1@PURE_QUANTA.LCMXO3LF9400C5BG484C(CHIPS)':
 'GND33': CDS_PINID='GND33';
NODE_NAME     U249 M14
 '@S9S_MB_2U_LIB.S9S_MB_2U(SCH_1):PAGE202_I1@PURE_QUANTA.LCMXO3LF9400C5BG484C(CHIPS)':
 'GND34': CDS_PINID='GND34';
NODE_NAME     U249 N9
 '@S9S_MB_2U_LIB.S9S_MB_2U(SCH_1):PAGE202_I1@PURE_QUANTA.LCMXO3LF9400C5BG484C(CHIPS)':
 'GND35': CDS_PINID='GND35';
NODE_NAME     U249 N14
 '@S9S_MB_2U_LIB.S9S_MB_2U(SCH_1):PAGE202_I1@PURE_QUANTA.LCMXO3LF9400C5BG484C(CHIPS)':
 'GND36': CDS_PINID='GND36';
NODE_NAME     U249 N21
 '@S9S_MB_2U_LIB.S9S_MB_2U(SCH_1):PAGE202_I1@PURE_QUANTA.LCMXO3LF9400C5BG484C(CHIPS)':
 'GND37': CDS_PINID='GND37';
NODE_NAME     U249 P9
 '@S9S_MB_2U_LIB.S9S_MB_2U(SCH_1):PAGE202_I1@PURE_QUANTA.LCMXO3LF9400C5BG484C(CHIPS)':
 'GND38': CDS_PINID='GND38';
NODE_NAME     U249 P10
 '@S9S_MB_2U_LIB.S9S_MB_2U(SCH_1):PAGE202_I1@PURE_QUANTA.LCMXO3LF9400C5BG484C(CHIPS)':
 'GND39': CDS_PINID='GND39';
NODE_NAME     U249 P11
 '@S9S_MB_2U_LIB.S9S_MB_2U(SCH_1):PAGE202_I1@PURE_QUANTA.LCMXO3LF9400C5BG484C(CHIPS)':
 'GND40': CDS_PINID='GND40';
NODE_NAME     U249 P12
 '@S9S_MB_2U_LIB.S9S_MB_2U(SCH_1):PAGE202_I1@PURE_QUANTA.LCMXO3LF9400C5BG484C(CHIPS)':
 'GND41': CDS_PINID='GND41';
NODE_NAME     U249 P13
 '@S9S_MB_2U_LIB.S9S_MB_2U(SCH_1):PAGE202_I1@PURE_QUANTA.LCMXO3LF9400C5BG484C(CHIPS)':
 'GND42': CDS_PINID='GND42';
NODE_NAME     U249 P14
 '@S9S_MB_2U_LIB.S9S_MB_2U(SCH_1):PAGE202_I1@PURE_QUANTA.LCMXO3LF9400C5BG484C(CHIPS)':
 'GND43': CDS_PINID='GND43';
NODE_NAME     U249 R8
 '@S9S_MB_2U_LIB.S9S_MB_2U(SCH_1):PAGE202_I1@PURE_QUANTA.LCMXO3LF9400C5BG484C(CHIPS)':
 'GND44': CDS_PINID='GND44';
NODE_NAME     U249 R15
 '@S9S_MB_2U_LIB.S9S_MB_2U(SCH_1):PAGE202_I1@PURE_QUANTA.LCMXO3LF9400C5BG484C(CHIPS)':
 'GND45': CDS_PINID='GND45';
NODE_NAME     U249 V2
 '@S9S_MB_2U_LIB.S9S_MB_2U(SCH_1):PAGE202_I1@PURE_QUANTA.LCMXO3LF9400C5BG484C(CHIPS)':
 'GND46': CDS_PINID='GND46';
NODE_NAME     U249 V21
 '@S9S_MB_2U_LIB.S9S_MB_2U(SCH_1):PAGE202_I1@PURE_QUANTA.LCMXO3LF9400C5BG484C(CHIPS)':
 'GND47': CDS_PINID='GND47';
NODE_NAME     U249 W12
 '@S9S_MB_2U_LIB.S9S_MB_2U(SCH_1):PAGE202_I1@PURE_QUANTA.LCMXO3LF9400C5BG484C(CHIPS)':
 'GND48': CDS_PINID='GND48';
NODE_NAME     U249 Y7
 '@S9S_MB_2U_LIB.S9S_MB_2U(SCH_1):PAGE202_I1@PURE_QUANTA.LCMXO3LF9400C5BG484C(CHIPS)':
 'GND49': CDS_PINID='GND49';
NODE_NAME     U249 Y16
 '@S9S_MB_2U_LIB.S9S_MB_2U(SCH_1):PAGE202_I1@PURE_QUANTA.LCMXO3LF9400C5BG484C(CHIPS)':
 'GND50': CDS_PINID='GND50';
NODE_NAME     U249 AB1
 '@S9S_MB_2U_LIB.S9S_MB_2U(SCH_1):PAGE202_I1@PURE_QUANTA.LCMXO3LF9400C5BG484C(CHIPS)':
 'GND51': CDS_PINID='GND51';
NODE_NAME     U249 AB22
 '@S9S_MB_2U_LIB.S9S_MB_2U(SCH_1):PAGE202_I1@PURE_QUANTA.LCMXO3LF9400C5BG484C(CHIPS)':
 'GND52': CDS_PINID='GND52';
NODE_NAME     C1154 2
 '@S9S_MB_2U_LIB.S9S_MB_2U(SCH_1):PAGE202_I3@PURE_QUANTA.Q_CAP(CHIPS)':
 'B': CDS_PINID='B';
NODE_NAME     C1152 2
 '@S9S_MB_2U_LIB.S9S_MB_2U(SCH_1):PAGE202_I5@PURE_QUANTA.Q_CAP(CHIPS)':
 'B': CDS_PINID='B';
NODE_NAME     C1932 2
 '@S9S_MB_2U_LIB.S9S_MB_2U(SCH_1):PAGE202_I9@PURE_QUANTA.Q_CAP(CHIPS)':
 'B': CDS_PINID='B';
NODE_NAME     C1933 2
 '@S9S_MB_2U_LIB.S9S_MB_2U(SCH_1):PAGE202_I12@PURE_QUANTA.Q_CAP(CHIPS)':
 'B': CDS_PINID='B';
NODE_NAME     C1146 2
 '@S9S_MB_2U_LIB.S9S_MB_2U(SCH_1):PAGE202_I15@PURE_QUANTA.Q_CAP(CHIPS)':
 'B': CDS_PINID='B';
NODE_NAME     C1904 2
 '@S9S_MB_2U_LIB.S9S_MB_2U(SCH_1):PAGE202_I18@PURE_QUANTA.Q_CAP(CHIPS)':
 'B': CDS_PINID='B';
NODE_NAME     C1898 2
 '@S9S_MB_2U_LIB.S9S_MB_2U(SCH_1):PAGE202_I20@PURE_QUANTA.Q_CAP(CHIPS)':
 'B': CDS_PINID='B';
NODE_NAME     C1931 2
 '@S9S_MB_2U_LIB.S9S_MB_2U(SCH_1):PAGE202_I21@PURE_QUANTA.Q_CAP(CHIPS)':
 'B': CDS_PINID='B';
NODE_NAME     C1928 2
 '@S9S_MB_2U_LIB.S9S_MB_2U(SCH_1):PAGE202_I22@PURE_QUANTA.Q_CAP(CHIPS)':
 'B': CDS_PINID='B';
NODE_NAME     C1919 2
 '@S9S_MB_2U_LIB.S9S_MB_2U(SCH_1):PAGE202_I23@PURE_QUANTA.Q_CAP(CHIPS)':
 'B': CDS_PINID='B';
NODE_NAME     C1916 2
 '@S9S_MB_2U_LIB.S9S_MB_2U(SCH_1):PAGE202_I24@PURE_QUANTA.Q_CAP(CHIPS)':
 'B': CDS_PINID='B';
NODE_NAME     C1907 2
 '@S9S_MB_2U_LIB.S9S_MB_2U(SCH_1):PAGE202_I25@PURE_QUANTA.Q_CAP(CHIPS)':
 'B': CDS_PINID='B';
NODE_NAME     C1903 2
 '@S9S_MB_2U_LIB.S9S_MB_2U(SCH_1):PAGE202_I26@PURE_QUANTA.Q_CAP(CHIPS)':
 'B': CDS_PINID='B';
NODE_NAME     C1897 2
 '@S9S_MB_2U_LIB.S9S_MB_2U(SCH_1):PAGE202_I27@PURE_QUANTA.Q_CAP(CHIPS)':
 'B': CDS_PINID='B';
NODE_NAME     C1912 2
 '@S9S_MB_2U_LIB.S9S_MB_2U(SCH_1):PAGE202_I28@PURE_QUANTA.Q_CAP(CHIPS)':
 'B': CDS_PINID='B';
NODE_NAME     C1943 2
 '@S9S_MB_2U_LIB.S9S_MB_2U(SCH_1):PAGE202_I29@PURE_QUANTA.Q_CAP(CHIPS)':
 'B': CDS_PINID='B';
NODE_NAME     C1936 2
 '@S9S_MB_2U_LIB.S9S_MB_2U(SCH_1):PAGE202_I30@PURE_QUANTA.Q_CAP(CHIPS)':
 'B': CDS_PINID='B';
NODE_NAME     C1929 2
 '@S9S_MB_2U_LIB.S9S_MB_2U(SCH_1):PAGE202_I33@PURE_QUANTA.Q_CAP(CHIPS)':
 'B': CDS_PINID='B';
NODE_NAME     C1926 2
 '@S9S_MB_2U_LIB.S9S_MB_2U(SCH_1):PAGE202_I34@PURE_QUANTA.Q_CAP(CHIPS)':
 'B': CDS_PINID='B';
NODE_NAME     C1917 2
 '@S9S_MB_2U_LIB.S9S_MB_2U(SCH_1):PAGE202_I35@PURE_QUANTA.Q_CAP(CHIPS)':
 'B': CDS_PINID='B';
NODE_NAME     C1914 2
 '@S9S_MB_2U_LIB.S9S_MB_2U(SCH_1):PAGE202_I36@PURE_QUANTA.Q_CAP(CHIPS)':
 'B': CDS_PINID='B';
NODE_NAME     C1930 2
 '@S9S_MB_2U_LIB.S9S_MB_2U(SCH_1):PAGE202_I37@PURE_QUANTA.Q_CAP(CHIPS)':
 'B': CDS_PINID='B';
NODE_NAME     C1927 2
 '@S9S_MB_2U_LIB.S9S_MB_2U(SCH_1):PAGE202_I38@PURE_QUANTA.Q_CAP(CHIPS)':
 'B': CDS_PINID='B';
NODE_NAME     C1918 2
 '@S9S_MB_2U_LIB.S9S_MB_2U(SCH_1):PAGE202_I39@PURE_QUANTA.Q_CAP(CHIPS)':
 'B': CDS_PINID='B';
NODE_NAME     C1915 2
 '@S9S_MB_2U_LIB.S9S_MB_2U(SCH_1):PAGE202_I40@PURE_QUANTA.Q_CAP(CHIPS)':
 'B': CDS_PINID='B';
NODE_NAME     C1905 2
 '@S9S_MB_2U_LIB.S9S_MB_2U(SCH_1):PAGE202_I41@PURE_QUANTA.Q_CAP(CHIPS)':
 'B': CDS_PINID='B';
NODE_NAME     C1901 2
 '@S9S_MB_2U_LIB.S9S_MB_2U(SCH_1):PAGE202_I42@PURE_QUANTA.Q_CAP(CHIPS)':
 'B': CDS_PINID='B';
NODE_NAME     C1895 2
 '@S9S_MB_2U_LIB.S9S_MB_2U(SCH_1):PAGE202_I43@PURE_QUANTA.Q_CAP(CHIPS)':
 'B': CDS_PINID='B';
NODE_NAME     C1910 2
 '@S9S_MB_2U_LIB.S9S_MB_2U(SCH_1):PAGE202_I44@PURE_QUANTA.Q_CAP(CHIPS)':
 'B': CDS_PINID='B';
NODE_NAME     C1906 2
 '@S9S_MB_2U_LIB.S9S_MB_2U(SCH_1):PAGE202_I45@PURE_QUANTA.Q_CAP(CHIPS)':
 'B': CDS_PINID='B';
NODE_NAME     C1902 2
 '@S9S_MB_2U_LIB.S9S_MB_2U(SCH_1):PAGE202_I46@PURE_QUANTA.Q_CAP(CHIPS)':
 'B': CDS_PINID='B';
NODE_NAME     C1896 2
 '@S9S_MB_2U_LIB.S9S_MB_2U(SCH_1):PAGE202_I47@PURE_QUANTA.Q_CAP(CHIPS)':
 'B': CDS_PINID='B';
NODE_NAME     C1911 2
 '@S9S_MB_2U_LIB.S9S_MB_2U(SCH_1):PAGE202_I48@PURE_QUANTA.Q_CAP(CHIPS)':
 'B': CDS_PINID='B';
NODE_NAME     C1142 2
 '@S9S_MB_2U_LIB.S9S_MB_2U(SCH_1):PAGE202_I49@PURE_QUANTA.Q_CAP(CHIPS)':
 'B': CDS_PINID='B';
NODE_NAME     C1138 2
 '@S9S_MB_2U_LIB.S9S_MB_2U(SCH_1):PAGE202_I50@PURE_QUANTA.Q_CAP(CHIPS)':
 'B': CDS_PINID='B';
NODE_NAME     C1133 2
 '@S9S_MB_2U_LIB.S9S_MB_2U(SCH_1):PAGE202_I51@PURE_QUANTA.Q_CAP(CHIPS)':
 'B': CDS_PINID='B';
NODE_NAME     C1127 2
 '@S9S_MB_2U_LIB.S9S_MB_2U(SCH_1):PAGE202_I52@PURE_QUANTA.Q_CAP(CHIPS)':
 'B': CDS_PINID='B';
NODE_NAME     C1913 2
 '@S9S_MB_2U_LIB.S9S_MB_2U(SCH_1):PAGE202_I53@PURE_QUANTA.Q_CAP(CHIPS)':
 'B': CDS_PINID='B';
NODE_NAME     C1947 2
 '@S9S_MB_2U_LIB.S9S_MB_2U(SCH_1):PAGE202_I54@PURE_QUANTA.Q_CAP(CHIPS)':
 'B': CDS_PINID='B';
NODE_NAME     C1940 2
 '@S9S_MB_2U_LIB.S9S_MB_2U(SCH_1):PAGE202_I55@PURE_QUANTA.Q_CAP(CHIPS)':
 'B': CDS_PINID='B';
NODE_NAME     C1122 2
 '@S9S_MB_2U_LIB.S9S_MB_2U(SCH_1):PAGE202_I56@PURE_QUANTA.Q_CAP(CHIPS)':
 'B': CDS_PINID='B';
NODE_NAME     C1900 2
 '@S9S_MB_2U_LIB.S9S_MB_2U(SCH_1):PAGE202_I57@PURE_QUANTA.Q_CAP(CHIPS)':
 'B': CDS_PINID='B';
NODE_NAME     C1894 2
 '@S9S_MB_2U_LIB.S9S_MB_2U(SCH_1):PAGE202_I58@PURE_QUANTA.Q_CAP(CHIPS)':
 'B': CDS_PINID='B';
NODE_NAME     C1909 2
 '@S9S_MB_2U_LIB.S9S_MB_2U(SCH_1):PAGE202_I59@PURE_QUANTA.Q_CAP(CHIPS)':
 'B': CDS_PINID='B';
NODE_NAME     C1945 2
 '@S9S_MB_2U_LIB.S9S_MB_2U(SCH_1):PAGE202_I62@PURE_QUANTA.Q_CAP(CHIPS)':
 'B': CDS_PINID='B';
NODE_NAME     C1938 2
 '@S9S_MB_2U_LIB.S9S_MB_2U(SCH_1):PAGE202_I64@PURE_QUANTA.Q_CAP(CHIPS)':
 'B': CDS_PINID='B';
NODE_NAME     C1946 2
 '@S9S_MB_2U_LIB.S9S_MB_2U(SCH_1):PAGE202_I65@PURE_QUANTA.Q_CAP(CHIPS)':
 'B': CDS_PINID='B';
NODE_NAME     C1939 2
 '@S9S_MB_2U_LIB.S9S_MB_2U(SCH_1):PAGE202_I66@PURE_QUANTA.Q_CAP(CHIPS)':
 'B': CDS_PINID='B';
NODE_NAME     C1944 2
 '@S9S_MB_2U_LIB.S9S_MB_2U(SCH_1):PAGE202_I70@PURE_QUANTA.Q_CAP(CHIPS)':
 'B': CDS_PINID='B';
NODE_NAME     C1937 2
 '@S9S_MB_2U_LIB.S9S_MB_2U(SCH_1):PAGE202_I71@PURE_QUANTA.Q_CAP(CHIPS)':
 'B': CDS_PINID='B';
NODE_NAME     C1899 2
 '@S9S_MB_2U_LIB.S9S_MB_2U(SCH_1):PAGE202_I74@PURE_QUANTA.Q_CAP(CHIPS)':
 'B': CDS_PINID='B';
NODE_NAME     C1893 2
 '@S9S_MB_2U_LIB.S9S_MB_2U(SCH_1):PAGE202_I76@PURE_QUANTA.Q_CAP(CHIPS)':
 'B': CDS_PINID='B';
NODE_NAME     C1908 2
 '@S9S_MB_2U_LIB.S9S_MB_2U(SCH_1):PAGE202_I77@PURE_QUANTA.Q_CAP(CHIPS)':
 'B': CDS_PINID='B';
NODE_NAME     C1942 2
 '@S9S_MB_2U_LIB.S9S_MB_2U(SCH_1):PAGE202_I80@PURE_QUANTA.Q_CAP(CHIPS)':
 'B': CDS_PINID='B';
NODE_NAME     C1935 2
 '@S9S_MB_2U_LIB.S9S_MB_2U(SCH_1):PAGE202_I82@PURE_QUANTA.Q_CAP(CHIPS)':
 'B': CDS_PINID='B';
NODE_NAME     C1118 2
 '@S9S_MB_2U_LIB.S9S_MB_2U(SCH_1):PAGE202_I97@PURE_QUANTA.Q_CAP(CHIPS)':
 'B': CDS_PINID='B';
NODE_NAME     C1113 2
 '@S9S_MB_2U_LIB.S9S_MB_2U(SCH_1):PAGE202_I99@PURE_QUANTA.Q_CAP(CHIPS)':
 'B': CDS_PINID='B';
NODE_NAME     C1124 2
 '@S9S_MB_2U_LIB.S9S_MB_2U(SCH_1):PAGE202_I100@PURE_QUANTA.Q_CAP(CHIPS)':
 'B': CDS_PINID='B';
NODE_NAME     C1941 2
 '@S9S_MB_2U_LIB.S9S_MB_2U(SCH_1):PAGE202_I101@PURE_QUANTA.Q_CAP(CHIPS)':
 'B': CDS_PINID='B';
NODE_NAME     C1842 2
 '@S9S_MB_2U_LIB.S9S_MB_2U(SCH_1):PAGE202_I107@PURE_QUANTA.Q_CAP(CHIPS)':
 'B': CDS_PINID='B';
NODE_NAME     PC603_P0_2 2
 '@S9S_MB_2U_LIB.S9S_MB_2U(SCH_1):PAGE257_I27@PURE_QUANTA.Q_CAP(CHIPS)':
 'B': CDS_PINID='B';
NODE_NAME     PC602_P0_1 2
 '@S9S_MB_2U_LIB.S9S_MB_2U(SCH_1):PAGE257_I44@PURE_QUANTA.Q_CAP(CHIPS)':
 'B': CDS_PINID='B';
NODE_NAME     PC604_P0_1 2
 '@S9S_MB_2U_LIB.S9S_MB_2U(SCH_1):PAGE257_I45@PURE_QUANTA.Q_CAP(CHIPS)':
 'B': CDS_PINID='B';
NODE_NAME     PC723_P0_4 2
 '@S9S_MB_2U_LIB.S9S_MB_2U(SCH_1):PAGE258_I41@PURE_QUANTA.Q_CAP(CHIPS)':
 'B': CDS_PINID='B';
NODE_NAME     PC1675 2
 '@S9S_MB_2U_LIB.S9S_MB_2U(SCH_1):PAGE258_I77@PURE_QUANTA.Q_CAP(CHIPS)':
 'B': CDS_PINID='B';
NODE_NAME     C2860 2
 '@S9S_MB_2U_LIB.S9S_MB_2U(SCH_1):PAGE270_I67@PURE_QUANTA.Q_CAP(CHIPS)':
 'B': CDS_PINID='B';
NODE_NAME     PR224 2
 '@S9S_MB_2U_LIB.S9S_MB_2U(SCH_1):PAGE275_I2@PURE_QUANTA.Q_RES(CHIPS)':
 'B': CDS_PINID='B';
NODE_NAME     PU76_P1_2 2
 '@S9S_MB_2U_LIB.S9S_MB_2U(SCH_1):PAGE275_I9@PURE_QUANTA.ISL99390FRZTR5935(CHIPS)':
 'AGND': CDS_PINID='AGND';
NODE_NAME     PU76_P1_2 5
 '@S9S_MB_2U_LIB.S9S_MB_2U(SCH_1):PAGE275_I9@PURE_QUANTA.ISL99390FRZTR5935(CHIPS)':
 'PGND1': CDS_PINID='PGND1';
NODE_NAME     PU76_P1_2 7_9-20_24
 '@S9S_MB_2U_LIB.S9S_MB_2U(SCH_1):PAGE275_I9@PURE_QUANTA.ISL99390FRZTR5935(CHIPS)':
 'PGND2': CDS_PINID='PGND2';
NODE_NAME     PU76_P1_2 40
 '@S9S_MB_2U_LIB.S9S_MB_2U(SCH_1):PAGE275_I9@PURE_QUANTA.ISL99390FRZTR5935(CHIPS)':
 'PGND3': CDS_PINID='PGND3';
NODE_NAME     PC395 2
 '@S9S_MB_2U_LIB.S9S_MB_2U(SCH_1):PAGE275_I27@PURE_QUANTA.Q_CAP(CHIPS)':
 'B': CDS_PINID='B';
NODE_NAME     PC398_P1_2 2
 '@S9S_MB_2U_LIB.S9S_MB_2U(SCH_1):PAGE275_I37@PURE_QUANTA.Q_CAP(CHIPS)':
 'B': CDS_PINID='B';
NODE_NAME     PC400_P1_2 2
 '@S9S_MB_2U_LIB.S9S_MB_2U(SCH_1):PAGE275_I39@PURE_QUANTA.Q_CAP(CHIPS)':
 'B': CDS_PINID='B';
NODE_NAME     PC725_P1_2 2
 '@S9S_MB_2U_LIB.S9S_MB_2U(SCH_1):PAGE275_I46@PURE_QUANTA.Q_CAP(CHIPS)':
 'B': CDS_PINID='B';
NODE_NAME     PC397_P1_1 2
 '@S9S_MB_2U_LIB.S9S_MB_2U(SCH_1):PAGE275_I49@PURE_QUANTA.Q_CAP(CHIPS)':
 'B': CDS_PINID='B';
NODE_NAME     PC621_P1_1 2
 '@S9S_MB_2U_LIB.S9S_MB_2U(SCH_1):PAGE275_I60@PURE_QUANTA.Q_CAP(CHIPS)':
 'B': CDS_PINID='B';
NODE_NAME     PC413_P1_2 2
 '@S9S_MB_2U_LIB.S9S_MB_2U(SCH_1):PAGE275_I63@PURE_QUANTA.Q_CAP(CHIPS)':
 'B': CDS_PINID='B';
NODE_NAME     PC416 2
 '@S9S_MB_2U_LIB.S9S_MB_2U(SCH_1):PAGE275_I68@PURE_QUANTA.Q_CAPP(CHIPS)':
 'B': CDS_PINID='B';
NODE_NAME     PC1679 2
 '@S9S_MB_2U_LIB.S9S_MB_2U(SCH_1):PAGE275_I84@PURE_QUANTA.Q_CAP(CHIPS)':
 'B': CDS_PINID='B';
NODE_NAME     PC1193_P1_3 2
 '@S9S_MB_2U_LIB.S9S_MB_2U(SCH_1):PAGE276_I38@PURE_QUANTA.Q_CAP(CHIPS)':
 'B': CDS_PINID='B';
NODE_NAME     PC1199_P1_3 2
 '@S9S_MB_2U_LIB.S9S_MB_2U(SCH_1):PAGE276_I41@PURE_QUANTA.Q_CAP(CHIPS)':
 'B': CDS_PINID='B';
NODE_NAME     R4653 2
 '@S9S_MB_2U_LIB.S9S_MB_2U(SCH_1):PAGE159_I2@PURE_QUANTA.Q_RES(CHIPS)':
 'B': CDS_PINID='B';
NODE_NAME     R4647 2
 '@S9S_MB_2U_LIB.S9S_MB_2U(SCH_1):PAGE159_I4@PURE_QUANTA.Q_RES(CHIPS)':
 'B': CDS_PINID='B';
NODE_NAME     R4646 2
 '@S9S_MB_2U_LIB.S9S_MB_2U(SCH_1):PAGE159_I15@PURE_QUANTA.Q_RES(CHIPS)':
 'B': CDS_PINID='B';
NODE_NAME     R4654 2
 '@S9S_MB_2U_LIB.S9S_MB_2U(SCH_1):PAGE159_I67@PURE_QUANTA.Q_RES(CHIPS)':
 'B': CDS_PINID='B';
NODE_NAME     U328 25
 '@S9S_MB_2U_LIB.S9S_MB_2U(SCH_1):PAGE159_I95@PURE_QUANTA.DS125BR111RTWR(CHIPS)':
 'TH_GND': CDS_PINID='TH_GND';
NODE_NAME     U328 16
 '@S9S_MB_2U_LIB.S9S_MB_2U(SCH_1):PAGE159_I95@PURE_QUANTA.DS125BR111RTWR(CHIPS)':
 'VDD_SEL': CDS_PINID='VDD_SEL';
NODE_NAME     R3430 2
 '@S9S_MB_2U_LIB.S9S_MB_2U(SCH_1):PAGE299_I3@PURE_QUANTA.Q_RES(CHIPS)':
 'B': CDS_PINID='B';
NODE_NAME     R3428 2
 '@S9S_MB_2U_LIB.S9S_MB_2U(SCH_1):PAGE299_I17@PURE_QUANTA.Q_RES(CHIPS)':
 'B': CDS_PINID='B';
NODE_NAME     Q104 1
 '@S9S_MB_2U_LIB.S9S_MB_2U(SCH_1):PAGE299_I21@PURE_QUANTA.MOSFET_NCH_DUAL(CHIPS)':
 'S1': CDS_PINID='S1';
NODE_NAME     Q104 4
 '@S9S_MB_2U_LIB.S9S_MB_2U(SCH_1):PAGE299_I26@PURE_QUANTA.MOSFET_NCH_DUAL(CHIPS)':
 'S2': CDS_PINID='S2';
NODE_NAME     C1976 2
 '@S9S_MB_2U_LIB.S9S_MB_2U(SCH_1):PAGE299_I30@PURE_QUANTA.Q_CAP(CHIPS)':
 'B': CDS_PINID='B';
NODE_NAME     Q103 1
 '@S9S_MB_2U_LIB.S9S_MB_2U(SCH_1):PAGE299_I37@PURE_QUANTA.MOSFET_NCH_DUAL(CHIPS)':
 'S1': CDS_PINID='S1';
NODE_NAME     Q102 1
 '@S9S_MB_2U_LIB.S9S_MB_2U(SCH_1):PAGE299_I40@PURE_QUANTA.MOSFET_NCH_DUAL(CHIPS)':
 'S1': CDS_PINID='S1';
NODE_NAME     Q103 4
 '@S9S_MB_2U_LIB.S9S_MB_2U(SCH_1):PAGE299_I43@PURE_QUANTA.MOSFET_NCH_DUAL(CHIPS)':
 'S2': CDS_PINID='S2';
NODE_NAME     Q102 4
 '@S9S_MB_2U_LIB.S9S_MB_2U(SCH_1):PAGE299_I48@PURE_QUANTA.MOSFET_NCH_DUAL(CHIPS)':
 'S2': CDS_PINID='S2';
NODE_NAME     Q101 1
 '@S9S_MB_2U_LIB.S9S_MB_2U(SCH_1):PAGE299_I52@PURE_QUANTA.MOSFET_NCH_DUAL(CHIPS)':
 'S1': CDS_PINID='S1';
NODE_NAME     Q101 4
 '@S9S_MB_2U_LIB.S9S_MB_2U(SCH_1):PAGE299_I57@PURE_QUANTA.MOSFET_NCH_DUAL(CHIPS)':
 'S2': CDS_PINID='S2';
NODE_NAME     C1973 2
 '@S9S_MB_2U_LIB.S9S_MB_2U(SCH_1):PAGE299_I71@PURE_QUANTA.Q_CAP(CHIPS)':
 'B': CDS_PINID='B';
NODE_NAME     C1974 2
 '@S9S_MB_2U_LIB.S9S_MB_2U(SCH_1):PAGE299_I74@PURE_QUANTA.Q_CAP(CHIPS)':
 'B': CDS_PINID='B';
NODE_NAME     C1975 2
 '@S9S_MB_2U_LIB.S9S_MB_2U(SCH_1):PAGE299_I129@PURE_QUANTA.Q_CAP(CHIPS)':
 'B': CDS_PINID='B';
NODE_NAME     U253 2
 '@S9S_MB_2U_LIB.S9S_MB_2U(SCH_1):PAGE160_I26@PURE_QUANTA.74LVC2G17GW(CHIPS)':
 'GND': CDS_PINID='GND';
NODE_NAME     C1958 2
 '@S9S_MB_2U_LIB.S9S_MB_2U(SCH_1):PAGE160_I29@PURE_QUANTA.Q_CAP(CHIPS)':
 'B': CDS_PINID='B';
NODE_NAME     R3443 2
 '@S9S_MB_2U_LIB.S9S_MB_2U(SCH_1):PAGE147_I5@PURE_QUANTA.Q_RES(CHIPS)':
 'B': CDS_PINID='B';
NODE_NAME     R3440 2
 '@S9S_MB_2U_LIB.S9S_MB_2U(SCH_1):PAGE147_I8@PURE_QUANTA.Q_RES(CHIPS)':
 'B': CDS_PINID='B';
NODE_NAME     R2656 2
 '@S9S_MB_2U_LIB.S9S_MB_2U(SCH_1):PAGE147_I11@PURE_QUANTA.Q_RES(CHIPS)':
 'B': CDS_PINID='B';
NODE_NAME     R3452 2
 '@S9S_MB_2U_LIB.S9S_MB_2U(SCH_1):PAGE160_I95@PURE_QUANTA.Q_RES(CHIPS)':
 'B': CDS_PINID='B';
NODE_NAME     R3457 2
 '@S9S_MB_2U_LIB.S9S_MB_2U(SCH_1):PAGE160_I123@PURE_QUANTA.Q_RES(CHIPS)':
 'B': CDS_PINID='B';
NODE_NAME     R3463 2
 '@S9S_MB_2U_LIB.S9S_MB_2U(SCH_1):PAGE299_I131@PURE_QUANTA.Q_RES(CHIPS)':
 'B': CDS_PINID='B';
NODE_NAME     R3431 2
 '@S9S_MB_2U_LIB.S9S_MB_2U(SCH_1):PAGE299_I133@PURE_QUANTA.Q_RES(CHIPS)':
 'B': CDS_PINID='B';
NODE_NAME     R3455 2
 '@S9S_MB_2U_LIB.S9S_MB_2U(SCH_1):PAGE160_I139@PURE_QUANTA.Q_RES(CHIPS)':
 'B': CDS_PINID='B';
NODE_NAME     C1957 2
 '@S9S_MB_2U_LIB.S9S_MB_2U(SCH_1):PAGE160_I148@PURE_QUANTA.Q_CAP(CHIPS)':
 'B': CDS_PINID='B';
NODE_NAME     U252 2
 '@S9S_MB_2U_LIB.S9S_MB_2U(SCH_1):PAGE160_I153@PURE_QUANTA.74LVC2G17GW(CHIPS)':
 'GND': CDS_PINID='GND';
NODE_NAME     C1963 2
 '@S9S_MB_2U_LIB.S9S_MB_2U(SCH_1):PAGE296_I13@PURE_QUANTA.Q_CAP(CHIPS)':
 'B': CDS_PINID='B';
NODE_NAME     U255 2
 '@S9S_MB_2U_LIB.S9S_MB_2U(SCH_1):PAGE296_I16@PURE_QUANTA.74LVC2G07DW7(CHIPS)':
 'GND': CDS_PINID='GND';
NODE_NAME     R3460 2
 '@S9S_MB_2U_LIB.S9S_MB_2U(SCH_1):PAGE296_I31@PURE_QUANTA.Q_RES(CHIPS)':
 'B': CDS_PINID='B';
NODE_NAME     R3462 2
 '@S9S_MB_2U_LIB.S9S_MB_2U(SCH_1):PAGE296_I33@PURE_QUANTA.Q_RES(CHIPS)':
 'B': CDS_PINID='B';
NODE_NAME     Q105 1
 '@S9S_MB_2U_LIB.S9S_MB_2U(SCH_1):PAGE304_I76@PURE_QUANTA.MOSFET_NCH_DUAL(CHIPS)':
 'S1': CDS_PINID='S1';
NODE_NAME     R3454 2
 '@S9S_MB_2U_LIB.S9S_MB_2U(SCH_1):PAGE160_I165@PURE_QUANTA.Q_RES(CHIPS)':
 'B': CDS_PINID='B';
NODE_NAME     R3449 2
 '@S9S_MB_2U_LIB.S9S_MB_2U(SCH_1):PAGE160_I170@PURE_QUANTA.Q_RES(CHIPS)':
 'B': CDS_PINID='B';
NODE_NAME     U256 2
 '@S9S_MB_2U_LIB.S9S_MB_2U(SCH_1):PAGE160_I173@PURE_QUANTA.74LVC2G17GW(CHIPS)':
 'GND': CDS_PINID='GND';
NODE_NAME     C1977 2
 '@S9S_MB_2U_LIB.S9S_MB_2U(SCH_1):PAGE160_I175@PURE_QUANTA.Q_CAP(CHIPS)':
 'B': CDS_PINID='B';
NODE_NAME     R3467 2
 '@S9S_MB_2U_LIB.S9S_MB_2U(SCH_1):PAGE160_I181@PURE_QUANTA.Q_RES(CHIPS)':
 'B': CDS_PINID='B';
NODE_NAME     R3466 2
 '@S9S_MB_2U_LIB.S9S_MB_2U(SCH_1):PAGE160_I184@PURE_QUANTA.Q_RES(CHIPS)':
 'B': CDS_PINID='B';
NODE_NAME     Q106 1
 '@S9S_MB_2U_LIB.S9S_MB_2U(SCH_1):PAGE299_I135@PURE_QUANTA.MOSFET_NCH_DUAL(CHIPS)':
 'S1': CDS_PINID='S1';
NODE_NAME     R3471 2
 '@S9S_MB_2U_LIB.S9S_MB_2U(SCH_1):PAGE299_I144@PURE_QUANTA.Q_RES(CHIPS)':
 'B': CDS_PINID='B';
NODE_NAME     R3472 1
 '@S9S_MB_2U_LIB.S9S_MB_2U(SCH_1):PAGE299_I147@PURE_QUANTA.Q_RES(CHIPS)':
 'A': CDS_PINID='A';
NODE_NAME     C1978 2
 '@S9S_MB_2U_LIB.S9S_MB_2U(SCH_1):PAGE299_I152@PURE_QUANTA.Q_CAP(CHIPS)':
 'B': CDS_PINID='B';
NODE_NAME     Q107 4
 '@S9S_MB_2U_LIB.S9S_MB_2U(SCH_1):PAGE299_I157@PURE_QUANTA.MOSFET_NCH_DUAL(CHIPS)':
 'S2': CDS_PINID='S2';
NODE_NAME     Q107 1
 '@S9S_MB_2U_LIB.S9S_MB_2U(SCH_1):PAGE299_I160@PURE_QUANTA.MOSFET_NCH_DUAL(CHIPS)':
 'S1': CDS_PINID='S1';
NODE_NAME     R3473 2
 '@S9S_MB_2U_LIB.S9S_MB_2U(SCH_1):PAGE299_I163@PURE_QUANTA.Q_RES(CHIPS)':
 'B': CDS_PINID='B';
NODE_NAME     R3489 2
 '@S9S_MB_2U_LIB.S9S_MB_2U(SCH_1):PAGE296_I42@PURE_QUANTA.Q_RES(CHIPS)':
 'B': CDS_PINID='B';
NODE_NAME     R3493 2
 '@S9S_MB_2U_LIB.S9S_MB_2U(SCH_1):PAGE296_I48@PURE_QUANTA.Q_RES(CHIPS)':
 'B': CDS_PINID='B';
NODE_NAME     U257 3
 '@S9S_MB_2U_LIB.S9S_MB_2U(SCH_1):PAGE296_I50@PURE_QUANTA.74LVC2G07DW7(CHIPS)':
 '2A': CDS_PINID='\2a\';
NODE_NAME     U257 2
 '@S9S_MB_2U_LIB.S9S_MB_2U(SCH_1):PAGE296_I50@PURE_QUANTA.74LVC2G07DW7(CHIPS)':
 'GND': CDS_PINID='GND';
NODE_NAME     R3495 2
 '@S9S_MB_2U_LIB.S9S_MB_2U(SCH_1):PAGE296_I62@PURE_QUANTA.Q_RES(CHIPS)':
 'B': CDS_PINID='B';
NODE_NAME     C1979 2
 '@S9S_MB_2U_LIB.S9S_MB_2U(SCH_1):PAGE296_I67@PURE_QUANTA.Q_CAP(CHIPS)':
 'B': CDS_PINID='B';
NODE_NAME     R3491 2
 '@S9S_MB_2U_LIB.S9S_MB_2U(SCH_1):PAGE296_I70@PURE_QUANTA.Q_RES(CHIPS)':
 'B': CDS_PINID='B';
NODE_NAME     R3511 2
 '@S9S_MB_2U_LIB.S9S_MB_2U(SCH_1):PAGE145_I172@PURE_QUANTA.Q_RES(CHIPS)':
 'B': CDS_PINID='B';
NODE_NAME     R3513 2
 '@S9S_MB_2U_LIB.S9S_MB_2U(SCH_1):PAGE145_I173@PURE_QUANTA.Q_RES(CHIPS)':
 'B': CDS_PINID='B';
NODE_NAME     R3509 2
 '@S9S_MB_2U_LIB.S9S_MB_2U(SCH_1):PAGE140_I191@PURE_QUANTA.Q_RES(CHIPS)':
 'B': CDS_PINID='B';
NODE_NAME     R3507 2
 '@S9S_MB_2U_LIB.S9S_MB_2U(SCH_1):PAGE140_I192@PURE_QUANTA.Q_RES(CHIPS)':
 'B': CDS_PINID='B';
NODE_NAME     R3508 2
 '@S9S_MB_2U_LIB.S9S_MB_2U(SCH_1):PAGE140_I194@PURE_QUANTA.Q_RES(CHIPS)':
 'B': CDS_PINID='B';
NODE_NAME     Q108 4
 '@S9S_MB_2U_LIB.S9S_MB_2U(SCH_1):PAGE299_I168@PURE_QUANTA.MOSFET_NCH_DUAL(CHIPS)':
 'S2': CDS_PINID='S2';
NODE_NAME     Q108 1
 '@S9S_MB_2U_LIB.S9S_MB_2U(SCH_1):PAGE299_I169@PURE_QUANTA.MOSFET_NCH_DUAL(CHIPS)':
 'S1': CDS_PINID='S1';
NODE_NAME     C1988 2
 '@S9S_MB_2U_LIB.S9S_MB_2U(SCH_1):PAGE299_I171@PURE_QUANTA.Q_CAP(CHIPS)':
 'B': CDS_PINID='B';
NODE_NAME     R3502 2
 '@S9S_MB_2U_LIB.S9S_MB_2U(SCH_1):PAGE299_I181@PURE_QUANTA.Q_RES(CHIPS)':
 'B': CDS_PINID='B';
NODE_NAME     R2918 2
 '@S9S_MB_2U_LIB.S9S_MB_2U(SCH_1):PAGE160_I188@PURE_QUANTA.Q_RES(CHIPS)':
 'B': CDS_PINID='B';
NODE_NAME     R2932 2
 '@S9S_MB_2U_LIB.S9S_MB_2U(SCH_1):PAGE160_I195@PURE_QUANTA.Q_RES(CHIPS)':
 'B': CDS_PINID='B';
NODE_NAME     C1998 2
 '@S9S_MB_2U_LIB.S9S_MB_2U(SCH_1):PAGE183_I82@PURE_QUANTA.Q_CAP(CHIPS)':
 'B': CDS_PINID='B';
NODE_NAME     C1997 2
 '@S9S_MB_2U_LIB.S9S_MB_2U(SCH_1):PAGE183_I89@PURE_QUANTA.Q_CAP(CHIPS)':
 'B': CDS_PINID='B';
NODE_NAME     U268 TH
 '@S9S_MB_2U_LIB.S9S_MB_2U(SCH_1):PAGE155_I100@PURE_QUANTA.GL852GOHY60(CHIPS)':
 'TH': CDS_PINID='TH';
NODE_NAME     C2018 2
 '@S9S_MB_2U_LIB.S9S_MB_2U(SCH_1):PAGE163_I26@PURE_QUANTA.Q_CAP(CHIPS)':
 'B': CDS_PINID='B';
NODE_NAME     R3611 1
 '@S9S_MB_2U_LIB.S9S_MB_2U(SCH_1):PAGE163_I36@PURE_QUANTA.Q_RES(CHIPS)':
 'A': CDS_PINID='A';
NODE_NAME     C2013 2
 '@S9S_MB_2U_LIB.S9S_MB_2U(SCH_1):PAGE163_I42@PURE_QUANTA.Q_CAP(CHIPS)':
 'B': CDS_PINID='B';
NODE_NAME     R3610 1
 '@S9S_MB_2U_LIB.S9S_MB_2U(SCH_1):PAGE163_I45@PURE_QUANTA.Q_RES(CHIPS)':
 'A': CDS_PINID='A';
NODE_NAME     U264 10
 '@S9S_MB_2U_LIB.S9S_MB_2U(SCH_1):PAGE163_I46@PURE_QUANTA.INA230AIRGTR(CHIPS)':
 'GND': CDS_PINID='GND';
NODE_NAME     U264 TH
 '@S9S_MB_2U_LIB.S9S_MB_2U(SCH_1):PAGE163_I46@PURE_QUANTA.INA230AIRGTR(CHIPS)':
 'TH': CDS_PINID='TH';
NODE_NAME     C2019 2
 '@S9S_MB_2U_LIB.S9S_MB_2U(SCH_1):PAGE163_I49@PURE_QUANTA.Q_CAP(CHIPS)':
 'B': CDS_PINID='B';
NODE_NAME     R3613 1
 '@S9S_MB_2U_LIB.S9S_MB_2U(SCH_1):PAGE163_I59@PURE_QUANTA.Q_RES(CHIPS)':
 'A': CDS_PINID='A';
NODE_NAME     C2014 2
 '@S9S_MB_2U_LIB.S9S_MB_2U(SCH_1):PAGE163_I65@PURE_QUANTA.Q_CAP(CHIPS)':
 'B': CDS_PINID='B';
NODE_NAME     R3612 1
 '@S9S_MB_2U_LIB.S9S_MB_2U(SCH_1):PAGE163_I68@PURE_QUANTA.Q_RES(CHIPS)':
 'A': CDS_PINID='A';
NODE_NAME     U265 10
 '@S9S_MB_2U_LIB.S9S_MB_2U(SCH_1):PAGE163_I69@PURE_QUANTA.INA230AIRGTR(CHIPS)':
 'GND': CDS_PINID='GND';
NODE_NAME     U265 TH
 '@S9S_MB_2U_LIB.S9S_MB_2U(SCH_1):PAGE163_I69@PURE_QUANTA.INA230AIRGTR(CHIPS)':
 'TH': CDS_PINID='TH';
NODE_NAME     U266 10
 '@S9S_MB_2U_LIB.S9S_MB_2U(SCH_1):PAGE295_I30@PURE_QUANTA.INA230AIRGTR(CHIPS)':
 'GND': CDS_PINID='GND';
NODE_NAME     U266 TH
 '@S9S_MB_2U_LIB.S9S_MB_2U(SCH_1):PAGE295_I30@PURE_QUANTA.INA230AIRGTR(CHIPS)':
 'TH': CDS_PINID='TH';
NODE_NAME     R3616 1
 '@S9S_MB_2U_LIB.S9S_MB_2U(SCH_1):PAGE295_I31@PURE_QUANTA.Q_RES(CHIPS)':
 'A': CDS_PINID='A';
NODE_NAME     C2015 2
 '@S9S_MB_2U_LIB.S9S_MB_2U(SCH_1):PAGE295_I34@PURE_QUANTA.Q_CAP(CHIPS)':
 'B': CDS_PINID='B';
NODE_NAME     R3617 1
 '@S9S_MB_2U_LIB.S9S_MB_2U(SCH_1):PAGE295_I40@PURE_QUANTA.Q_RES(CHIPS)':
 'A': CDS_PINID='A';
NODE_NAME     C2024 2
 '@S9S_MB_2U_LIB.S9S_MB_2U(SCH_1):PAGE295_I50@PURE_QUANTA.Q_CAP(CHIPS)':
 'B': CDS_PINID='B';
NODE_NAME     PC2147 1
 '@S9S_MB_2U_LIB.S9S_MB_2U(SCH_1):PAGE131_I87@PURE_QUANTA.Q_CAP(CHIPS)':
 'A': CDS_PINID='A';
NODE_NAME     R3653 2
 '@S9S_MB_2U_LIB.S9S_MB_2U(SCH_1):PAGE155_I139@PURE_QUANTA.Q_RES(CHIPS)':
 'B': CDS_PINID='B';
NODE_NAME     C2034 2
 '@S9S_MB_2U_LIB.S9S_MB_2U(SCH_1):PAGE155_I142@PURE_QUANTA.Q_CAP(CHIPS)':
 'B': CDS_PINID='B';
NODE_NAME     C2033 2
 '@S9S_MB_2U_LIB.S9S_MB_2U(SCH_1):PAGE155_I143@PURE_QUANTA.Q_CAP(CHIPS)':
 'B': CDS_PINID='B';
NODE_NAME     C2032 2
 '@S9S_MB_2U_LIB.S9S_MB_2U(SCH_1):PAGE155_I145@PURE_QUANTA.Q_CAP(CHIPS)':
 'B': CDS_PINID='B';
NODE_NAME     C2035 2
 '@S9S_MB_2U_LIB.S9S_MB_2U(SCH_1):PAGE155_I147@PURE_QUANTA.Q_CAP(CHIPS)':
 'B': CDS_PINID='B';
NODE_NAME     C2031 2
 '@S9S_MB_2U_LIB.S9S_MB_2U(SCH_1):PAGE155_I148@PURE_QUANTA.Q_CAP(CHIPS)':
 'B': CDS_PINID='B';
NODE_NAME     C2041 2
 '@S9S_MB_2U_LIB.S9S_MB_2U(SCH_1):PAGE155_I158@PURE_QUANTA.Q_CAP(CHIPS)':
 'B': CDS_PINID='B';
NODE_NAME     C2040 2
 '@S9S_MB_2U_LIB.S9S_MB_2U(SCH_1):PAGE155_I162@PURE_QUANTA.Q_CAP(CHIPS)':
 'B': CDS_PINID='B';
NODE_NAME     C2039 2
 '@S9S_MB_2U_LIB.S9S_MB_2U(SCH_1):PAGE155_I163@PURE_QUANTA.Q_CAP(CHIPS)':
 'B': CDS_PINID='B';
NODE_NAME     C2038 2
 '@S9S_MB_2U_LIB.S9S_MB_2U(SCH_1):PAGE155_I164@PURE_QUANTA.Q_CAP(CHIPS)':
 'B': CDS_PINID='B';
NODE_NAME     R3665 2
 '@S9S_MB_2U_LIB.S9S_MB_2U(SCH_1):PAGE155_I182@PURE_QUANTA.Q_RES(CHIPS)':
 'B': CDS_PINID='B';
NODE_NAME     R3664 2
 '@S9S_MB_2U_LIB.S9S_MB_2U(SCH_1):PAGE155_I187@PURE_QUANTA.Q_RES(CHIPS)':
 'B': CDS_PINID='B';
NODE_NAME     R3666 2
 '@S9S_MB_2U_LIB.S9S_MB_2U(SCH_1):PAGE155_I199@PURE_QUANTA.Q_RES(CHIPS)':
 'B': CDS_PINID='B';
NODE_NAME     U269 4
 '@S9S_MB_2U_LIB.S9S_MB_2U(SCH_1):PAGE239_I103@PURE_QUANTA.ADC128D818CIMTXNOPB(CHIPS)':
 'GND': CDS_PINID='GND';
NODE_NAME     C2051 2
 '@S9S_MB_2U_LIB.S9S_MB_2U(SCH_1):PAGE239_I127@PURE_QUANTA.Q_CAP(CHIPS)':
 'B': CDS_PINID='B';
NODE_NAME     C2052 2
 '@S9S_MB_2U_LIB.S9S_MB_2U(SCH_1):PAGE239_I128@PURE_QUANTA.Q_CAP(CHIPS)':
 'B': CDS_PINID='B';
NODE_NAME     R3690 2
 '@S9S_MB_2U_LIB.S9S_MB_2U(SCH_1):PAGE239_I131@PURE_QUANTA.Q_RES(CHIPS)':
 'B': CDS_PINID='B';
NODE_NAME     R1785 2
 '@S9S_MB_2U_LIB.S9S_MB_2U(SCH_1):PAGE239_I149@PURE_QUANTA.Q_RES(CHIPS)':
 'B': CDS_PINID='B';
NODE_NAME     R2843 2
 '@S9S_MB_2U_LIB.S9S_MB_2U(SCH_1):PAGE239_I162@PURE_QUANTA.Q_RES(CHIPS)':
 'B': CDS_PINID='B';
NODE_NAME     R1791 2
 '@S9S_MB_2U_LIB.S9S_MB_2U(SCH_1):PAGE239_I163@PURE_QUANTA.Q_RES(CHIPS)':
 'B': CDS_PINID='B';
NODE_NAME     R1800 2
 '@S9S_MB_2U_LIB.S9S_MB_2U(SCH_1):PAGE239_I174@PURE_QUANTA.Q_RES(CHIPS)':
 'B': CDS_PINID='B';
NODE_NAME     C2042 2
 '@S9S_MB_2U_LIB.S9S_MB_2U(SCH_1):PAGE239_I180@PURE_QUANTA.Q_CAP(CHIPS)':
 'B': CDS_PINID='B';
NODE_NAME     C2047 2
 '@S9S_MB_2U_LIB.S9S_MB_2U(SCH_1):PAGE239_I181@PURE_QUANTA.Q_CAP(CHIPS)':
 'B': CDS_PINID='B';
NODE_NAME     C2044 2
 '@S9S_MB_2U_LIB.S9S_MB_2U(SCH_1):PAGE239_I187@PURE_QUANTA.Q_CAP(CHIPS)':
 'B': CDS_PINID='B';
NODE_NAME     C2049 2
 '@S9S_MB_2U_LIB.S9S_MB_2U(SCH_1):PAGE239_I188@PURE_QUANTA.Q_CAP(CHIPS)':
 'B': CDS_PINID='B';
NODE_NAME     C2043 2
 '@S9S_MB_2U_LIB.S9S_MB_2U(SCH_1):PAGE239_I196@PURE_QUANTA.Q_CAP(CHIPS)':
 'B': CDS_PINID='B';
NODE_NAME     C2048 2
 '@S9S_MB_2U_LIB.S9S_MB_2U(SCH_1):PAGE239_I197@PURE_QUANTA.Q_CAP(CHIPS)':
 'B': CDS_PINID='B';
NODE_NAME     C1344 2
 '@S9S_MB_2U_LIB.S9S_MB_2U(SCH_1):PAGE239_I205@PURE_QUANTA.Q_CAP(CHIPS)':
 'B': CDS_PINID='B';
NODE_NAME     C2046 2
 '@S9S_MB_2U_LIB.S9S_MB_2U(SCH_1):PAGE239_I207@PURE_QUANTA.Q_CAP(CHIPS)':
 'B': CDS_PINID='B';
NODE_NAME     R3668 2
 '@S9S_MB_2U_LIB.S9S_MB_2U(SCH_1):PAGE239_I223@PURE_QUANTA.Q_RES(CHIPS)':
 'B': CDS_PINID='B';
NODE_NAME     R3670 2
 '@S9S_MB_2U_LIB.S9S_MB_2U(SCH_1):PAGE239_I227@PURE_QUANTA.Q_RES(CHIPS)':
 'B': CDS_PINID='B';
NODE_NAME     C2045 2
 '@S9S_MB_2U_LIB.S9S_MB_2U(SCH_1):PAGE239_I236@PURE_QUANTA.Q_CAP(CHIPS)':
 'B': CDS_PINID='B';
NODE_NAME     C2050 2
 '@S9S_MB_2U_LIB.S9S_MB_2U(SCH_1):PAGE239_I238@PURE_QUANTA.Q_CAP(CHIPS)':
 'B': CDS_PINID='B';
NODE_NAME     C2010 2
 '@S9S_MB_2U_LIB.S9S_MB_2U(SCH_1):PAGE161_I16@PURE_QUANTA.Q_CAP(CHIPS)':
 'B': CDS_PINID='B';
NODE_NAME     R3704 2
 '@S9S_MB_2U_LIB.S9S_MB_2U(SCH_1):PAGE221_I2@PURE_QUANTA.Q_RES(CHIPS)':
 'B': CDS_PINID='B';
NODE_NAME     R3707 2
 '@S9S_MB_2U_LIB.S9S_MB_2U(SCH_1):PAGE221_I6@PURE_QUANTA.Q_RES(CHIPS)':
 'B': CDS_PINID='B';
NODE_NAME     R3709 2
 '@S9S_MB_2U_LIB.S9S_MB_2U(SCH_1):PAGE221_I8@PURE_QUANTA.Q_RES(CHIPS)':
 'B': CDS_PINID='B';
NODE_NAME     C2067 2
 '@S9S_MB_2U_LIB.S9S_MB_2U(SCH_1):PAGE295_I125@PURE_QUANTA.Q_CAP(CHIPS)':
 'B': CDS_PINID='B';
NODE_NAME     U276 10
 '@S9S_MB_2U_LIB.S9S_MB_2U(SCH_1):PAGE295_I129@PURE_QUANTA.INA230AIRGTR(CHIPS)':
 'GND': CDS_PINID='GND';
NODE_NAME     U276 TH
 '@S9S_MB_2U_LIB.S9S_MB_2U(SCH_1):PAGE295_I129@PURE_QUANTA.INA230AIRGTR(CHIPS)':
 'TH': CDS_PINID='TH';
NODE_NAME     R3764 1
 '@S9S_MB_2U_LIB.S9S_MB_2U(SCH_1):PAGE295_I135@PURE_QUANTA.Q_RES(CHIPS)':
 'A': CDS_PINID='A';
NODE_NAME     R3763 1
 '@S9S_MB_2U_LIB.S9S_MB_2U(SCH_1):PAGE295_I136@PURE_QUANTA.Q_RES(CHIPS)':
 'A': CDS_PINID='A';
NODE_NAME     C2069 2
 '@S9S_MB_2U_LIB.S9S_MB_2U(SCH_1):PAGE295_I142@PURE_QUANTA.Q_CAP(CHIPS)':
 'B': CDS_PINID='B';
NODE_NAME     U263 10
 '@S9S_MB_2U_LIB.S9S_MB_2U(SCH_1):PAGE163_I94@PURE_QUANTA.INA230AIRGTR(CHIPS)':
 'GND': CDS_PINID='GND';
NODE_NAME     U263 TH
 '@S9S_MB_2U_LIB.S9S_MB_2U(SCH_1):PAGE163_I94@PURE_QUANTA.INA230AIRGTR(CHIPS)':
 'TH': CDS_PINID='TH';
NODE_NAME     C2012 2
 '@S9S_MB_2U_LIB.S9S_MB_2U(SCH_1):PAGE163_I98@PURE_QUANTA.Q_CAP(CHIPS)':
 'B': CDS_PINID='B';
NODE_NAME     R3608 1
 '@S9S_MB_2U_LIB.S9S_MB_2U(SCH_1):PAGE163_I103@PURE_QUANTA.Q_RES(CHIPS)':
 'A': CDS_PINID='A';
NODE_NAME     R3609 1
 '@S9S_MB_2U_LIB.S9S_MB_2U(SCH_1):PAGE163_I104@PURE_QUANTA.Q_RES(CHIPS)':
 'A': CDS_PINID='A';
NODE_NAME     C2017 2
 '@S9S_MB_2U_LIB.S9S_MB_2U(SCH_1):PAGE163_I114@PURE_QUANTA.Q_CAP(CHIPS)':
 'B': CDS_PINID='B';
NODE_NAME     J37 G1
 '@S9S_MB_2U_LIB.S9S_MB_2U(SCH_1):PAGE150_I199@PURE_QUANTA.SCONN168_ME1016810202011(CHIPS)':
 'G1': CDS_PINID='G1';
NODE_NAME     J37 G2
 '@S9S_MB_2U_LIB.S9S_MB_2U(SCH_1):PAGE150_I199@PURE_QUANTA.SCONN168_ME1016810202011(CHIPS)':
 'G2': CDS_PINID='G2';
NODE_NAME     J37 G3
 '@S9S_MB_2U_LIB.S9S_MB_2U(SCH_1):PAGE150_I199@PURE_QUANTA.SCONN168_ME1016810202011(CHIPS)':
 'G3': CDS_PINID='G3';
NODE_NAME     J37 G4
 '@S9S_MB_2U_LIB.S9S_MB_2U(SCH_1):PAGE150_I199@PURE_QUANTA.SCONN168_ME1016810202011(CHIPS)':
 'G4': CDS_PINID='G4';
NODE_NAME     J37 G5
 '@S9S_MB_2U_LIB.S9S_MB_2U(SCH_1):PAGE150_I199@PURE_QUANTA.SCONN168_ME1016810202011(CHIPS)':
 'G5': CDS_PINID='G5';
NODE_NAME     J37 A1
 '@S9S_MB_2U_LIB.S9S_MB_2U(SCH_1):PAGE150_I199@PURE_QUANTA.SCONN168_ME1016810202011(CHIPS)':
 'GND_A1': CDS_PINID='GND_A1';
NODE_NAME     J37 A2
 '@S9S_MB_2U_LIB.S9S_MB_2U(SCH_1):PAGE150_I199@PURE_QUANTA.SCONN168_ME1016810202011(CHIPS)':
 'GND_A2': CDS_PINID='GND_A2';
NODE_NAME     J37 A3
 '@S9S_MB_2U_LIB.S9S_MB_2U(SCH_1):PAGE150_I199@PURE_QUANTA.SCONN168_ME1016810202011(CHIPS)':
 'GND_A3': CDS_PINID='GND_A3';
NODE_NAME     J37 A4
 '@S9S_MB_2U_LIB.S9S_MB_2U(SCH_1):PAGE150_I199@PURE_QUANTA.SCONN168_ME1016810202011(CHIPS)':
 'GND_A4': CDS_PINID='GND_A4';
NODE_NAME     J37 A5
 '@S9S_MB_2U_LIB.S9S_MB_2U(SCH_1):PAGE150_I199@PURE_QUANTA.SCONN168_ME1016810202011(CHIPS)':
 'GND_A5': CDS_PINID='GND_A5';
NODE_NAME     J37 A6
 '@S9S_MB_2U_LIB.S9S_MB_2U(SCH_1):PAGE150_I199@PURE_QUANTA.SCONN168_ME1016810202011(CHIPS)':
 'GND_A6': CDS_PINID='GND_A6';
NODE_NAME     J37 A13
 '@S9S_MB_2U_LIB.S9S_MB_2U(SCH_1):PAGE150_I199@PURE_QUANTA.SCONN168_ME1016810202011(CHIPS)':
 'GND_A13': CDS_PINID='GND_A13';
NODE_NAME     J37 A16
 '@S9S_MB_2U_LIB.S9S_MB_2U(SCH_1):PAGE150_I199@PURE_QUANTA.SCONN168_ME1016810202011(CHIPS)':
 'GND_A16': CDS_PINID='GND_A16';
NODE_NAME     J37 A19
 '@S9S_MB_2U_LIB.S9S_MB_2U(SCH_1):PAGE150_I199@PURE_QUANTA.SCONN168_ME1016810202011(CHIPS)':
 'GND_A19': CDS_PINID='GND_A19';
NODE_NAME     J37 A22
 '@S9S_MB_2U_LIB.S9S_MB_2U(SCH_1):PAGE150_I199@PURE_QUANTA.SCONN168_ME1016810202011(CHIPS)':
 'GND_A22': CDS_PINID='GND_A22';
NODE_NAME     J37 A25
 '@S9S_MB_2U_LIB.S9S_MB_2U(SCH_1):PAGE150_I199@PURE_QUANTA.SCONN168_ME1016810202011(CHIPS)':
 'GND_A25': CDS_PINID='GND_A25';
NODE_NAME     J37 A28
 '@S9S_MB_2U_LIB.S9S_MB_2U(SCH_1):PAGE150_I199@PURE_QUANTA.SCONN168_ME1016810202011(CHIPS)':
 'GND_A28': CDS_PINID='GND_A28';
NODE_NAME     J37 A29
 '@S9S_MB_2U_LIB.S9S_MB_2U(SCH_1):PAGE150_I199@PURE_QUANTA.SCONN168_ME1016810202011(CHIPS)':
 'GND_A29': CDS_PINID='GND_A29';
NODE_NAME     J37 A32
 '@S9S_MB_2U_LIB.S9S_MB_2U(SCH_1):PAGE150_I199@PURE_QUANTA.SCONN168_ME1016810202011(CHIPS)':
 'GND_A32': CDS_PINID='GND_A32';
NODE_NAME     J37 A35
 '@S9S_MB_2U_LIB.S9S_MB_2U(SCH_1):PAGE150_I199@PURE_QUANTA.SCONN168_ME1016810202011(CHIPS)':
 'GND_A35': CDS_PINID='GND_A35';
NODE_NAME     J37 A38
 '@S9S_MB_2U_LIB.S9S_MB_2U(SCH_1):PAGE150_I199@PURE_QUANTA.SCONN168_ME1016810202011(CHIPS)':
 'GND_A38': CDS_PINID='GND_A38';
NODE_NAME     J37 A41
 '@S9S_MB_2U_LIB.S9S_MB_2U(SCH_1):PAGE150_I199@PURE_QUANTA.SCONN168_ME1016810202011(CHIPS)':
 'GND_A41': CDS_PINID='GND_A41';
NODE_NAME     J37 A43
 '@S9S_MB_2U_LIB.S9S_MB_2U(SCH_1):PAGE150_I199@PURE_QUANTA.SCONN168_ME1016810202011(CHIPS)':
 'GND_A43': CDS_PINID='GND_A43';
NODE_NAME     J37 A46
 '@S9S_MB_2U_LIB.S9S_MB_2U(SCH_1):PAGE150_I199@PURE_QUANTA.SCONN168_ME1016810202011(CHIPS)':
 'GND_A46': CDS_PINID='GND_A46';
NODE_NAME     J37 A49
 '@S9S_MB_2U_LIB.S9S_MB_2U(SCH_1):PAGE150_I199@PURE_QUANTA.SCONN168_ME1016810202011(CHIPS)':
 'GND_A49': CDS_PINID='GND_A49';
NODE_NAME     J37 A52
 '@S9S_MB_2U_LIB.S9S_MB_2U(SCH_1):PAGE150_I199@PURE_QUANTA.SCONN168_ME1016810202011(CHIPS)':
 'GND_A52': CDS_PINID='GND_A52';
NODE_NAME     J37 A55
 '@S9S_MB_2U_LIB.S9S_MB_2U(SCH_1):PAGE150_I199@PURE_QUANTA.SCONN168_ME1016810202011(CHIPS)':
 'GND_A55': CDS_PINID='GND_A55';
NODE_NAME     J37 A58
 '@S9S_MB_2U_LIB.S9S_MB_2U(SCH_1):PAGE150_I199@PURE_QUANTA.SCONN168_ME1016810202011(CHIPS)':
 'GND_A58': CDS_PINID='GND_A58';
NODE_NAME     J37 A61
 '@S9S_MB_2U_LIB.S9S_MB_2U(SCH_1):PAGE150_I199@PURE_QUANTA.SCONN168_ME1016810202011(CHIPS)':
 'GND_A61': CDS_PINID='GND_A61';
NODE_NAME     J37 A64
 '@S9S_MB_2U_LIB.S9S_MB_2U(SCH_1):PAGE150_I199@PURE_QUANTA.SCONN168_ME1016810202011(CHIPS)':
 'GND_A64': CDS_PINID='GND_A64';
NODE_NAME     J37 A67
 '@S9S_MB_2U_LIB.S9S_MB_2U(SCH_1):PAGE150_I199@PURE_QUANTA.SCONN168_ME1016810202011(CHIPS)':
 'GND_A67': CDS_PINID='GND_A67';
NODE_NAME     J37 B13
 '@S9S_MB_2U_LIB.S9S_MB_2U(SCH_1):PAGE150_I199@PURE_QUANTA.SCONN168_ME1016810202011(CHIPS)':
 'GND_B13': CDS_PINID='GND_B13';
NODE_NAME     J37 B16
 '@S9S_MB_2U_LIB.S9S_MB_2U(SCH_1):PAGE150_I199@PURE_QUANTA.SCONN168_ME1016810202011(CHIPS)':
 'GND_B16': CDS_PINID='GND_B16';
NODE_NAME     J37 B19
 '@S9S_MB_2U_LIB.S9S_MB_2U(SCH_1):PAGE150_I199@PURE_QUANTA.SCONN168_ME1016810202011(CHIPS)':
 'GND_B19': CDS_PINID='GND_B19';
NODE_NAME     J37 B22
 '@S9S_MB_2U_LIB.S9S_MB_2U(SCH_1):PAGE150_I199@PURE_QUANTA.SCONN168_ME1016810202011(CHIPS)':
 'GND_B22': CDS_PINID='GND_B22';
NODE_NAME     J37 B25
 '@S9S_MB_2U_LIB.S9S_MB_2U(SCH_1):PAGE150_I199@PURE_QUANTA.SCONN168_ME1016810202011(CHIPS)':
 'GND_B25': CDS_PINID='GND_B25';
NODE_NAME     J37 B28
 '@S9S_MB_2U_LIB.S9S_MB_2U(SCH_1):PAGE150_I199@PURE_QUANTA.SCONN168_ME1016810202011(CHIPS)':
 'GND_B28': CDS_PINID='GND_B28';
NODE_NAME     J37 B29
 '@S9S_MB_2U_LIB.S9S_MB_2U(SCH_1):PAGE150_I199@PURE_QUANTA.SCONN168_ME1016810202011(CHIPS)':
 'GND_B29': CDS_PINID='GND_B29';
NODE_NAME     J37 B32
 '@S9S_MB_2U_LIB.S9S_MB_2U(SCH_1):PAGE150_I199@PURE_QUANTA.SCONN168_ME1016810202011(CHIPS)':
 'GND_B32': CDS_PINID='GND_B32';
NODE_NAME     J37 B35
 '@S9S_MB_2U_LIB.S9S_MB_2U(SCH_1):PAGE150_I199@PURE_QUANTA.SCONN168_ME1016810202011(CHIPS)':
 'GND_B35': CDS_PINID='GND_B35';
NODE_NAME     J37 B38
 '@S9S_MB_2U_LIB.S9S_MB_2U(SCH_1):PAGE150_I199@PURE_QUANTA.SCONN168_ME1016810202011(CHIPS)':
 'GND_B38': CDS_PINID='GND_B38';
NODE_NAME     J37 B41
 '@S9S_MB_2U_LIB.S9S_MB_2U(SCH_1):PAGE150_I199@PURE_QUANTA.SCONN168_ME1016810202011(CHIPS)':
 'GND_B41': CDS_PINID='GND_B41';
NODE_NAME     J37 B43
 '@S9S_MB_2U_LIB.S9S_MB_2U(SCH_1):PAGE150_I199@PURE_QUANTA.SCONN168_ME1016810202011(CHIPS)':
 'GND_B43': CDS_PINID='GND_B43';
NODE_NAME     J37 B46
 '@S9S_MB_2U_LIB.S9S_MB_2U(SCH_1):PAGE150_I199@PURE_QUANTA.SCONN168_ME1016810202011(CHIPS)':
 'GND_B46': CDS_PINID='GND_B46';
NODE_NAME     J37 B49
 '@S9S_MB_2U_LIB.S9S_MB_2U(SCH_1):PAGE150_I199@PURE_QUANTA.SCONN168_ME1016810202011(CHIPS)':
 'GND_B49': CDS_PINID='GND_B49';
NODE_NAME     J37 B52
 '@S9S_MB_2U_LIB.S9S_MB_2U(SCH_1):PAGE150_I199@PURE_QUANTA.SCONN168_ME1016810202011(CHIPS)':
 'GND_B52': CDS_PINID='GND_B52';
NODE_NAME     J37 B55
 '@S9S_MB_2U_LIB.S9S_MB_2U(SCH_1):PAGE150_I199@PURE_QUANTA.SCONN168_ME1016810202011(CHIPS)':
 'GND_B55': CDS_PINID='GND_B55';
NODE_NAME     J37 B58
 '@S9S_MB_2U_LIB.S9S_MB_2U(SCH_1):PAGE150_I199@PURE_QUANTA.SCONN168_ME1016810202011(CHIPS)':
 'GND_B58': CDS_PINID='GND_B58';
NODE_NAME     J37 B61
 '@S9S_MB_2U_LIB.S9S_MB_2U(SCH_1):PAGE150_I199@PURE_QUANTA.SCONN168_ME1016810202011(CHIPS)':
 'GND_B61': CDS_PINID='GND_B61';
NODE_NAME     J37 B64
 '@S9S_MB_2U_LIB.S9S_MB_2U(SCH_1):PAGE150_I199@PURE_QUANTA.SCONN168_ME1016810202011(CHIPS)':
 'GND_B64': CDS_PINID='GND_B64';
NODE_NAME     J37 B67
 '@S9S_MB_2U_LIB.S9S_MB_2U(SCH_1):PAGE150_I199@PURE_QUANTA.SCONN168_ME1016810202011(CHIPS)':
 'GND_B67': CDS_PINID='GND_B67';
NODE_NAME     J37 OA10
 '@S9S_MB_2U_LIB.S9S_MB_2U(SCH_1):PAGE150_I199@PURE_QUANTA.SCONN168_ME1016810202011(CHIPS)':
 'GND_OA10': CDS_PINID='GND_OA10';
NODE_NAME     J37 OA13
 '@S9S_MB_2U_LIB.S9S_MB_2U(SCH_1):PAGE150_I199@PURE_QUANTA.SCONN168_ME1016810202011(CHIPS)':
 'GND_OA13': CDS_PINID='GND_OA13';
NODE_NAME     J37 OB10
 '@S9S_MB_2U_LIB.S9S_MB_2U(SCH_1):PAGE150_I199@PURE_QUANTA.SCONN168_ME1016810202011(CHIPS)':
 'GND_OB10': CDS_PINID='GND_OB10';
NODE_NAME     J37 OB13
 '@S9S_MB_2U_LIB.S9S_MB_2U(SCH_1):PAGE150_I199@PURE_QUANTA.SCONN168_ME1016810202011(CHIPS)':
 'GND_OB13': CDS_PINID='GND_OB13';
NODE_NAME     J35 G1
 '@S9S_MB_2U_LIB.S9S_MB_2U(SCH_1):PAGE146_I303@PURE_QUANTA.SCONN168_ME1016810202011(CHIPS)':
 'G1': CDS_PINID='G1';
NODE_NAME     J35 G2
 '@S9S_MB_2U_LIB.S9S_MB_2U(SCH_1):PAGE146_I303@PURE_QUANTA.SCONN168_ME1016810202011(CHIPS)':
 'G2': CDS_PINID='G2';
NODE_NAME     J35 G3
 '@S9S_MB_2U_LIB.S9S_MB_2U(SCH_1):PAGE146_I303@PURE_QUANTA.SCONN168_ME1016810202011(CHIPS)':
 'G3': CDS_PINID='G3';
NODE_NAME     J35 G4
 '@S9S_MB_2U_LIB.S9S_MB_2U(SCH_1):PAGE146_I303@PURE_QUANTA.SCONN168_ME1016810202011(CHIPS)':
 'G4': CDS_PINID='G4';
NODE_NAME     J35 G5
 '@S9S_MB_2U_LIB.S9S_MB_2U(SCH_1):PAGE146_I303@PURE_QUANTA.SCONN168_ME1016810202011(CHIPS)':
 'G5': CDS_PINID='G5';
NODE_NAME     J35 A1
 '@S9S_MB_2U_LIB.S9S_MB_2U(SCH_1):PAGE146_I303@PURE_QUANTA.SCONN168_ME1016810202011(CHIPS)':
 'GND_A1': CDS_PINID='GND_A1';
NODE_NAME     J35 A2
 '@S9S_MB_2U_LIB.S9S_MB_2U(SCH_1):PAGE146_I303@PURE_QUANTA.SCONN168_ME1016810202011(CHIPS)':
 'GND_A2': CDS_PINID='GND_A2';
NODE_NAME     J35 A3
 '@S9S_MB_2U_LIB.S9S_MB_2U(SCH_1):PAGE146_I303@PURE_QUANTA.SCONN168_ME1016810202011(CHIPS)':
 'GND_A3': CDS_PINID='GND_A3';
NODE_NAME     J35 A4
 '@S9S_MB_2U_LIB.S9S_MB_2U(SCH_1):PAGE146_I303@PURE_QUANTA.SCONN168_ME1016810202011(CHIPS)':
 'GND_A4': CDS_PINID='GND_A4';
NODE_NAME     J35 A5
 '@S9S_MB_2U_LIB.S9S_MB_2U(SCH_1):PAGE146_I303@PURE_QUANTA.SCONN168_ME1016810202011(CHIPS)':
 'GND_A5': CDS_PINID='GND_A5';
NODE_NAME     J35 A6
 '@S9S_MB_2U_LIB.S9S_MB_2U(SCH_1):PAGE146_I303@PURE_QUANTA.SCONN168_ME1016810202011(CHIPS)':
 'GND_A6': CDS_PINID='GND_A6';
NODE_NAME     J35 A13
 '@S9S_MB_2U_LIB.S9S_MB_2U(SCH_1):PAGE146_I303@PURE_QUANTA.SCONN168_ME1016810202011(CHIPS)':
 'GND_A13': CDS_PINID='GND_A13';
NODE_NAME     J35 A16
 '@S9S_MB_2U_LIB.S9S_MB_2U(SCH_1):PAGE146_I303@PURE_QUANTA.SCONN168_ME1016810202011(CHIPS)':
 'GND_A16': CDS_PINID='GND_A16';
NODE_NAME     J35 A19
 '@S9S_MB_2U_LIB.S9S_MB_2U(SCH_1):PAGE146_I303@PURE_QUANTA.SCONN168_ME1016810202011(CHIPS)':
 'GND_A19': CDS_PINID='GND_A19';
NODE_NAME     J35 A22
 '@S9S_MB_2U_LIB.S9S_MB_2U(SCH_1):PAGE146_I303@PURE_QUANTA.SCONN168_ME1016810202011(CHIPS)':
 'GND_A22': CDS_PINID='GND_A22';
NODE_NAME     J35 A25
 '@S9S_MB_2U_LIB.S9S_MB_2U(SCH_1):PAGE146_I303@PURE_QUANTA.SCONN168_ME1016810202011(CHIPS)':
 'GND_A25': CDS_PINID='GND_A25';
NODE_NAME     J35 A28
 '@S9S_MB_2U_LIB.S9S_MB_2U(SCH_1):PAGE146_I303@PURE_QUANTA.SCONN168_ME1016810202011(CHIPS)':
 'GND_A28': CDS_PINID='GND_A28';
NODE_NAME     J35 A29
 '@S9S_MB_2U_LIB.S9S_MB_2U(SCH_1):PAGE146_I303@PURE_QUANTA.SCONN168_ME1016810202011(CHIPS)':
 'GND_A29': CDS_PINID='GND_A29';
NODE_NAME     J35 A32
 '@S9S_MB_2U_LIB.S9S_MB_2U(SCH_1):PAGE146_I303@PURE_QUANTA.SCONN168_ME1016810202011(CHIPS)':
 'GND_A32': CDS_PINID='GND_A32';
NODE_NAME     J35 A35
 '@S9S_MB_2U_LIB.S9S_MB_2U(SCH_1):PAGE146_I303@PURE_QUANTA.SCONN168_ME1016810202011(CHIPS)':
 'GND_A35': CDS_PINID='GND_A35';
NODE_NAME     J35 A38
 '@S9S_MB_2U_LIB.S9S_MB_2U(SCH_1):PAGE146_I303@PURE_QUANTA.SCONN168_ME1016810202011(CHIPS)':
 'GND_A38': CDS_PINID='GND_A38';
NODE_NAME     J35 A41
 '@S9S_MB_2U_LIB.S9S_MB_2U(SCH_1):PAGE146_I303@PURE_QUANTA.SCONN168_ME1016810202011(CHIPS)':
 'GND_A41': CDS_PINID='GND_A41';
NODE_NAME     J35 A43
 '@S9S_MB_2U_LIB.S9S_MB_2U(SCH_1):PAGE146_I303@PURE_QUANTA.SCONN168_ME1016810202011(CHIPS)':
 'GND_A43': CDS_PINID='GND_A43';
NODE_NAME     J35 A46
 '@S9S_MB_2U_LIB.S9S_MB_2U(SCH_1):PAGE146_I303@PURE_QUANTA.SCONN168_ME1016810202011(CHIPS)':
 'GND_A46': CDS_PINID='GND_A46';
NODE_NAME     J35 A49
 '@S9S_MB_2U_LIB.S9S_MB_2U(SCH_1):PAGE146_I303@PURE_QUANTA.SCONN168_ME1016810202011(CHIPS)':
 'GND_A49': CDS_PINID='GND_A49';
NODE_NAME     J35 A52
 '@S9S_MB_2U_LIB.S9S_MB_2U(SCH_1):PAGE146_I303@PURE_QUANTA.SCONN168_ME1016810202011(CHIPS)':
 'GND_A52': CDS_PINID='GND_A52';
NODE_NAME     J35 A55
 '@S9S_MB_2U_LIB.S9S_MB_2U(SCH_1):PAGE146_I303@PURE_QUANTA.SCONN168_ME1016810202011(CHIPS)':
 'GND_A55': CDS_PINID='GND_A55';
NODE_NAME     J35 A58
 '@S9S_MB_2U_LIB.S9S_MB_2U(SCH_1):PAGE146_I303@PURE_QUANTA.SCONN168_ME1016810202011(CHIPS)':
 'GND_A58': CDS_PINID='GND_A58';
NODE_NAME     J35 A61
 '@S9S_MB_2U_LIB.S9S_MB_2U(SCH_1):PAGE146_I303@PURE_QUANTA.SCONN168_ME1016810202011(CHIPS)':
 'GND_A61': CDS_PINID='GND_A61';
NODE_NAME     J35 A64
 '@S9S_MB_2U_LIB.S9S_MB_2U(SCH_1):PAGE146_I303@PURE_QUANTA.SCONN168_ME1016810202011(CHIPS)':
 'GND_A64': CDS_PINID='GND_A64';
NODE_NAME     J35 A67
 '@S9S_MB_2U_LIB.S9S_MB_2U(SCH_1):PAGE146_I303@PURE_QUANTA.SCONN168_ME1016810202011(CHIPS)':
 'GND_A67': CDS_PINID='GND_A67';
NODE_NAME     J35 B13
 '@S9S_MB_2U_LIB.S9S_MB_2U(SCH_1):PAGE146_I303@PURE_QUANTA.SCONN168_ME1016810202011(CHIPS)':
 'GND_B13': CDS_PINID='GND_B13';
NODE_NAME     J35 B16
 '@S9S_MB_2U_LIB.S9S_MB_2U(SCH_1):PAGE146_I303@PURE_QUANTA.SCONN168_ME1016810202011(CHIPS)':
 'GND_B16': CDS_PINID='GND_B16';
NODE_NAME     J35 B19
 '@S9S_MB_2U_LIB.S9S_MB_2U(SCH_1):PAGE146_I303@PURE_QUANTA.SCONN168_ME1016810202011(CHIPS)':
 'GND_B19': CDS_PINID='GND_B19';
NODE_NAME     J35 B22
 '@S9S_MB_2U_LIB.S9S_MB_2U(SCH_1):PAGE146_I303@PURE_QUANTA.SCONN168_ME1016810202011(CHIPS)':
 'GND_B22': CDS_PINID='GND_B22';
NODE_NAME     J35 B25
 '@S9S_MB_2U_LIB.S9S_MB_2U(SCH_1):PAGE146_I303@PURE_QUANTA.SCONN168_ME1016810202011(CHIPS)':
 'GND_B25': CDS_PINID='GND_B25';
NODE_NAME     J35 B28
 '@S9S_MB_2U_LIB.S9S_MB_2U(SCH_1):PAGE146_I303@PURE_QUANTA.SCONN168_ME1016810202011(CHIPS)':
 'GND_B28': CDS_PINID='GND_B28';
NODE_NAME     J35 B29
 '@S9S_MB_2U_LIB.S9S_MB_2U(SCH_1):PAGE146_I303@PURE_QUANTA.SCONN168_ME1016810202011(CHIPS)':
 'GND_B29': CDS_PINID='GND_B29';
NODE_NAME     J35 B32
 '@S9S_MB_2U_LIB.S9S_MB_2U(SCH_1):PAGE146_I303@PURE_QUANTA.SCONN168_ME1016810202011(CHIPS)':
 'GND_B32': CDS_PINID='GND_B32';
NODE_NAME     J35 B35
 '@S9S_MB_2U_LIB.S9S_MB_2U(SCH_1):PAGE146_I303@PURE_QUANTA.SCONN168_ME1016810202011(CHIPS)':
 'GND_B35': CDS_PINID='GND_B35';
NODE_NAME     J35 B38
 '@S9S_MB_2U_LIB.S9S_MB_2U(SCH_1):PAGE146_I303@PURE_QUANTA.SCONN168_ME1016810202011(CHIPS)':
 'GND_B38': CDS_PINID='GND_B38';
NODE_NAME     J35 B41
 '@S9S_MB_2U_LIB.S9S_MB_2U(SCH_1):PAGE146_I303@PURE_QUANTA.SCONN168_ME1016810202011(CHIPS)':
 'GND_B41': CDS_PINID='GND_B41';
NODE_NAME     J35 B43
 '@S9S_MB_2U_LIB.S9S_MB_2U(SCH_1):PAGE146_I303@PURE_QUANTA.SCONN168_ME1016810202011(CHIPS)':
 'GND_B43': CDS_PINID='GND_B43';
NODE_NAME     J35 B46
 '@S9S_MB_2U_LIB.S9S_MB_2U(SCH_1):PAGE146_I303@PURE_QUANTA.SCONN168_ME1016810202011(CHIPS)':
 'GND_B46': CDS_PINID='GND_B46';
NODE_NAME     J35 B49
 '@S9S_MB_2U_LIB.S9S_MB_2U(SCH_1):PAGE146_I303@PURE_QUANTA.SCONN168_ME1016810202011(CHIPS)':
 'GND_B49': CDS_PINID='GND_B49';
NODE_NAME     J35 B52
 '@S9S_MB_2U_LIB.S9S_MB_2U(SCH_1):PAGE146_I303@PURE_QUANTA.SCONN168_ME1016810202011(CHIPS)':
 'GND_B52': CDS_PINID='GND_B52';
NODE_NAME     J35 B55
 '@S9S_MB_2U_LIB.S9S_MB_2U(SCH_1):PAGE146_I303@PURE_QUANTA.SCONN168_ME1016810202011(CHIPS)':
 'GND_B55': CDS_PINID='GND_B55';
NODE_NAME     J35 B58
 '@S9S_MB_2U_LIB.S9S_MB_2U(SCH_1):PAGE146_I303@PURE_QUANTA.SCONN168_ME1016810202011(CHIPS)':
 'GND_B58': CDS_PINID='GND_B58';
NODE_NAME     J35 B61
 '@S9S_MB_2U_LIB.S9S_MB_2U(SCH_1):PAGE146_I303@PURE_QUANTA.SCONN168_ME1016810202011(CHIPS)':
 'GND_B61': CDS_PINID='GND_B61';
NODE_NAME     J35 B64
 '@S9S_MB_2U_LIB.S9S_MB_2U(SCH_1):PAGE146_I303@PURE_QUANTA.SCONN168_ME1016810202011(CHIPS)':
 'GND_B64': CDS_PINID='GND_B64';
NODE_NAME     J35 B67
 '@S9S_MB_2U_LIB.S9S_MB_2U(SCH_1):PAGE146_I303@PURE_QUANTA.SCONN168_ME1016810202011(CHIPS)':
 'GND_B67': CDS_PINID='GND_B67';
NODE_NAME     J35 OA10
 '@S9S_MB_2U_LIB.S9S_MB_2U(SCH_1):PAGE146_I303@PURE_QUANTA.SCONN168_ME1016810202011(CHIPS)':
 'GND_OA10': CDS_PINID='GND_OA10';
NODE_NAME     J35 OA13
 '@S9S_MB_2U_LIB.S9S_MB_2U(SCH_1):PAGE146_I303@PURE_QUANTA.SCONN168_ME1016810202011(CHIPS)':
 'GND_OA13': CDS_PINID='GND_OA13';
NODE_NAME     J35 OB10
 '@S9S_MB_2U_LIB.S9S_MB_2U(SCH_1):PAGE146_I303@PURE_QUANTA.SCONN168_ME1016810202011(CHIPS)':
 'GND_OB10': CDS_PINID='GND_OB10';
NODE_NAME     J35 OB13
 '@S9S_MB_2U_LIB.S9S_MB_2U(SCH_1):PAGE146_I303@PURE_QUANTA.SCONN168_ME1016810202011(CHIPS)':
 'GND_OB13': CDS_PINID='GND_OB13';
NODE_NAME     U278 3
 '@S9S_MB_2U_LIB.S9S_MB_2U(SCH_1):PAGE230_I31@PURE_QUANTA.74LVC1G08W57(CHIPS)':
 'GND': CDS_PINID='GND';
NODE_NAME     Y4 2
 '@S9S_MB_2U_LIB.S9S_MB_2U(SCH_1):PAGE155_I200@PURE_QUANTA.Q_XTAL_4P_13BI_24GND(CHIPS)':
 'G1': CDS_PINID='G1';
NODE_NAME     Y4 4
 '@S9S_MB_2U_LIB.S9S_MB_2U(SCH_1):PAGE155_I200@PURE_QUANTA.Q_XTAL_4P_13BI_24GND(CHIPS)':
 'G2': CDS_PINID='G2';
NODE_NAME     U145 3
 '@S9S_MB_2U_LIB.S9S_MB_2U(SCH_1):PAGE297_I163@PURE_QUANTA.74LVC1G126SE7(CHIPS)':
 'GND': CDS_PINID='GND';
NODE_NAME     R2457 2
 '@S9S_MB_2U_LIB.S9S_MB_2U(SCH_1):PAGE297_I165@PURE_QUANTA.Q_RES(CHIPS)':
 'B': CDS_PINID='B';
NODE_NAME     C1614 2
 '@S9S_MB_2U_LIB.S9S_MB_2U(SCH_1):PAGE297_I170@PURE_QUANTA.Q_CAP(CHIPS)':
 'B': CDS_PINID='B';
NODE_NAME     R3297 2
 '@S9S_MB_2U_LIB.S9S_MB_2U(SCH_1):PAGE182_I303@PURE_QUANTA.Q_RES(CHIPS)':
 'B': CDS_PINID='B';
NODE_NAME     C1873 2
 '@S9S_MB_2U_LIB.S9S_MB_2U(SCH_1):PAGE182_I308@PURE_QUANTA.Q_CAP(CHIPS)':
 'B': CDS_PINID='B';
NODE_NAME     U239 3
 '@S9S_MB_2U_LIB.S9S_MB_2U(SCH_1):PAGE182_I315@PURE_QUANTA.74LVC1G126SE7(CHIPS)':
 'GND': CDS_PINID='GND';
NODE_NAME     C2007 2
 '@S9S_MB_2U_LIB.S9S_MB_2U(SCH_1):PAGE182_I326@PURE_QUANTA.Q_CAP(CHIPS)':
 'B': CDS_PINID='B';
NODE_NAME     U259 2
 '@S9S_MB_2U_LIB.S9S_MB_2U(SCH_1):PAGE182_I327@PURE_QUANTA.SN74LVC2G07DCKR(CHIPS)':
 'GND': CDS_PINID='GND';
NODE_NAME     U279 4
 '@S9S_MB_2U_LIB.S9S_MB_2U(SCH_1):PAGE183_I93@PURE_QUANTA.PCA9617ADP(CHIPS)':
 'GND': CDS_PINID='GND';
NODE_NAME     C1277 2
 '@S9S_MB_2U_LIB.S9S_MB_2U(SCH_1):PAGE297_I237@PURE_QUANTA.Q_CAP(CHIPS)':
 'B': CDS_PINID='B';
NODE_NAME     C1283 2
 '@S9S_MB_2U_LIB.S9S_MB_2U(SCH_1):PAGE297_I245@PURE_QUANTA.Q_CAP(CHIPS)':
 'B': CDS_PINID='B';
NODE_NAME     C1282 2
 '@S9S_MB_2U_LIB.S9S_MB_2U(SCH_1):PAGE297_I247@PURE_QUANTA.Q_CAP(CHIPS)':
 'B': CDS_PINID='B';
NODE_NAME     C1279 2
 '@S9S_MB_2U_LIB.S9S_MB_2U(SCH_1):PAGE297_I252@PURE_QUANTA.Q_CAP(CHIPS)':
 'B': CDS_PINID='B';
NODE_NAME     C1278 2
 '@S9S_MB_2U_LIB.S9S_MB_2U(SCH_1):PAGE297_I258@PURE_QUANTA.Q_CAP(CHIPS)':
 'B': CDS_PINID='B';
NODE_NAME     C1276 2
 '@S9S_MB_2U_LIB.S9S_MB_2U(SCH_1):PAGE297_I260@PURE_QUANTA.Q_CAP(CHIPS)':
 'B': CDS_PINID='B';
NODE_NAME     R2296 2
 '@S9S_MB_2U_LIB.S9S_MB_2U(SCH_1):PAGE297_I293@PURE_QUANTA.Q_RES(CHIPS)':
 'B': CDS_PINID='B';
NODE_NAME     C1592 2
 '@S9S_MB_2U_LIB.S9S_MB_2U(SCH_1):PAGE297_I304@PURE_QUANTA.Q_CAP(CHIPS)':
 'B': CDS_PINID='B';
NODE_NAME     U134 2
 '@S9S_MB_2U_LIB.S9S_MB_2U(SCH_1):PAGE297_I305@PURE_QUANTA.74LVC2G07DW7(CHIPS)':
 'GND': CDS_PINID='GND';
NODE_NAME     U150 2
 '@S9S_MB_2U_LIB.S9S_MB_2U(SCH_1):PAGE213_I2@PURE_QUANTA.74LVC2G17GW(CHIPS)':
 'GND': CDS_PINID='GND';
NODE_NAME     C1619 2
 '@S9S_MB_2U_LIB.S9S_MB_2U(SCH_1):PAGE213_I5@PURE_QUANTA.Q_CAP(CHIPS)':
 'B': CDS_PINID='B';
NODE_NAME     PR3821 2
 '@S9S_MB_2U_LIB.S9S_MB_2U(SCH_1):PAGE131_I59@PURE_QUANTA.Q_RES(CHIPS)':
 'B': CDS_PINID='B';
NODE_NAME     R2426 2
 '@S9S_MB_2U_LIB.S9S_MB_2U(SCH_1):PAGE297_I311@PURE_QUANTA.Q_RES(CHIPS)':
 'B': CDS_PINID='B';
NODE_NAME     R3661 1
 '@S9S_MB_2U_LIB.S9S_MB_2U(SCH_1):PAGE155_I201@PURE_QUANTA.Q_RES(CHIPS)':
 'A': CDS_PINID='A';
NODE_NAME     U286 3
 '@S9S_MB_2U_LIB.S9S_MB_2U(SCH_1):PAGE307_I80@PURE_QUANTA.74LVC1G126SE7(CHIPS)':
 'GND': CDS_PINID='GND';
NODE_NAME     U225 3
 '@S9S_MB_2U_LIB.S9S_MB_2U(SCH_1):PAGE156_I74@PURE_QUANTA.74LVC1G126SE7(CHIPS)':
 'GND': CDS_PINID='GND';
NODE_NAME     U217 3
 '@S9S_MB_2U_LIB.S9S_MB_2U(SCH_1):PAGE156_I79@PURE_QUANTA.74LVC1G126SE7(CHIPS)':
 'GND': CDS_PINID='GND';
NODE_NAME     U82 3
 '@S9S_MB_2U_LIB.S9S_MB_2U(SCH_1):PAGE152_I79@PURE_QUANTA.74LVC1G126SE7(CHIPS)':
 'GND': CDS_PINID='GND';
NODE_NAME     U204 3
 '@S9S_MB_2U_LIB.S9S_MB_2U(SCH_1):PAGE140_I195@PURE_QUANTA.74LVC1G126SE7(CHIPS)':
 'GND': CDS_PINID='GND';
NODE_NAME     U154 3
 '@S9S_MB_2U_LIB.S9S_MB_2U(SCH_1):PAGE190_I95@PURE_QUANTA.74LVC1G07SE7(CHIPS)':
 'GND': CDS_PINID='GND';
NODE_NAME     Q46 S
 '@S9S_MB_2U_LIB.S9S_MB_2U(SCH_1):PAGE297_I316@PURE_QUANTA.MOSFET_NCH_GDS_ESD_PROTECTED(CHIPS)':
 'S': CDS_PINID='S';
NODE_NAME     Q54 S
 '@S9S_MB_2U_LIB.S9S_MB_2U(SCH_1):PAGE234_I14@PURE_QUANTA.MOSFET_NCH_GDS_ESD_PROTECTED(CHIPS)':
 'S': CDS_PINID='S';
NODE_NAME     H91 1
 '@S9S_MB_2U_LIB.S9S_MB_2U(SCH_1):PAGE289_I147@PURE_QUANTA.HOLE(CHIPS)':
 '1': CDS_PINID='\1\';
NODE_NAME     H97 1
 '@S9S_MB_2U_LIB.S9S_MB_2U(SCH_1):PAGE289_I149@PURE_QUANTA.HOLE(CHIPS)':
 '1': CDS_PINID='\1\';
NODE_NAME     H99 1
 '@S9S_MB_2U_LIB.S9S_MB_2U(SCH_1):PAGE289_I155@PURE_QUANTA.HOLE(CHIPS)':
 '1': CDS_PINID='\1\';
NODE_NAME     H102 1
 '@S9S_MB_2U_LIB.S9S_MB_2U(SCH_1):PAGE289_I158@PURE_QUANTA.HOLE(CHIPS)':
 '1': CDS_PINID='\1\';
NODE_NAME     H98 1
 '@S9S_MB_2U_LIB.S9S_MB_2U(SCH_1):PAGE289_I160@PURE_QUANTA.HOLE(CHIPS)':
 '1': CDS_PINID='\1\';
NODE_NAME     H92 1
 '@S9S_MB_2U_LIB.S9S_MB_2U(SCH_1):PAGE289_I166@PURE_QUANTA.HOLE(CHIPS)':
 '1': CDS_PINID='\1\';
NODE_NAME     H87 1
 '@S9S_MB_2U_LIB.S9S_MB_2U(SCH_1):PAGE289_I168@PURE_QUANTA.HOLE(CHIPS)':
 '1': CDS_PINID='\1\';
NODE_NAME     H104 1
 '@S9S_MB_2U_LIB.S9S_MB_2U(SCH_1):PAGE289_I175@PURE_QUANTA.HOLE(CHIPS)':
 '1': CDS_PINID='\1\';
NODE_NAME     H86 1
 '@S9S_MB_2U_LIB.S9S_MB_2U(SCH_1):PAGE289_I140@PURE_QUANTA.HOLE(CHIPS)':
 '1': CDS_PINID='\1\';
NODE_NAME     H88 1
 '@S9S_MB_2U_LIB.S9S_MB_2U(SCH_1):PAGE289_I144@PURE_QUANTA.HOLE(CHIPS)':
 '1': CDS_PINID='\1\';
NODE_NAME     H93 1
 '@S9S_MB_2U_LIB.S9S_MB_2U(SCH_1):PAGE289_I148@PURE_QUANTA.HOLE(CHIPS)':
 '1': CDS_PINID='\1\';
NODE_NAME     H95 1
 '@S9S_MB_2U_LIB.S9S_MB_2U(SCH_1):PAGE289_I150@PURE_QUANTA.HOLE(CHIPS)':
 '1': CDS_PINID='\1\';
NODE_NAME     H101 1
 '@S9S_MB_2U_LIB.S9S_MB_2U(SCH_1):PAGE289_I154@PURE_QUANTA.HOLE(CHIPS)':
 '1': CDS_PINID='\1\';
NODE_NAME     H100 1
 '@S9S_MB_2U_LIB.S9S_MB_2U(SCH_1):PAGE289_I159@PURE_QUANTA.HOLE(CHIPS)':
 '1': CDS_PINID='\1\';
NODE_NAME     H96 1
 '@S9S_MB_2U_LIB.S9S_MB_2U(SCH_1):PAGE289_I161@PURE_QUANTA.HOLE(CHIPS)':
 '1': CDS_PINID='\1\';
NODE_NAME     H94 1
 '@S9S_MB_2U_LIB.S9S_MB_2U(SCH_1):PAGE289_I165@PURE_QUANTA.HOLE(CHIPS)':
 '1': CDS_PINID='\1\';
NODE_NAME     H89 1
 '@S9S_MB_2U_LIB.S9S_MB_2U(SCH_1):PAGE289_I167@PURE_QUANTA.HOLE(CHIPS)':
 '1': CDS_PINID='\1\';
NODE_NAME     H103 1
 '@S9S_MB_2U_LIB.S9S_MB_2U(SCH_1):PAGE289_I174@PURE_QUANTA.HOLE(CHIPS)':
 '1': CDS_PINID='\1\';
NODE_NAME     H106 1
 '@S9S_MB_2U_LIB.S9S_MB_2U(SCH_1):PAGE289_I190@PURE_QUANTA.HOLE(CHIPS)':
 '1': CDS_PINID='\1\';
NODE_NAME     H105 1
 '@S9S_MB_2U_LIB.S9S_MB_2U(SCH_1):PAGE289_I192@PURE_QUANTA.HOLE(CHIPS)':
 '1': CDS_PINID='\1\';
NODE_NAME     C2176 2
 '@S9S_MB_2U_LIB.S9S_MB_2U(SCH_1):PAGE239_I304@PURE_QUANTA.Q_CAP(CHIPS)':
 'B': CDS_PINID='B';
NODE_NAME     C2178 2
 '@S9S_MB_2U_LIB.S9S_MB_2U(SCH_1):PAGE239_I305@PURE_QUANTA.Q_CAP(CHIPS)':
 'B': CDS_PINID='B';
NODE_NAME     C2175 2
 '@S9S_MB_2U_LIB.S9S_MB_2U(SCH_1):PAGE239_I309@PURE_QUANTA.Q_CAP(CHIPS)':
 'B': CDS_PINID='B';
NODE_NAME     C2177 2
 '@S9S_MB_2U_LIB.S9S_MB_2U(SCH_1):PAGE239_I311@PURE_QUANTA.Q_CAP(CHIPS)':
 'B': CDS_PINID='B';
NODE_NAME     PR3969 2
 '@S9S_MB_2U_LIB.S9S_MB_2U(SCH_1):PAGE324_I34@PURE_QUANTA.Q_RES(CHIPS)':
 'B': CDS_PINID='B';
NODE_NAME     PC2216 2
 '@S9S_MB_2U_LIB.S9S_MB_2U(SCH_1):PAGE324_I45@PURE_QUANTA.Q_CAP(CHIPS)':
 'B': CDS_PINID='B';
NODE_NAME     PD113 A
 '@S9S_MB_2U_LIB.S9S_MB_2U(SCH_1):PAGE324_I46@PURE_QUANTA.SCHOTTKY_AC(CHIPS)':
 'A': CDS_PINID='A';
NODE_NAME     PU294 A7
 '@S9S_MB_2U_LIB.S9S_MB_2U(SCH_1):PAGE324_I62@PURE_QUANTA.MAX15090BEWIT(CHIPS)':
 'CDLY': CDS_PINID='CDLY';
NODE_NAME     PU294 B7
 '@S9S_MB_2U_LIB.S9S_MB_2U(SCH_1):PAGE324_I62@PURE_QUANTA.MAX15090BEWIT(CHIPS)':
 'EN#': CDS_PINID='\en#\';
NODE_NAME     PU294 B2
 '@S9S_MB_2U_LIB.S9S_MB_2U(SCH_1):PAGE324_I62@PURE_QUANTA.MAX15090BEWIT(CHIPS)':
 'GND_B2': CDS_PINID='GND_B2';
NODE_NAME     PU294 C1
 '@S9S_MB_2U_LIB.S9S_MB_2U(SCH_1):PAGE324_I62@PURE_QUANTA.MAX15090BEWIT(CHIPS)':
 'GND_C1': CDS_PINID='GND_C1';
NODE_NAME     PU294 C2
 '@S9S_MB_2U_LIB.S9S_MB_2U(SCH_1):PAGE324_I62@PURE_QUANTA.MAX15090BEWIT(CHIPS)':
 'GND_C2': CDS_PINID='GND_C2';
NODE_NAME     PD112 A
 '@S9S_MB_2U_LIB.S9S_MB_2U(SCH_1):PAGE324_I71@PURE_QUANTA.SCHOTTKY_AC(CHIPS)':
 'A': CDS_PINID='A';
NODE_NAME     PC2197 2
 '@S9S_MB_2U_LIB.S9S_MB_2U(SCH_1):PAGE323_I3@PURE_QUANTA.Q_CAP(CHIPS)':
 'B': CDS_PINID='B';
NODE_NAME     PC2200 2
 '@S9S_MB_2U_LIB.S9S_MB_2U(SCH_1):PAGE323_I9@PURE_QUANTA.Q_CAP(CHIPS)':
 'B': CDS_PINID='B';
NODE_NAME     PC2204 2
 '@S9S_MB_2U_LIB.S9S_MB_2U(SCH_1):PAGE323_I34@PURE_QUANTA.Q_CAP(CHIPS)':
 'B': CDS_PINID='B';
NODE_NAME     C2195 2
 '@S9S_MB_2U_LIB.S9S_MB_2U(SCH_1):PAGE239_I333@PURE_QUANTA.Q_CAP(CHIPS)':
 'B': CDS_PINID='B';
NODE_NAME     C2194 2
 '@S9S_MB_2U_LIB.S9S_MB_2U(SCH_1):PAGE239_I336@PURE_QUANTA.Q_CAP(CHIPS)':
 'B': CDS_PINID='B';
NODE_NAME     PR4004 2
 '@S9S_MB_2U_LIB.S9S_MB_2U(SCH_1):PAGE229_I63@PURE_QUANTA.Q_RES(CHIPS)':
 'B': CDS_PINID='B';
NODE_NAME     PR4008 2
 '@S9S_MB_2U_LIB.S9S_MB_2U(SCH_1):PAGE229_I72@PURE_QUANTA.Q_RES(CHIPS)':
 'B': CDS_PINID='B';
NODE_NAME     R4029 2
 '@S9S_MB_2U_LIB.S9S_MB_2U(SCH_1):PAGE321_I77@PURE_QUANTA.Q_RES(CHIPS)':
 'B': CDS_PINID='B';
NODE_NAME     C2249 2
 '@S9S_MB_2U_LIB.S9S_MB_2U(SCH_1):PAGE321_I83@PURE_QUANTA.Q_CAP(CHIPS)':
 'B': CDS_PINID='B';
NODE_NAME     C2243 2
 '@S9S_MB_2U_LIB.S9S_MB_2U(SCH_1):PAGE321_I85@PURE_QUANTA.Q_CAP(CHIPS)':
 'B': CDS_PINID='B';
NODE_NAME     U301 7
 '@S9S_MB_2U_LIB.S9S_MB_2U(SCH_1):PAGE321_I91@PURE_QUANTA.GTL2014PW(CHIPS)':
 'GND_0': CDS_PINID='GND_0';
NODE_NAME     U301 8
 '@S9S_MB_2U_LIB.S9S_MB_2U(SCH_1):PAGE321_I91@PURE_QUANTA.GTL2014PW(CHIPS)':
 'GND_1': CDS_PINID='GND_1';
NODE_NAME     U301 11
 '@S9S_MB_2U_LIB.S9S_MB_2U(SCH_1):PAGE321_I91@PURE_QUANTA.GTL2014PW(CHIPS)':
 'GND_2': CDS_PINID='GND_2';
NODE_NAME     C2246 2
 '@S9S_MB_2U_LIB.S9S_MB_2U(SCH_1):PAGE322_I9@PURE_QUANTA.Q_CAP(CHIPS)':
 'B': CDS_PINID='B';
NODE_NAME     U304 7
 '@S9S_MB_2U_LIB.S9S_MB_2U(SCH_1):PAGE322_I27@PURE_QUANTA.GTL2014PW(CHIPS)':
 'GND_0': CDS_PINID='GND_0';
NODE_NAME     U304 8
 '@S9S_MB_2U_LIB.S9S_MB_2U(SCH_1):PAGE322_I27@PURE_QUANTA.GTL2014PW(CHIPS)':
 'GND_1': CDS_PINID='GND_1';
NODE_NAME     U304 11
 '@S9S_MB_2U_LIB.S9S_MB_2U(SCH_1):PAGE322_I27@PURE_QUANTA.GTL2014PW(CHIPS)':
 'GND_2': CDS_PINID='GND_2';
NODE_NAME     U305 7
 '@S9S_MB_2U_LIB.S9S_MB_2U(SCH_1):PAGE322_I44@PURE_QUANTA.GTL2014PW(CHIPS)':
 'GND_0': CDS_PINID='GND_0';
NODE_NAME     U305 8
 '@S9S_MB_2U_LIB.S9S_MB_2U(SCH_1):PAGE322_I44@PURE_QUANTA.GTL2014PW(CHIPS)':
 'GND_1': CDS_PINID='GND_1';
NODE_NAME     U305 11
 '@S9S_MB_2U_LIB.S9S_MB_2U(SCH_1):PAGE322_I44@PURE_QUANTA.GTL2014PW(CHIPS)':
 'GND_2': CDS_PINID='GND_2';
NODE_NAME     C2247 2
 '@S9S_MB_2U_LIB.S9S_MB_2U(SCH_1):PAGE322_I59@PURE_QUANTA.Q_CAP(CHIPS)':
 'B': CDS_PINID='B';
NODE_NAME     R4053 2
 '@S9S_MB_2U_LIB.S9S_MB_2U(SCH_1):PAGE322_I66@PURE_QUANTA.Q_RES(CHIPS)':
 'B': CDS_PINID='B';
NODE_NAME     R4054 2
 '@S9S_MB_2U_LIB.S9S_MB_2U(SCH_1):PAGE322_I67@PURE_QUANTA.Q_RES(CHIPS)':
 'B': CDS_PINID='B';
NODE_NAME     U306 7
 '@S9S_MB_2U_LIB.S9S_MB_2U(SCH_1):PAGE322_I80@PURE_QUANTA.GTL2014PW(CHIPS)':
 'GND_0': CDS_PINID='GND_0';
NODE_NAME     U306 8
 '@S9S_MB_2U_LIB.S9S_MB_2U(SCH_1):PAGE322_I80@PURE_QUANTA.GTL2014PW(CHIPS)':
 'GND_1': CDS_PINID='GND_1';
NODE_NAME     U306 11
 '@S9S_MB_2U_LIB.S9S_MB_2U(SCH_1):PAGE322_I80@PURE_QUANTA.GTL2014PW(CHIPS)':
 'GND_2': CDS_PINID='GND_2';
NODE_NAME     C2248 2
 '@S9S_MB_2U_LIB.S9S_MB_2U(SCH_1):PAGE322_I83@PURE_QUANTA.Q_CAP(CHIPS)':
 'B': CDS_PINID='B';
NODE_NAME     R4055 2
 '@S9S_MB_2U_LIB.S9S_MB_2U(SCH_1):PAGE322_I91@PURE_QUANTA.Q_RES(CHIPS)':
 'B': CDS_PINID='B';
NODE_NAME     C2252 2
 '@S9S_MB_2U_LIB.S9S_MB_2U(SCH_1):PAGE322_I101@PURE_QUANTA.Q_CAP(CHIPS)':
 'B': CDS_PINID='B';
NODE_NAME     C2253 2
 '@S9S_MB_2U_LIB.S9S_MB_2U(SCH_1):PAGE322_I106@PURE_QUANTA.Q_CAP(CHIPS)':
 'B': CDS_PINID='B';
NODE_NAME     C2254 2
 '@S9S_MB_2U_LIB.S9S_MB_2U(SCH_1):PAGE322_I111@PURE_QUANTA.Q_CAP(CHIPS)':
 'B': CDS_PINID='B';
NODE_NAME     H115 2
 '@S9S_MB_2U_LIB.S9S_MB_2U(SCH_1):PAGE289_I202@PURE_QUANTA.GND_HOLE(CHIPS)':
 'GND2': CDS_PINID='GND2';
NODE_NAME     H115 3
 '@S9S_MB_2U_LIB.S9S_MB_2U(SCH_1):PAGE289_I202@PURE_QUANTA.GND_HOLE(CHIPS)':
 'GND3': CDS_PINID='GND3';
NODE_NAME     H115 4
 '@S9S_MB_2U_LIB.S9S_MB_2U(SCH_1):PAGE289_I202@PURE_QUANTA.GND_HOLE(CHIPS)':
 'GND4': CDS_PINID='GND4';
NODE_NAME     H115 5
 '@S9S_MB_2U_LIB.S9S_MB_2U(SCH_1):PAGE289_I202@PURE_QUANTA.GND_HOLE(CHIPS)':
 'GND5': CDS_PINID='GND5';
NODE_NAME     H115 6
 '@S9S_MB_2U_LIB.S9S_MB_2U(SCH_1):PAGE289_I202@PURE_QUANTA.GND_HOLE(CHIPS)':
 'GND6': CDS_PINID='GND6';
NODE_NAME     H115 7
 '@S9S_MB_2U_LIB.S9S_MB_2U(SCH_1):PAGE289_I202@PURE_QUANTA.GND_HOLE(CHIPS)':
 'GND7': CDS_PINID='GND7';
NODE_NAME     H115 8
 '@S9S_MB_2U_LIB.S9S_MB_2U(SCH_1):PAGE289_I202@PURE_QUANTA.GND_HOLE(CHIPS)':
 'GND8': CDS_PINID='GND8';
NODE_NAME     H115 9
 '@S9S_MB_2U_LIB.S9S_MB_2U(SCH_1):PAGE289_I202@PURE_QUANTA.GND_HOLE(CHIPS)':
 'GND9': CDS_PINID='GND9';
NODE_NAME     H111 2
 '@S9S_MB_2U_LIB.S9S_MB_2U(SCH_1):PAGE289_I204@PURE_QUANTA.GND_HOLE(CHIPS)':
 'GND2': CDS_PINID='GND2';
NODE_NAME     H111 3
 '@S9S_MB_2U_LIB.S9S_MB_2U(SCH_1):PAGE289_I204@PURE_QUANTA.GND_HOLE(CHIPS)':
 'GND3': CDS_PINID='GND3';
NODE_NAME     H111 4
 '@S9S_MB_2U_LIB.S9S_MB_2U(SCH_1):PAGE289_I204@PURE_QUANTA.GND_HOLE(CHIPS)':
 'GND4': CDS_PINID='GND4';
NODE_NAME     H111 5
 '@S9S_MB_2U_LIB.S9S_MB_2U(SCH_1):PAGE289_I204@PURE_QUANTA.GND_HOLE(CHIPS)':
 'GND5': CDS_PINID='GND5';
NODE_NAME     H111 6
 '@S9S_MB_2U_LIB.S9S_MB_2U(SCH_1):PAGE289_I204@PURE_QUANTA.GND_HOLE(CHIPS)':
 'GND6': CDS_PINID='GND6';
NODE_NAME     H111 7
 '@S9S_MB_2U_LIB.S9S_MB_2U(SCH_1):PAGE289_I204@PURE_QUANTA.GND_HOLE(CHIPS)':
 'GND7': CDS_PINID='GND7';
NODE_NAME     H111 8
 '@S9S_MB_2U_LIB.S9S_MB_2U(SCH_1):PAGE289_I204@PURE_QUANTA.GND_HOLE(CHIPS)':
 'GND8': CDS_PINID='GND8';
NODE_NAME     H111 9
 '@S9S_MB_2U_LIB.S9S_MB_2U(SCH_1):PAGE289_I204@PURE_QUANTA.GND_HOLE(CHIPS)':
 'GND9': CDS_PINID='GND9';
NODE_NAME     H112 2
 '@S9S_MB_2U_LIB.S9S_MB_2U(SCH_1):PAGE289_I207@PURE_QUANTA.GND_HOLE(CHIPS)':
 'GND2': CDS_PINID='GND2';
NODE_NAME     H112 3
 '@S9S_MB_2U_LIB.S9S_MB_2U(SCH_1):PAGE289_I207@PURE_QUANTA.GND_HOLE(CHIPS)':
 'GND3': CDS_PINID='GND3';
NODE_NAME     H112 4
 '@S9S_MB_2U_LIB.S9S_MB_2U(SCH_1):PAGE289_I207@PURE_QUANTA.GND_HOLE(CHIPS)':
 'GND4': CDS_PINID='GND4';
NODE_NAME     H112 5
 '@S9S_MB_2U_LIB.S9S_MB_2U(SCH_1):PAGE289_I207@PURE_QUANTA.GND_HOLE(CHIPS)':
 'GND5': CDS_PINID='GND5';
NODE_NAME     H112 6
 '@S9S_MB_2U_LIB.S9S_MB_2U(SCH_1):PAGE289_I207@PURE_QUANTA.GND_HOLE(CHIPS)':
 'GND6': CDS_PINID='GND6';
NODE_NAME     H112 7
 '@S9S_MB_2U_LIB.S9S_MB_2U(SCH_1):PAGE289_I207@PURE_QUANTA.GND_HOLE(CHIPS)':
 'GND7': CDS_PINID='GND7';
NODE_NAME     H112 8
 '@S9S_MB_2U_LIB.S9S_MB_2U(SCH_1):PAGE289_I207@PURE_QUANTA.GND_HOLE(CHIPS)':
 'GND8': CDS_PINID='GND8';
NODE_NAME     H112 9
 '@S9S_MB_2U_LIB.S9S_MB_2U(SCH_1):PAGE289_I207@PURE_QUANTA.GND_HOLE(CHIPS)':
 'GND9': CDS_PINID='GND9';
NODE_NAME     C1934 2
 '@S9S_MB_2U_LIB.S9S_MB_2U(SCH_1):PAGE202_I120@PURE_QUANTA.Q_CAP(CHIPS)':
 'B': CDS_PINID='B';
NODE_NAME     C1150 2
 '@S9S_MB_2U_LIB.S9S_MB_2U(SCH_1):PAGE202_I121@PURE_QUANTA.Q_CAP(CHIPS)':
 'B': CDS_PINID='B';
NODE_NAME     C1884 2
 '@S9S_MB_2U_LIB.S9S_MB_2U(SCH_1):PAGE201_I103@PURE_QUANTA.Q_CAP(CHIPS)':
 'B': CDS_PINID='B';
NODE_NAME     C2257 2
 '@S9S_MB_2U_LIB.S9S_MB_2U(SCH_1):PAGE201_I104@PURE_QUANTA.Q_CAP(CHIPS)':
 'B': CDS_PINID='B';
NODE_NAME     C2258 2
 '@S9S_MB_2U_LIB.S9S_MB_2U(SCH_1):PAGE201_I105@PURE_QUANTA.Q_CAP(CHIPS)':
 'B': CDS_PINID='B';
NODE_NAME     C2259 2
 '@S9S_MB_2U_LIB.S9S_MB_2U(SCH_1):PAGE201_I106@PURE_QUANTA.Q_CAP(CHIPS)':
 'B': CDS_PINID='B';
NODE_NAME     R4079 2
 '@S9S_MB_2U_LIB.S9S_MB_2U(SCH_1):PAGE201_I128@PURE_QUANTA.Q_RES(CHIPS)':
 'B': CDS_PINID='B';
NODE_NAME     R4082 2
 '@S9S_MB_2U_LIB.S9S_MB_2U(SCH_1):PAGE201_I134@PURE_QUANTA.Q_RES(CHIPS)':
 'B': CDS_PINID='B';
NODE_NAME     C110 2
 '@S9S_MB_2U_LIB.S9S_MB_2U(SCH_1):PAGE199_I76@PURE_QUANTA.Q_CAP(CHIPS)':
 'B': CDS_PINID='B';
NODE_NAME     C171 2
 '@S9S_MB_2U_LIB.S9S_MB_2U(SCH_1):PAGE199_I77@PURE_QUANTA.Q_CAP(CHIPS)':
 'B': CDS_PINID='B';
NODE_NAME     C173 2
 '@S9S_MB_2U_LIB.S9S_MB_2U(SCH_1):PAGE199_I78@PURE_QUANTA.Q_CAP(CHIPS)':
 'B': CDS_PINID='B';
NODE_NAME     C114 2
 '@S9S_MB_2U_LIB.S9S_MB_2U(SCH_1):PAGE199_I79@PURE_QUANTA.Q_CAP(CHIPS)':
 'B': CDS_PINID='B';
NODE_NAME     C112 2
 '@S9S_MB_2U_LIB.S9S_MB_2U(SCH_1):PAGE199_I80@PURE_QUANTA.Q_CAP(CHIPS)':
 'B': CDS_PINID='B';
NODE_NAME     C111 2
 '@S9S_MB_2U_LIB.S9S_MB_2U(SCH_1):PAGE199_I81@PURE_QUANTA.Q_CAP(CHIPS)':
 'B': CDS_PINID='B';
NODE_NAME     C107 2
 '@S9S_MB_2U_LIB.S9S_MB_2U(SCH_1):PAGE199_I82@PURE_QUANTA.Q_CAP(CHIPS)':
 'B': CDS_PINID='B';
NODE_NAME     C120 2
 '@S9S_MB_2U_LIB.S9S_MB_2U(SCH_1):PAGE199_I85@PURE_QUANTA.Q_CAP(CHIPS)':
 'B': CDS_PINID='B';
NODE_NAME     C119 2
 '@S9S_MB_2U_LIB.S9S_MB_2U(SCH_1):PAGE199_I86@PURE_QUANTA.Q_CAP(CHIPS)':
 'B': CDS_PINID='B';
NODE_NAME     C117 2
 '@S9S_MB_2U_LIB.S9S_MB_2U(SCH_1):PAGE199_I87@PURE_QUANTA.Q_CAP(CHIPS)':
 'B': CDS_PINID='B';
NODE_NAME     C116 2
 '@S9S_MB_2U_LIB.S9S_MB_2U(SCH_1):PAGE199_I88@PURE_QUANTA.Q_CAP(CHIPS)':
 'B': CDS_PINID='B';
NODE_NAME     C115 2
 '@S9S_MB_2U_LIB.S9S_MB_2U(SCH_1):PAGE199_I89@PURE_QUANTA.Q_CAP(CHIPS)':
 'B': CDS_PINID='B';
NODE_NAME     C400 2
 '@S9S_MB_2U_LIB.S9S_MB_2U(SCH_1):PAGE74_I1@PURE_QUANTA.Q_CAP(CHIPS)':
 'B': CDS_PINID='B';
NODE_NAME     C402 2
 '@S9S_MB_2U_LIB.S9S_MB_2U(SCH_1):PAGE74_I3@PURE_QUANTA.Q_CAP(CHIPS)':
 'B': CDS_PINID='B';
NODE_NAME     C404 2
 '@S9S_MB_2U_LIB.S9S_MB_2U(SCH_1):PAGE74_I4@PURE_QUANTA.Q_CAP(CHIPS)':
 'B': CDS_PINID='B';
NODE_NAME     C406 2
 '@S9S_MB_2U_LIB.S9S_MB_2U(SCH_1):PAGE74_I5@PURE_QUANTA.Q_CAP(CHIPS)':
 'B': CDS_PINID='B';
NODE_NAME     C399 2
 '@S9S_MB_2U_LIB.S9S_MB_2U(SCH_1):PAGE74_I11@PURE_QUANTA.Q_CAP(CHIPS)':
 'B': CDS_PINID='B';
NODE_NAME     C967 2
 '@S9S_MB_2U_LIB.S9S_MB_2U(SCH_1):PAGE74_I25@PURE_QUANTA.Q_CAP(CHIPS)':
 'B': CDS_PINID='B';
NODE_NAME     C966 2
 '@S9S_MB_2U_LIB.S9S_MB_2U(SCH_1):PAGE74_I27@PURE_QUANTA.Q_CAP(CHIPS)':
 'B': CDS_PINID='B';
NODE_NAME     C972 2
 '@S9S_MB_2U_LIB.S9S_MB_2U(SCH_1):PAGE74_I28@PURE_QUANTA.Q_CAP(CHIPS)':
 'B': CDS_PINID='B';
NODE_NAME     C970 2
 '@S9S_MB_2U_LIB.S9S_MB_2U(SCH_1):PAGE74_I31@PURE_QUANTA.Q_CAP(CHIPS)':
 'B': CDS_PINID='B';
NODE_NAME     C405 2
 '@S9S_MB_2U_LIB.S9S_MB_2U(SCH_1):PAGE74_I34@PURE_QUANTA.Q_CAP(CHIPS)':
 'B': CDS_PINID='B';
NODE_NAME     C217 2
 '@S9S_MB_2U_LIB.S9S_MB_2U(SCH_1):PAGE74_I43@PURE_QUANTA.Q_CAP(CHIPS)':
 'B': CDS_PINID='B';
NODE_NAME     C989 2
 '@S9S_MB_2U_LIB.S9S_MB_2U(SCH_1):PAGE74_I45@PURE_QUANTA.Q_CAP(CHIPS)':
 'B': CDS_PINID='B';
NODE_NAME     C992 2
 '@S9S_MB_2U_LIB.S9S_MB_2U(SCH_1):PAGE74_I55@PURE_QUANTA.Q_CAP(CHIPS)':
 'B': CDS_PINID='B';
NODE_NAME     C987 2
 '@S9S_MB_2U_LIB.S9S_MB_2U(SCH_1):PAGE74_I57@PURE_QUANTA.Q_CAP(CHIPS)':
 'B': CDS_PINID='B';
NODE_NAME     C994 2
 '@S9S_MB_2U_LIB.S9S_MB_2U(SCH_1):PAGE74_I62@PURE_QUANTA.Q_CAP(CHIPS)':
 'B': CDS_PINID='B';
NODE_NAME     C1004 2
 '@S9S_MB_2U_LIB.S9S_MB_2U(SCH_1):PAGE74_I83@PURE_QUANTA.Q_CAP(CHIPS)':
 'B': CDS_PINID='B';
NODE_NAME     C420 2
 '@S9S_MB_2U_LIB.S9S_MB_2U(SCH_1):PAGE74_I100@PURE_QUANTA.Q_CAP(CHIPS)':
 'B': CDS_PINID='B';
NODE_NAME     C1021 2
 '@S9S_MB_2U_LIB.S9S_MB_2U(SCH_1):PAGE74_I106@PURE_QUANTA.Q_CAP(CHIPS)':
 'B': CDS_PINID='B';
NODE_NAME     C422 2
 '@S9S_MB_2U_LIB.S9S_MB_2U(SCH_1):PAGE74_I107@PURE_QUANTA.Q_CAP(CHIPS)':
 'B': CDS_PINID='B';
NODE_NAME     C1025 2
 '@S9S_MB_2U_LIB.S9S_MB_2U(SCH_1):PAGE74_I108@PURE_QUANTA.Q_CAP(CHIPS)':
 'B': CDS_PINID='B';
NODE_NAME     C1029 2
 '@S9S_MB_2U_LIB.S9S_MB_2U(SCH_1):PAGE74_I109@PURE_QUANTA.Q_CAP(CHIPS)':
 'B': CDS_PINID='B';
NODE_NAME     C1033 2
 '@S9S_MB_2U_LIB.S9S_MB_2U(SCH_1):PAGE74_I110@PURE_QUANTA.Q_CAP(CHIPS)':
 'B': CDS_PINID='B';
NODE_NAME     C1018 2
 '@S9S_MB_2U_LIB.S9S_MB_2U(SCH_1):PAGE74_I116@PURE_QUANTA.Q_CAP(CHIPS)':
 'B': CDS_PINID='B';
NODE_NAME     C1024 2
 '@S9S_MB_2U_LIB.S9S_MB_2U(SCH_1):PAGE74_I117@PURE_QUANTA.Q_CAP(CHIPS)':
 'B': CDS_PINID='B';
NODE_NAME     C1028 2
 '@S9S_MB_2U_LIB.S9S_MB_2U(SCH_1):PAGE74_I118@PURE_QUANTA.Q_CAP(CHIPS)':
 'B': CDS_PINID='B';
NODE_NAME     C1032 2
 '@S9S_MB_2U_LIB.S9S_MB_2U(SCH_1):PAGE74_I119@PURE_QUANTA.Q_CAP(CHIPS)':
 'B': CDS_PINID='B';
NODE_NAME     C1023 2
 '@S9S_MB_2U_LIB.S9S_MB_2U(SCH_1):PAGE74_I120@PURE_QUANTA.Q_CAP(CHIPS)':
 'B': CDS_PINID='B';
NODE_NAME     C1027 2
 '@S9S_MB_2U_LIB.S9S_MB_2U(SCH_1):PAGE74_I121@PURE_QUANTA.Q_CAP(CHIPS)':
 'B': CDS_PINID='B';
NODE_NAME     C1022 2
 '@S9S_MB_2U_LIB.S9S_MB_2U(SCH_1):PAGE74_I122@PURE_QUANTA.Q_CAP(CHIPS)':
 'B': CDS_PINID='B';
NODE_NAME     C1026 2
 '@S9S_MB_2U_LIB.S9S_MB_2U(SCH_1):PAGE74_I123@PURE_QUANTA.Q_CAP(CHIPS)':
 'B': CDS_PINID='B';
NODE_NAME     C1031 2
 '@S9S_MB_2U_LIB.S9S_MB_2U(SCH_1):PAGE74_I124@PURE_QUANTA.Q_CAP(CHIPS)':
 'B': CDS_PINID='B';
NODE_NAME     C1030 2
 '@S9S_MB_2U_LIB.S9S_MB_2U(SCH_1):PAGE74_I125@PURE_QUANTA.Q_CAP(CHIPS)':
 'B': CDS_PINID='B';
NODE_NAME     C1037 2
 '@S9S_MB_2U_LIB.S9S_MB_2U(SCH_1):PAGE74_I127@PURE_QUANTA.Q_CAP(CHIPS)':
 'B': CDS_PINID='B';
NODE_NAME     C1041 2
 '@S9S_MB_2U_LIB.S9S_MB_2U(SCH_1):PAGE74_I128@PURE_QUANTA.Q_CAP(CHIPS)':
 'B': CDS_PINID='B';
NODE_NAME     C1045 2
 '@S9S_MB_2U_LIB.S9S_MB_2U(SCH_1):PAGE74_I130@PURE_QUANTA.Q_CAP(CHIPS)':
 'B': CDS_PINID='B';
NODE_NAME     C505 2
 '@S9S_MB_2U_LIB.S9S_MB_2U(SCH_1):PAGE75_I6@PURE_QUANTA.Q_CAP(CHIPS)':
 'B': CDS_PINID='B';
NODE_NAME     C509 2
 '@S9S_MB_2U_LIB.S9S_MB_2U(SCH_1):PAGE75_I8@PURE_QUANTA.Q_CAP(CHIPS)':
 'B': CDS_PINID='B';
NODE_NAME     C522 2
 '@S9S_MB_2U_LIB.S9S_MB_2U(SCH_1):PAGE75_I9@PURE_QUANTA.Q_CAP(CHIPS)':
 'B': CDS_PINID='B';
NODE_NAME     C492 2
 '@S9S_MB_2U_LIB.S9S_MB_2U(SCH_1):PAGE75_I11@PURE_QUANTA.Q_CAP(CHIPS)':
 'B': CDS_PINID='B';
NODE_NAME     C491 2
 '@S9S_MB_2U_LIB.S9S_MB_2U(SCH_1):PAGE75_I13@PURE_QUANTA.Q_CAP(CHIPS)':
 'B': CDS_PINID='B';
NODE_NAME     C496 2
 '@S9S_MB_2U_LIB.S9S_MB_2U(SCH_1):PAGE75_I16@PURE_QUANTA.Q_CAP(CHIPS)':
 'B': CDS_PINID='B';
NODE_NAME     C533 2
 '@S9S_MB_2U_LIB.S9S_MB_2U(SCH_1):PAGE75_I17@PURE_QUANTA.Q_CAP(CHIPS)':
 'B': CDS_PINID='B';
NODE_NAME     C495 2
 '@S9S_MB_2U_LIB.S9S_MB_2U(SCH_1):PAGE75_I18@PURE_QUANTA.Q_CAP(CHIPS)':
 'B': CDS_PINID='B';
NODE_NAME     C515 2
 '@S9S_MB_2U_LIB.S9S_MB_2U(SCH_1):PAGE75_I19@PURE_QUANTA.Q_CAP(CHIPS)':
 'B': CDS_PINID='B';
NODE_NAME     C356 2
 '@S9S_MB_2U_LIB.S9S_MB_2U(SCH_1):PAGE75_I21@PURE_QUANTA.Q_CAP(CHIPS)':
 'B': CDS_PINID='B';
NODE_NAME     C355 2
 '@S9S_MB_2U_LIB.S9S_MB_2U(SCH_1):PAGE75_I23@PURE_QUANTA.Q_CAP(CHIPS)':
 'B': CDS_PINID='B';
NODE_NAME     C534 2
 '@S9S_MB_2U_LIB.S9S_MB_2U(SCH_1):PAGE75_I29@PURE_QUANTA.Q_CAP(CHIPS)':
 'B': CDS_PINID='B';
NODE_NAME     C518 2
 '@S9S_MB_2U_LIB.S9S_MB_2U(SCH_1):PAGE75_I31@PURE_QUANTA.Q_CAP(CHIPS)':
 'B': CDS_PINID='B';
NODE_NAME     C365 2
 '@S9S_MB_2U_LIB.S9S_MB_2U(SCH_1):PAGE75_I32@PURE_QUANTA.Q_CAP(CHIPS)':
 'B': CDS_PINID='B';
NODE_NAME     C364 2
 '@S9S_MB_2U_LIB.S9S_MB_2U(SCH_1):PAGE75_I34@PURE_QUANTA.Q_CAP(CHIPS)':
 'B': CDS_PINID='B';
NODE_NAME     C367 2
 '@S9S_MB_2U_LIB.S9S_MB_2U(SCH_1):PAGE75_I35@PURE_QUANTA.Q_CAP(CHIPS)':
 'B': CDS_PINID='B';
NODE_NAME     C371 2
 '@S9S_MB_2U_LIB.S9S_MB_2U(SCH_1):PAGE75_I36@PURE_QUANTA.Q_CAP(CHIPS)':
 'B': CDS_PINID='B';
NODE_NAME     C397 2
 '@S9S_MB_2U_LIB.S9S_MB_2U(SCH_1):PAGE75_I37@PURE_QUANTA.Q_CAP(CHIPS)':
 'B': CDS_PINID='B';
NODE_NAME     C357 2
 '@S9S_MB_2U_LIB.S9S_MB_2U(SCH_1):PAGE75_I38@PURE_QUANTA.Q_CAP(CHIPS)':
 'B': CDS_PINID='B';
NODE_NAME     C370 2
 '@S9S_MB_2U_LIB.S9S_MB_2U(SCH_1):PAGE75_I39@PURE_QUANTA.Q_CAP(CHIPS)':
 'B': CDS_PINID='B';
NODE_NAME     C373 2
 '@S9S_MB_2U_LIB.S9S_MB_2U(SCH_1):PAGE75_I40@PURE_QUANTA.Q_CAP(CHIPS)':
 'B': CDS_PINID='B';
NODE_NAME     C376 2
 '@S9S_MB_2U_LIB.S9S_MB_2U(SCH_1):PAGE75_I41@PURE_QUANTA.Q_CAP(CHIPS)':
 'B': CDS_PINID='B';
NODE_NAME     C395 2
 '@S9S_MB_2U_LIB.S9S_MB_2U(SCH_1):PAGE75_I46@PURE_QUANTA.Q_CAP(CHIPS)':
 'B': CDS_PINID='B';
NODE_NAME     C1405 2
 '@S9S_MB_2U_LIB.S9S_MB_2U(SCH_1):PAGE75_I47@PURE_QUANTA.Q_CAP(CHIPS)':
 'B': CDS_PINID='B';
NODE_NAME     C389 2
 '@S9S_MB_2U_LIB.S9S_MB_2U(SCH_1):PAGE75_I48@PURE_QUANTA.Q_CAP(CHIPS)':
 'B': CDS_PINID='B';
NODE_NAME     C382 2
 '@S9S_MB_2U_LIB.S9S_MB_2U(SCH_1):PAGE75_I51@PURE_QUANTA.Q_CAP(CHIPS)':
 'B': CDS_PINID='B';
NODE_NAME     C385 2
 '@S9S_MB_2U_LIB.S9S_MB_2U(SCH_1):PAGE75_I55@PURE_QUANTA.Q_CAP(CHIPS)':
 'B': CDS_PINID='B';
NODE_NAME     C387 2
 '@S9S_MB_2U_LIB.S9S_MB_2U(SCH_1):PAGE75_I56@PURE_QUANTA.Q_CAP(CHIPS)':
 'B': CDS_PINID='B';
NODE_NAME     C1398 2
 '@S9S_MB_2U_LIB.S9S_MB_2U(SCH_1):PAGE75_I58@PURE_QUANTA.Q_CAP(CHIPS)':
 'B': CDS_PINID='B';
NODE_NAME     C1436 2
 '@S9S_MB_2U_LIB.S9S_MB_2U(SCH_1):PAGE75_I59@PURE_QUANTA.Q_CAP(CHIPS)':
 'B': CDS_PINID='B';
NODE_NAME     C1406 2
 '@S9S_MB_2U_LIB.S9S_MB_2U(SCH_1):PAGE75_I61@PURE_QUANTA.Q_CAP(CHIPS)':
 'B': CDS_PINID='B';
NODE_NAME     C1407 2
 '@S9S_MB_2U_LIB.S9S_MB_2U(SCH_1):PAGE75_I62@PURE_QUANTA.Q_CAP(CHIPS)':
 'B': CDS_PINID='B';
NODE_NAME     C363 2
 '@S9S_MB_2U_LIB.S9S_MB_2U(SCH_1):PAGE75_I64@PURE_QUANTA.Q_CAP(CHIPS)':
 'B': CDS_PINID='B';
NODE_NAME     C527 2
 '@S9S_MB_2U_LIB.S9S_MB_2U(SCH_1):PAGE75_I68@PURE_QUANTA.Q_CAP(CHIPS)':
 'B': CDS_PINID='B';
NODE_NAME     C498 2
 '@S9S_MB_2U_LIB.S9S_MB_2U(SCH_1):PAGE76_I2@PURE_QUANTA.Q_CAP(CHIPS)':
 'B': CDS_PINID='B';
NODE_NAME     C502 2
 '@S9S_MB_2U_LIB.S9S_MB_2U(SCH_1):PAGE76_I3@PURE_QUANTA.Q_CAP(CHIPS)':
 'B': CDS_PINID='B';
NODE_NAME     C525 2
 '@S9S_MB_2U_LIB.S9S_MB_2U(SCH_1):PAGE76_I5@PURE_QUANTA.Q_CAP(CHIPS)':
 'B': CDS_PINID='B';
NODE_NAME     C500 2
 '@S9S_MB_2U_LIB.S9S_MB_2U(SCH_1):PAGE76_I9@PURE_QUANTA.Q_CAP(CHIPS)':
 'B': CDS_PINID='B';
NODE_NAME     C504 2
 '@S9S_MB_2U_LIB.S9S_MB_2U(SCH_1):PAGE76_I10@PURE_QUANTA.Q_CAP(CHIPS)':
 'B': CDS_PINID='B';
NODE_NAME     C508 2
 '@S9S_MB_2U_LIB.S9S_MB_2U(SCH_1):PAGE76_I11@PURE_QUANTA.Q_CAP(CHIPS)':
 'B': CDS_PINID='B';
NODE_NAME     C1400 2
 '@S9S_MB_2U_LIB.S9S_MB_2U(SCH_1):PAGE76_I14@PURE_QUANTA.Q_CAP(CHIPS)':
 'B': CDS_PINID='B';
NODE_NAME     C1362 2
 '@S9S_MB_2U_LIB.S9S_MB_2U(SCH_1):PAGE76_I16@PURE_QUANTA.Q_CAP(CHIPS)':
 'B': CDS_PINID='B';
NODE_NAME     C507 2
 '@S9S_MB_2U_LIB.S9S_MB_2U(SCH_1):PAGE76_I21@PURE_QUANTA.Q_CAP(CHIPS)':
 'B': CDS_PINID='B';
NODE_NAME     C386 2
 '@S9S_MB_2U_LIB.S9S_MB_2U(SCH_1):PAGE76_I22@PURE_QUANTA.Q_CAP(CHIPS)':
 'B': CDS_PINID='B';
NODE_NAME     C388 2
 '@S9S_MB_2U_LIB.S9S_MB_2U(SCH_1):PAGE76_I23@PURE_QUANTA.Q_CAP(CHIPS)':
 'B': CDS_PINID='B';
NODE_NAME     C390 2
 '@S9S_MB_2U_LIB.S9S_MB_2U(SCH_1):PAGE76_I25@PURE_QUANTA.Q_CAP(CHIPS)':
 'B': CDS_PINID='B';
NODE_NAME     C506 2
 '@S9S_MB_2U_LIB.S9S_MB_2U(SCH_1):PAGE76_I26@PURE_QUANTA.Q_CAP(CHIPS)':
 'B': CDS_PINID='B';
NODE_NAME     C512 2
 '@S9S_MB_2U_LIB.S9S_MB_2U(SCH_1):PAGE76_I32@PURE_QUANTA.Q_CAP(CHIPS)':
 'B': CDS_PINID='B';
NODE_NAME     C516 2
 '@S9S_MB_2U_LIB.S9S_MB_2U(SCH_1):PAGE76_I33@PURE_QUANTA.Q_CAP(CHIPS)':
 'B': CDS_PINID='B';
NODE_NAME     C519 2
 '@S9S_MB_2U_LIB.S9S_MB_2U(SCH_1):PAGE76_I35@PURE_QUANTA.Q_CAP(CHIPS)':
 'B': CDS_PINID='B';
NODE_NAME     C520 2
 '@S9S_MB_2U_LIB.S9S_MB_2U(SCH_1):PAGE76_I36@PURE_QUANTA.Q_CAP(CHIPS)':
 'B': CDS_PINID='B';
NODE_NAME     C521 2
 '@S9S_MB_2U_LIB.S9S_MB_2U(SCH_1):PAGE76_I37@PURE_QUANTA.Q_CAP(CHIPS)':
 'B': CDS_PINID='B';
NODE_NAME     C523 2
 '@S9S_MB_2U_LIB.S9S_MB_2U(SCH_1):PAGE76_I38@PURE_QUANTA.Q_CAP(CHIPS)':
 'B': CDS_PINID='B';
NODE_NAME     C526 2
 '@S9S_MB_2U_LIB.S9S_MB_2U(SCH_1):PAGE76_I39@PURE_QUANTA.Q_CAP(CHIPS)':
 'B': CDS_PINID='B';
NODE_NAME     C511 2
 '@S9S_MB_2U_LIB.S9S_MB_2U(SCH_1):PAGE76_I43@PURE_QUANTA.Q_CAP(CHIPS)':
 'B': CDS_PINID='B';
NODE_NAME     C392 2
 '@S9S_MB_2U_LIB.S9S_MB_2U(SCH_1):PAGE76_I44@PURE_QUANTA.Q_CAP(CHIPS)':
 'B': CDS_PINID='B';
NODE_NAME     C394 2
 '@S9S_MB_2U_LIB.S9S_MB_2U(SCH_1):PAGE76_I45@PURE_QUANTA.Q_CAP(CHIPS)':
 'B': CDS_PINID='B';
NODE_NAME     C366 2
 '@S9S_MB_2U_LIB.S9S_MB_2U(SCH_1):PAGE76_I48@PURE_QUANTA.Q_CAP(CHIPS)':
 'B': CDS_PINID='B';
NODE_NAME     C369 2
 '@S9S_MB_2U_LIB.S9S_MB_2U(SCH_1):PAGE76_I49@PURE_QUANTA.Q_CAP(CHIPS)':
 'B': CDS_PINID='B';
NODE_NAME     C372 2
 '@S9S_MB_2U_LIB.S9S_MB_2U(SCH_1):PAGE76_I50@PURE_QUANTA.Q_CAP(CHIPS)':
 'B': CDS_PINID='B';
NODE_NAME     C374 2
 '@S9S_MB_2U_LIB.S9S_MB_2U(SCH_1):PAGE76_I51@PURE_QUANTA.Q_CAP(CHIPS)':
 'B': CDS_PINID='B';
NODE_NAME     C377 2
 '@S9S_MB_2U_LIB.S9S_MB_2U(SCH_1):PAGE76_I52@PURE_QUANTA.Q_CAP(CHIPS)':
 'B': CDS_PINID='B';
NODE_NAME     C380 2
 '@S9S_MB_2U_LIB.S9S_MB_2U(SCH_1):PAGE76_I53@PURE_QUANTA.Q_CAP(CHIPS)':
 'B': CDS_PINID='B';
NODE_NAME     C383 2
 '@S9S_MB_2U_LIB.S9S_MB_2U(SCH_1):PAGE76_I54@PURE_QUANTA.Q_CAP(CHIPS)':
 'B': CDS_PINID='B';
NODE_NAME     C426 2
 '@S9S_MB_2U_LIB.S9S_MB_2U(SCH_1):PAGE77_I2@PURE_QUANTA.Q_CAP(CHIPS)':
 'B': CDS_PINID='B';
NODE_NAME     C229 2
 '@S9S_MB_2U_LIB.S9S_MB_2U(SCH_1):PAGE77_I14@PURE_QUANTA.Q_CAP(CHIPS)':
 'B': CDS_PINID='B';
NODE_NAME     C235 2
 '@S9S_MB_2U_LIB.S9S_MB_2U(SCH_1):PAGE77_I16@PURE_QUANTA.Q_CAP(CHIPS)':
 'B': CDS_PINID='B';
NODE_NAME     C227 2
 '@S9S_MB_2U_LIB.S9S_MB_2U(SCH_1):PAGE77_I26@PURE_QUANTA.Q_CAP(CHIPS)':
 'B': CDS_PINID='B';
NODE_NAME     C437 2
 '@S9S_MB_2U_LIB.S9S_MB_2U(SCH_1):PAGE77_I40@PURE_QUANTA.Q_CAP(CHIPS)':
 'B': CDS_PINID='B';
NODE_NAME     C269 2
 '@S9S_MB_2U_LIB.S9S_MB_2U(SCH_1):PAGE77_I64@PURE_QUANTA.Q_CAP(CHIPS)':
 'B': CDS_PINID='B';
NODE_NAME     C443 2
 '@S9S_MB_2U_LIB.S9S_MB_2U(SCH_1):PAGE77_I67@PURE_QUANTA.Q_CAP(CHIPS)':
 'B': CDS_PINID='B';
NODE_NAME     C310 2
 '@S9S_MB_2U_LIB.S9S_MB_2U(SCH_1):PAGE77_I70@PURE_QUANTA.Q_CAP(CHIPS)':
 'B': CDS_PINID='B';
NODE_NAME     C243 2
 '@S9S_MB_2U_LIB.S9S_MB_2U(SCH_1):PAGE77_I74@PURE_QUANTA.Q_CAP(CHIPS)':
 'B': CDS_PINID='B';
NODE_NAME     C241 2
 '@S9S_MB_2U_LIB.S9S_MB_2U(SCH_1):PAGE77_I77@PURE_QUANTA.Q_CAP(CHIPS)':
 'B': CDS_PINID='B';
NODE_NAME     C253 2
 '@S9S_MB_2U_LIB.S9S_MB_2U(SCH_1):PAGE77_I80@PURE_QUANTA.Q_CAP(CHIPS)':
 'B': CDS_PINID='B';
NODE_NAME     C252 2
 '@S9S_MB_2U_LIB.S9S_MB_2U(SCH_1):PAGE77_I82@PURE_QUANTA.Q_CAP(CHIPS)':
 'B': CDS_PINID='B';
NODE_NAME     C256 2
 '@S9S_MB_2U_LIB.S9S_MB_2U(SCH_1):PAGE77_I85@PURE_QUANTA.Q_CAP(CHIPS)':
 'B': CDS_PINID='B';
NODE_NAME     C273 2
 '@S9S_MB_2U_LIB.S9S_MB_2U(SCH_1):PAGE77_I91@PURE_QUANTA.Q_CAP(CHIPS)':
 'B': CDS_PINID='B';
NODE_NAME     C267 2
 '@S9S_MB_2U_LIB.S9S_MB_2U(SCH_1):PAGE77_I94@PURE_QUANTA.Q_CAP(CHIPS)':
 'B': CDS_PINID='B';
NODE_NAME     C266 2
 '@S9S_MB_2U_LIB.S9S_MB_2U(SCH_1):PAGE77_I97@PURE_QUANTA.Q_CAP(CHIPS)':
 'B': CDS_PINID='B';
NODE_NAME     C287 2
 '@S9S_MB_2U_LIB.S9S_MB_2U(SCH_1):PAGE77_I124@PURE_QUANTA.Q_CAP(CHIPS)':
 'B': CDS_PINID='B';
NODE_NAME     C292 2
 '@S9S_MB_2U_LIB.S9S_MB_2U(SCH_1):PAGE77_I127@PURE_QUANTA.Q_CAP(CHIPS)':
 'B': CDS_PINID='B';
NODE_NAME     C291 2
 '@S9S_MB_2U_LIB.S9S_MB_2U(SCH_1):PAGE77_I128@PURE_QUANTA.Q_CAP(CHIPS)':
 'B': CDS_PINID='B';
NODE_NAME     C303 2
 '@S9S_MB_2U_LIB.S9S_MB_2U(SCH_1):PAGE77_I139@PURE_QUANTA.Q_CAP(CHIPS)':
 'B': CDS_PINID='B';
NODE_NAME     C307 2
 '@S9S_MB_2U_LIB.S9S_MB_2U(SCH_1):PAGE77_I142@PURE_QUANTA.Q_CAP(CHIPS)':
 'B': CDS_PINID='B';
NODE_NAME     C449 2
 '@S9S_MB_2U_LIB.S9S_MB_2U(SCH_1):PAGE78_I1@PURE_QUANTA.Q_CAP(CHIPS)':
 'B': CDS_PINID='B';
NODE_NAME     C457 2
 '@S9S_MB_2U_LIB.S9S_MB_2U(SCH_1):PAGE78_I4@PURE_QUANTA.Q_CAP(CHIPS)':
 'B': CDS_PINID='B';
NODE_NAME     C478 2
 '@S9S_MB_2U_LIB.S9S_MB_2U(SCH_1):PAGE78_I8@PURE_QUANTA.Q_CAP(CHIPS)':
 'B': CDS_PINID='B';
NODE_NAME     C448 2
 '@S9S_MB_2U_LIB.S9S_MB_2U(SCH_1):PAGE78_I10@PURE_QUANTA.Q_CAP(CHIPS)':
 'B': CDS_PINID='B';
NODE_NAME     C447 2
 '@S9S_MB_2U_LIB.S9S_MB_2U(SCH_1):PAGE78_I12@PURE_QUANTA.Q_CAP(CHIPS)':
 'B': CDS_PINID='B';
NODE_NAME     C312 2
 '@S9S_MB_2U_LIB.S9S_MB_2U(SCH_1):PAGE78_I14@PURE_QUANTA.Q_CAP(CHIPS)':
 'B': CDS_PINID='B';
NODE_NAME     C311 2
 '@S9S_MB_2U_LIB.S9S_MB_2U(SCH_1):PAGE78_I16@PURE_QUANTA.Q_CAP(CHIPS)':
 'B': CDS_PINID='B';
NODE_NAME     C488 2
 '@S9S_MB_2U_LIB.S9S_MB_2U(SCH_1):PAGE78_I18@PURE_QUANTA.Q_CAP(CHIPS)':
 'B': CDS_PINID='B';
NODE_NAME     C489 2
 '@S9S_MB_2U_LIB.S9S_MB_2U(SCH_1):PAGE78_I19@PURE_QUANTA.Q_CAP(CHIPS)':
 'B': CDS_PINID='B';
NODE_NAME     C452 2
 '@S9S_MB_2U_LIB.S9S_MB_2U(SCH_1):PAGE78_I21@PURE_QUANTA.Q_CAP(CHIPS)':
 'B': CDS_PINID='B';
NODE_NAME     C471 2
 '@S9S_MB_2U_LIB.S9S_MB_2U(SCH_1):PAGE78_I25@PURE_QUANTA.Q_CAP(CHIPS)':
 'B': CDS_PINID='B';
NODE_NAME     C315 2
 '@S9S_MB_2U_LIB.S9S_MB_2U(SCH_1):PAGE78_I26@PURE_QUANTA.Q_CAP(CHIPS)':
 'B': CDS_PINID='B';
NODE_NAME     C321 2
 '@S9S_MB_2U_LIB.S9S_MB_2U(SCH_1):PAGE78_I30@PURE_QUANTA.Q_CAP(CHIPS)':
 'B': CDS_PINID='B';
NODE_NAME     C324 2
 '@S9S_MB_2U_LIB.S9S_MB_2U(SCH_1):PAGE78_I31@PURE_QUANTA.Q_CAP(CHIPS)':
 'B': CDS_PINID='B';
NODE_NAME     C330 2
 '@S9S_MB_2U_LIB.S9S_MB_2U(SCH_1):PAGE78_I33@PURE_QUANTA.Q_CAP(CHIPS)':
 'B': CDS_PINID='B';
NODE_NAME     C333 2
 '@S9S_MB_2U_LIB.S9S_MB_2U(SCH_1):PAGE78_I34@PURE_QUANTA.Q_CAP(CHIPS)':
 'B': CDS_PINID='B';
NODE_NAME     C339 2
 '@S9S_MB_2U_LIB.S9S_MB_2U(SCH_1):PAGE78_I36@PURE_QUANTA.Q_CAP(CHIPS)':
 'B': CDS_PINID='B';
NODE_NAME     C317 2
 '@S9S_MB_2U_LIB.S9S_MB_2U(SCH_1):PAGE78_I38@PURE_QUANTA.Q_CAP(CHIPS)':
 'B': CDS_PINID='B';
NODE_NAME     C329 2
 '@S9S_MB_2U_LIB.S9S_MB_2U(SCH_1):PAGE78_I42@PURE_QUANTA.Q_CAP(CHIPS)':
 'B': CDS_PINID='B';
NODE_NAME     C332 2
 '@S9S_MB_2U_LIB.S9S_MB_2U(SCH_1):PAGE78_I43@PURE_QUANTA.Q_CAP(CHIPS)':
 'B': CDS_PINID='B';
NODE_NAME     C335 2
 '@S9S_MB_2U_LIB.S9S_MB_2U(SCH_1):PAGE78_I44@PURE_QUANTA.Q_CAP(CHIPS)':
 'B': CDS_PINID='B';
NODE_NAME     C338 2
 '@S9S_MB_2U_LIB.S9S_MB_2U(SCH_1):PAGE78_I45@PURE_QUANTA.Q_CAP(CHIPS)':
 'B': CDS_PINID='B';
NODE_NAME     C1388 2
 '@S9S_MB_2U_LIB.S9S_MB_2U(SCH_1):PAGE78_I46@PURE_QUANTA.Q_CAP(CHIPS)':
 'B': CDS_PINID='B';
NODE_NAME     C1390 2
 '@S9S_MB_2U_LIB.S9S_MB_2U(SCH_1):PAGE78_I48@PURE_QUANTA.Q_CAP(CHIPS)':
 'B': CDS_PINID='B';
NODE_NAME     C1387 2
 '@S9S_MB_2U_LIB.S9S_MB_2U(SCH_1):PAGE78_I49@PURE_QUANTA.Q_CAP(CHIPS)':
 'B': CDS_PINID='B';
NODE_NAME     C1389 2
 '@S9S_MB_2U_LIB.S9S_MB_2U(SCH_1):PAGE78_I51@PURE_QUANTA.Q_CAP(CHIPS)':
 'B': CDS_PINID='B';
NODE_NAME     C1392 2
 '@S9S_MB_2U_LIB.S9S_MB_2U(SCH_1):PAGE78_I53@PURE_QUANTA.Q_CAP(CHIPS)':
 'B': CDS_PINID='B';
NODE_NAME     C1437 2
 '@S9S_MB_2U_LIB.S9S_MB_2U(SCH_1):PAGE78_I55@PURE_QUANTA.Q_CAP(CHIPS)':
 'B': CDS_PINID='B';
NODE_NAME     C1393 2
 '@S9S_MB_2U_LIB.S9S_MB_2U(SCH_1):PAGE78_I57@PURE_QUANTA.Q_CAP(CHIPS)':
 'B': CDS_PINID='B';
NODE_NAME     C349 2
 '@S9S_MB_2U_LIB.S9S_MB_2U(SCH_1):PAGE78_I63@PURE_QUANTA.Q_CAP(CHIPS)':
 'B': CDS_PINID='B';
NODE_NAME     C351 2
 '@S9S_MB_2U_LIB.S9S_MB_2U(SCH_1):PAGE78_I64@PURE_QUANTA.Q_CAP(CHIPS)':
 'B': CDS_PINID='B';
NODE_NAME     C484 2
 '@S9S_MB_2U_LIB.S9S_MB_2U(SCH_1):PAGE79_I12@PURE_QUANTA.Q_CAP(CHIPS)':
 'B': CDS_PINID='B';
NODE_NAME     C481 2
 '@S9S_MB_2U_LIB.S9S_MB_2U(SCH_1):PAGE79_I13@PURE_QUANTA.Q_CAP(CHIPS)':
 'B': CDS_PINID='B';
NODE_NAME     C456 2
 '@S9S_MB_2U_LIB.S9S_MB_2U(SCH_1):PAGE79_I15@PURE_QUANTA.Q_CAP(CHIPS)':
 'B': CDS_PINID='B';
NODE_NAME     C460 2
 '@S9S_MB_2U_LIB.S9S_MB_2U(SCH_1):PAGE79_I16@PURE_QUANTA.Q_CAP(CHIPS)':
 'B': CDS_PINID='B';
NODE_NAME     C464 2
 '@S9S_MB_2U_LIB.S9S_MB_2U(SCH_1):PAGE79_I17@PURE_QUANTA.Q_CAP(CHIPS)':
 'B': CDS_PINID='B';
NODE_NAME     C455 2
 '@S9S_MB_2U_LIB.S9S_MB_2U(SCH_1):PAGE79_I19@PURE_QUANTA.Q_CAP(CHIPS)':
 'B': CDS_PINID='B';
NODE_NAME     C459 2
 '@S9S_MB_2U_LIB.S9S_MB_2U(SCH_1):PAGE79_I20@PURE_QUANTA.Q_CAP(CHIPS)':
 'B': CDS_PINID='B';
NODE_NAME     C463 2
 '@S9S_MB_2U_LIB.S9S_MB_2U(SCH_1):PAGE79_I21@PURE_QUANTA.Q_CAP(CHIPS)':
 'B': CDS_PINID='B';
NODE_NAME     C342 2
 '@S9S_MB_2U_LIB.S9S_MB_2U(SCH_1):PAGE79_I23@PURE_QUANTA.Q_CAP(CHIPS)':
 'B': CDS_PINID='B';
NODE_NAME     C344 2
 '@S9S_MB_2U_LIB.S9S_MB_2U(SCH_1):PAGE79_I24@PURE_QUANTA.Q_CAP(CHIPS)':
 'B': CDS_PINID='B';
NODE_NAME     C346 2
 '@S9S_MB_2U_LIB.S9S_MB_2U(SCH_1):PAGE79_I25@PURE_QUANTA.Q_CAP(CHIPS)':
 'B': CDS_PINID='B';
NODE_NAME     C468 2
 '@S9S_MB_2U_LIB.S9S_MB_2U(SCH_1):PAGE79_I26@PURE_QUANTA.Q_CAP(CHIPS)':
 'B': CDS_PINID='B';
NODE_NAME     C472 2
 '@S9S_MB_2U_LIB.S9S_MB_2U(SCH_1):PAGE79_I27@PURE_QUANTA.Q_CAP(CHIPS)':
 'B': CDS_PINID='B';
NODE_NAME     C475 2
 '@S9S_MB_2U_LIB.S9S_MB_2U(SCH_1):PAGE79_I29@PURE_QUANTA.Q_CAP(CHIPS)':
 'B': CDS_PINID='B';
NODE_NAME     C467 2
 '@S9S_MB_2U_LIB.S9S_MB_2U(SCH_1):PAGE79_I31@PURE_QUANTA.Q_CAP(CHIPS)':
 'B': CDS_PINID='B';
NODE_NAME     C348 2
 '@S9S_MB_2U_LIB.S9S_MB_2U(SCH_1):PAGE79_I32@PURE_QUANTA.Q_CAP(CHIPS)':
 'B': CDS_PINID='B';
NODE_NAME     C350 2
 '@S9S_MB_2U_LIB.S9S_MB_2U(SCH_1):PAGE79_I33@PURE_QUANTA.Q_CAP(CHIPS)':
 'B': CDS_PINID='B';
NODE_NAME     C352 2
 '@S9S_MB_2U_LIB.S9S_MB_2U(SCH_1):PAGE79_I34@PURE_QUANTA.Q_CAP(CHIPS)':
 'B': CDS_PINID='B';
NODE_NAME     C354 2
 '@S9S_MB_2U_LIB.S9S_MB_2U(SCH_1):PAGE79_I35@PURE_QUANTA.Q_CAP(CHIPS)':
 'B': CDS_PINID='B';
NODE_NAME     C476 2
 '@S9S_MB_2U_LIB.S9S_MB_2U(SCH_1):PAGE79_I37@PURE_QUANTA.Q_CAP(CHIPS)':
 'B': CDS_PINID='B';
NODE_NAME     C477 2
 '@S9S_MB_2U_LIB.S9S_MB_2U(SCH_1):PAGE79_I38@PURE_QUANTA.Q_CAP(CHIPS)':
 'B': CDS_PINID='B';
NODE_NAME     C479 2
 '@S9S_MB_2U_LIB.S9S_MB_2U(SCH_1):PAGE79_I39@PURE_QUANTA.Q_CAP(CHIPS)':
 'B': CDS_PINID='B';
NODE_NAME     C482 2
 '@S9S_MB_2U_LIB.S9S_MB_2U(SCH_1):PAGE79_I41@PURE_QUANTA.Q_CAP(CHIPS)':
 'B': CDS_PINID='B';
NODE_NAME     C485 2
 '@S9S_MB_2U_LIB.S9S_MB_2U(SCH_1):PAGE79_I42@PURE_QUANTA.Q_CAP(CHIPS)':
 'B': CDS_PINID='B';
NODE_NAME     C1403 2
 '@S9S_MB_2U_LIB.S9S_MB_2U(SCH_1):PAGE79_I43@PURE_QUANTA.Q_CAP(CHIPS)':
 'B': CDS_PINID='B';
NODE_NAME     C1404 2
 '@S9S_MB_2U_LIB.S9S_MB_2U(SCH_1):PAGE79_I44@PURE_QUANTA.Q_CAP(CHIPS)':
 'B': CDS_PINID='B';
NODE_NAME     C322 2
 '@S9S_MB_2U_LIB.S9S_MB_2U(SCH_1):PAGE79_I46@PURE_QUANTA.Q_CAP(CHIPS)':
 'B': CDS_PINID='B';
NODE_NAME     C325 2
 '@S9S_MB_2U_LIB.S9S_MB_2U(SCH_1):PAGE79_I47@PURE_QUANTA.Q_CAP(CHIPS)':
 'B': CDS_PINID='B';
NODE_NAME     C1353 2
 '@S9S_MB_2U_LIB.S9S_MB_2U(SCH_1):PAGE79_I49@PURE_QUANTA.Q_CAP(CHIPS)':
 'B': CDS_PINID='B';
NODE_NAME     C328 2
 '@S9S_MB_2U_LIB.S9S_MB_2U(SCH_1):PAGE79_I50@PURE_QUANTA.Q_CAP(CHIPS)':
 'B': CDS_PINID='B';
NODE_NAME     C341 2
 '@S9S_MB_2U_LIB.S9S_MB_2U(SCH_1):PAGE79_I51@PURE_QUANTA.Q_CAP(CHIPS)':
 'B': CDS_PINID='B';
NODE_NAME     C343 2
 '@S9S_MB_2U_LIB.S9S_MB_2U(SCH_1):PAGE79_I52@PURE_QUANTA.Q_CAP(CHIPS)':
 'B': CDS_PINID='B';
NODE_NAME     C345 2
 '@S9S_MB_2U_LIB.S9S_MB_2U(SCH_1):PAGE79_I53@PURE_QUANTA.Q_CAP(CHIPS)':
 'B': CDS_PINID='B';
NODE_NAME     C347 2
 '@S9S_MB_2U_LIB.S9S_MB_2U(SCH_1):PAGE79_I55@PURE_QUANTA.Q_CAP(CHIPS)':
 'B': CDS_PINID='B';
NODE_NAME     C1363 2
 '@S9S_MB_2U_LIB.S9S_MB_2U(SCH_1):PAGE80_I5@PURE_QUANTA.Q_CAP(CHIPS)':
 'B': CDS_PINID='B';
NODE_NAME     PR5484 2
 '@S9S_MB_2U_LIB.S9S_MB_2U(SCH_1):PAGE153_I49@PURE_QUANTA.Q_RES(CHIPS)':
 'B': CDS_PINID='B';
NODE_NAME     PC2087 1
 '@S9S_MB_2U_LIB.S9S_MB_2U(SCH_1):PAGE153_I54@PURE_QUANTA.Q_CAP(CHIPS)':
 'A': CDS_PINID='A';
NODE_NAME     PC2085 2
 '@S9S_MB_2U_LIB.S9S_MB_2U(SCH_1):PAGE153_I55@PURE_QUANTA.Q_CAP(CHIPS)':
 'B': CDS_PINID='B';
NODE_NAME     PR3781 2
 '@S9S_MB_2U_LIB.S9S_MB_2U(SCH_1):PAGE153_I80@PURE_QUANTA.Q_RES(CHIPS)':
 'B': CDS_PINID='B';
NODE_NAME     PC2092 2
 '@S9S_MB_2U_LIB.S9S_MB_2U(SCH_1):PAGE153_I93@PURE_QUANTA.Q_CAP(CHIPS)':
 'B': CDS_PINID='B';
NODE_NAME     PC2082 2
 '@S9S_MB_2U_LIB.S9S_MB_2U(SCH_1):PAGE153_I96@PURE_QUANTA.Q_CAP(CHIPS)':
 'B': CDS_PINID='B';
NODE_NAME     PC2089 2
 '@S9S_MB_2U_LIB.S9S_MB_2U(SCH_1):PAGE153_I107@PURE_QUANTA.Q_CAP(CHIPS)':
 'B': CDS_PINID='B';
NODE_NAME     PC2157 2
 '@S9S_MB_2U_LIB.S9S_MB_2U(SCH_1):PAGE236_I42@PURE_QUANTA.Q_CAP(CHIPS)':
 'B': CDS_PINID='B';
NODE_NAME     PC2162 2
 '@S9S_MB_2U_LIB.S9S_MB_2U(SCH_1):PAGE236_I52@PURE_QUANTA.Q_CAP(CHIPS)':
 'B': CDS_PINID='B';
NODE_NAME     PR3812 2
 '@S9S_MB_2U_LIB.S9S_MB_2U(SCH_1):PAGE131_I48@PURE_QUANTA.Q_RES(CHIPS)':
 'B': CDS_PINID='B';
NODE_NAME     Q126 4
 '@S9S_MB_2U_LIB.S9S_MB_2U(SCH_1):PAGE324_I4@PURE_QUANTA.MOSFET_NCH_DUAL(CHIPS)':
 'S2': CDS_PINID='S2';
NODE_NAME     R4073 2
 '@S9S_MB_2U_LIB.S9S_MB_2U(SCH_1):PAGE324_I9@PURE_QUANTA.Q_RES(CHIPS)':
 'B': CDS_PINID='B';
NODE_NAME     PR3965 2
 '@S9S_MB_2U_LIB.S9S_MB_2U(SCH_1):PAGE324_I13@PURE_QUANTA.Q_RES(CHIPS)':
 'B': CDS_PINID='B';
NODE_NAME     PC2208 2
 '@S9S_MB_2U_LIB.S9S_MB_2U(SCH_1):PAGE324_I17@PURE_QUANTA.Q_CAP(CHIPS)':
 'B': CDS_PINID='B';
NODE_NAME     PC2209 2
 '@S9S_MB_2U_LIB.S9S_MB_2U(SCH_1):PAGE324_I60@PURE_QUANTA.Q_CAP(CHIPS)':
 'B': CDS_PINID='B';
NODE_NAME     PC2215 2
 '@S9S_MB_2U_LIB.S9S_MB_2U(SCH_1):PAGE324_I66@PURE_QUANTA.Q_CAP(CHIPS)':
 'B': CDS_PINID='B';
NODE_NAME     PR3945 2
 '@S9S_MB_2U_LIB.S9S_MB_2U(SCH_1):PAGE323_I4@PURE_QUANTA.Q_RES(CHIPS)':
 'B': CDS_PINID='B';
NODE_NAME     Q125 1
 '@S9S_MB_2U_LIB.S9S_MB_2U(SCH_1):PAGE229_I21@PURE_QUANTA.MOSFET_NCH_DUAL(CHIPS)':
 'S1': CDS_PINID='S1';
NODE_NAME     PR4005 2
 '@S9S_MB_2U_LIB.S9S_MB_2U(SCH_1):PAGE229_I34@PURE_QUANTA.Q_RES(CHIPS)':
 'B': CDS_PINID='B';
NODE_NAME     PC2231 2
 '@S9S_MB_2U_LIB.S9S_MB_2U(SCH_1):PAGE229_I37@PURE_QUANTA.Q_CAP(CHIPS)':
 'B': CDS_PINID='B';
NODE_NAME     PC2235 2
 '@S9S_MB_2U_LIB.S9S_MB_2U(SCH_1):PAGE229_I42@PURE_QUANTA.Q_CAP(CHIPS)':
 'B': CDS_PINID='B';
NODE_NAME     PR4011 2
 '@S9S_MB_2U_LIB.S9S_MB_2U(SCH_1):PAGE229_I50@PURE_QUANTA.Q_RES(CHIPS)':
 'B': CDS_PINID='B';
NODE_NAME     C1172 2
 '@S9S_MB_2U_LIB.S9S_MB_2U(SCH_1):PAGE246_I2@PURE_QUANTA.Q_CAP(CHIPS)':
 'B': CDS_PINID='B';
NODE_NAME     U99 2
 '@S9S_MB_2U_LIB.S9S_MB_2U(SCH_1):PAGE246_I4@PURE_QUANTA.RT9818C44GV(CHIPS)':
 'GND': CDS_PINID='GND';
NODE_NAME     C1042 2
 '@S9S_MB_2U_LIB.S9S_MB_2U(SCH_1):PAGE246_I11@PURE_QUANTA.Q_CAP(CHIPS)':
 'B': CDS_PINID='B';
NODE_NAME     R1641 2
 '@S9S_MB_2U_LIB.S9S_MB_2U(SCH_1):PAGE246_I14@PURE_QUANTA.Q_RES(CHIPS)':
 'B': CDS_PINID='B';
NODE_NAME     C1170 2
 '@S9S_MB_2U_LIB.S9S_MB_2U(SCH_1):PAGE246_I24@PURE_QUANTA.Q_CAP(CHIPS)':
 'B': CDS_PINID='B';
NODE_NAME     C1171 2
 '@S9S_MB_2U_LIB.S9S_MB_2U(SCH_1):PAGE246_I25@PURE_QUANTA.Q_CAP(CHIPS)':
 'B': CDS_PINID='B';
NODE_NAME     C1227 2
 '@S9S_MB_2U_LIB.S9S_MB_2U(SCH_1):PAGE246_I44@PURE_QUANTA.Q_CAP(CHIPS)':
 'B': CDS_PINID='B';
NODE_NAME     C1331 2
 '@S9S_MB_2U_LIB.S9S_MB_2U(SCH_1):PAGE246_I45@PURE_QUANTA.Q_CAP(CHIPS)':
 'B': CDS_PINID='B';
NODE_NAME     C1332 2
 '@S9S_MB_2U_LIB.S9S_MB_2U(SCH_1):PAGE246_I48@PURE_QUANTA.Q_CAP(CHIPS)':
 'B': CDS_PINID='B';
NODE_NAME     C1333 2
 '@S9S_MB_2U_LIB.S9S_MB_2U(SCH_1):PAGE246_I49@PURE_QUANTA.Q_CAP(CHIPS)':
 'B': CDS_PINID='B';
NODE_NAME     C1338 2
 '@S9S_MB_2U_LIB.S9S_MB_2U(SCH_1):PAGE246_I50@PURE_QUANTA.Q_CAP(CHIPS)':
 'B': CDS_PINID='B';
NODE_NAME     C1339 2
 '@S9S_MB_2U_LIB.S9S_MB_2U(SCH_1):PAGE246_I58@PURE_QUANTA.Q_CAP(CHIPS)':
 'B': CDS_PINID='B';
NODE_NAME     C1340 2
 '@S9S_MB_2U_LIB.S9S_MB_2U(SCH_1):PAGE246_I61@PURE_QUANTA.Q_CAP(CHIPS)':
 'B': CDS_PINID='B';
NODE_NAME     PR1649 2
 '@S9S_MB_2U_LIB.S9S_MB_2U(SCH_1):PAGE248_I9@PURE_QUANTA.Q_RES(CHIPS)':
 'B': CDS_PINID='B';
NODE_NAME     PC1215 2
 '@S9S_MB_2U_LIB.S9S_MB_2U(SCH_1):PAGE248_I23@PURE_QUANTA.Q_CAPP(CHIPS)':
 'B': CDS_PINID='B';
NODE_NAME     PC1225 2
 '@S9S_MB_2U_LIB.S9S_MB_2U(SCH_1):PAGE248_I44@PURE_QUANTA.Q_CAP(CHIPS)':
 'B': CDS_PINID='B';
NODE_NAME     PC1651 2
 '@S9S_MB_2U_LIB.S9S_MB_2U(SCH_1):PAGE249_I14@PURE_QUANTA.Q_CAP(CHIPS)':
 'B': CDS_PINID='B';
NODE_NAME     PR1330 2
 '@S9S_MB_2U_LIB.S9S_MB_2U(SCH_1):PAGE249_I24@PURE_QUANTA.Q_RES(CHIPS)':
 'B': CDS_PINID='B';
NODE_NAME     PR586 2
 '@S9S_MB_2U_LIB.S9S_MB_2U(SCH_1):PAGE252_I15@PURE_QUANTA.Q_RES(CHIPS)':
 'B': CDS_PINID='B';
NODE_NAME     PR4217 2
 '@S9S_MB_2U_LIB.S9S_MB_2U(SCH_1):PAGE252_I74@PURE_QUANTA.Q_RES(CHIPS)':
 'B': CDS_PINID='B';
NODE_NAME     PC305_P0_1 2
 '@S9S_MB_2U_LIB.S9S_MB_2U(SCH_1):PAGE253_I50@PURE_QUANTA.Q_CAP(CHIPS)':
 'B': CDS_PINID='B';
NODE_NAME     PC316 2
 '@S9S_MB_2U_LIB.S9S_MB_2U(SCH_1):PAGE253_I61@PURE_QUANTA.Q_CAPP(CHIPS)':
 'B': CDS_PINID='B';
NODE_NAME     PC323 2
 '@S9S_MB_2U_LIB.S9S_MB_2U(SCH_1):PAGE253_I64@PURE_QUANTA.Q_CAPP(CHIPS)':
 'B': CDS_PINID='B';
NODE_NAME     PC325 2
 '@S9S_MB_2U_LIB.S9S_MB_2U(SCH_1):PAGE253_I70@PURE_QUANTA.Q_CAPP(CHIPS)':
 'B': CDS_PINID='B';
NODE_NAME     PC314_P0_1 2
 '@S9S_MB_2U_LIB.S9S_MB_2U(SCH_1):PAGE253_I86@PURE_QUANTA.Q_CAP(CHIPS)':
 'B': CDS_PINID='B';
NODE_NAME     PC315 2
 '@S9S_MB_2U_LIB.S9S_MB_2U(SCH_1):PAGE253_I91@PURE_QUANTA.Q_CAPP(CHIPS)':
 'B': CDS_PINID='B';
NODE_NAME     PC318 2
 '@S9S_MB_2U_LIB.S9S_MB_2U(SCH_1):PAGE253_I92@PURE_QUANTA.Q_CAPP(CHIPS)':
 'B': CDS_PINID='B';
NODE_NAME     PC2345 2
 '@S9S_MB_2U_LIB.S9S_MB_2U(SCH_1):PAGE253_I95@PURE_QUANTA.Q_CAPP(CHIPS)':
 'B': CDS_PINID='B';
NODE_NAME     PR145 2
 '@S9S_MB_2U_LIB.S9S_MB_2U(SCH_1):PAGE254_I4@PURE_QUANTA.Q_RES(CHIPS)':
 'B': CDS_PINID='B';
NODE_NAME     PC270 2
 '@S9S_MB_2U_LIB.S9S_MB_2U(SCH_1):PAGE254_I11@PURE_QUANTA.Q_CAP(CHIPS)':
 'B': CDS_PINID='B';
NODE_NAME     PC1340 1
 '@S9S_MB_2U_LIB.S9S_MB_2U(SCH_1):PAGE254_I12@PURE_QUANTA.Q_CAP(CHIPS)':
 'A': CDS_PINID='A';
NODE_NAME     PU11_P0_3 2
 '@S9S_MB_2U_LIB.S9S_MB_2U(SCH_1):PAGE254_I20@PURE_QUANTA.ISL99390FRZTR5935(CHIPS)':
 'AGND': CDS_PINID='AGND';
NODE_NAME     PU11_P0_3 5
 '@S9S_MB_2U_LIB.S9S_MB_2U(SCH_1):PAGE254_I20@PURE_QUANTA.ISL99390FRZTR5935(CHIPS)':
 'PGND1': CDS_PINID='PGND1';
NODE_NAME     PU11_P0_3 7_9-20_24
 '@S9S_MB_2U_LIB.S9S_MB_2U(SCH_1):PAGE254_I20@PURE_QUANTA.ISL99390FRZTR5935(CHIPS)':
 'PGND2': CDS_PINID='PGND2';
NODE_NAME     PU11_P0_3 40
 '@S9S_MB_2U_LIB.S9S_MB_2U(SCH_1):PAGE254_I20@PURE_QUANTA.ISL99390FRZTR5935(CHIPS)':
 'PGND3': CDS_PINID='PGND3';
NODE_NAME     PC271 2
 '@S9S_MB_2U_LIB.S9S_MB_2U(SCH_1):PAGE254_I25@PURE_QUANTA.Q_CAP(CHIPS)':
 'B': CDS_PINID='B';
NODE_NAME     PC284_P0_4 2
 '@S9S_MB_2U_LIB.S9S_MB_2U(SCH_1):PAGE254_I43@PURE_QUANTA.Q_CAP(CHIPS)':
 'B': CDS_PINID='B';
NODE_NAME     PC277_P0_3 2
 '@S9S_MB_2U_LIB.S9S_MB_2U(SCH_1):PAGE254_I52@PURE_QUANTA.Q_CAP(CHIPS)':
 'B': CDS_PINID='B';
NODE_NAME     PC283_P0_3 2
 '@S9S_MB_2U_LIB.S9S_MB_2U(SCH_1):PAGE254_I54@PURE_QUANTA.Q_CAP(CHIPS)':
 'B': CDS_PINID='B';
NODE_NAME     PC289_P0_3 2
 '@S9S_MB_2U_LIB.S9S_MB_2U(SCH_1):PAGE254_I59@PURE_QUANTA.Q_CAP(CHIPS)':
 'B': CDS_PINID='B';
NODE_NAME     PC288_P0_4 2
 '@S9S_MB_2U_LIB.S9S_MB_2U(SCH_1):PAGE254_I60@PURE_QUANTA.Q_CAP(CHIPS)':
 'B': CDS_PINID='B';
NODE_NAME     PC290_P0_4 2
 '@S9S_MB_2U_LIB.S9S_MB_2U(SCH_1):PAGE254_I61@PURE_QUANTA.Q_CAP(CHIPS)':
 'B': CDS_PINID='B';
NODE_NAME     PC291_P0_3 2
 '@S9S_MB_2U_LIB.S9S_MB_2U(SCH_1):PAGE254_I65@PURE_QUANTA.Q_CAP(CHIPS)':
 'B': CDS_PINID='B';
NODE_NAME     PR139 2
 '@S9S_MB_2U_LIB.S9S_MB_2U(SCH_1):PAGE255_I4@PURE_QUANTA.Q_RES(CHIPS)':
 'B': CDS_PINID='B';
NODE_NAME     PC248 2
 '@S9S_MB_2U_LIB.S9S_MB_2U(SCH_1):PAGE255_I13@PURE_QUANTA.Q_CAP(CHIPS)':
 'B': CDS_PINID='B';
NODE_NAME     PC249 2
 '@S9S_MB_2U_LIB.S9S_MB_2U(SCH_1):PAGE255_I24@PURE_QUANTA.Q_CAP(CHIPS)':
 'B': CDS_PINID='B';
NODE_NAME     PC1343 1
 '@S9S_MB_2U_LIB.S9S_MB_2U(SCH_1):PAGE255_I25@PURE_QUANTA.Q_CAP(CHIPS)':
 'A': CDS_PINID='A';
NODE_NAME     PC251_P0_5 2
 '@S9S_MB_2U_LIB.S9S_MB_2U(SCH_1):PAGE255_I29@PURE_QUANTA.Q_CAP(CHIPS)':
 'B': CDS_PINID='B';
NODE_NAME     PC262_P0_6 2
 '@S9S_MB_2U_LIB.S9S_MB_2U(SCH_1):PAGE255_I43@PURE_QUANTA.Q_CAP(CHIPS)':
 'B': CDS_PINID='B';
NODE_NAME     PC253_P0_5 2
 '@S9S_MB_2U_LIB.S9S_MB_2U(SCH_1):PAGE255_I48@PURE_QUANTA.Q_CAP(CHIPS)':
 'B': CDS_PINID='B';
NODE_NAME     PC255_P0_5 2
 '@S9S_MB_2U_LIB.S9S_MB_2U(SCH_1):PAGE255_I52@PURE_QUANTA.Q_CAP(CHIPS)':
 'B': CDS_PINID='B';
NODE_NAME     PC259_P0_5 2
 '@S9S_MB_2U_LIB.S9S_MB_2U(SCH_1):PAGE255_I53@PURE_QUANTA.Q_CAP(CHIPS)':
 'B': CDS_PINID='B';
NODE_NAME     PC261_P0_5 2
 '@S9S_MB_2U_LIB.S9S_MB_2U(SCH_1):PAGE255_I54@PURE_QUANTA.Q_CAP(CHIPS)':
 'B': CDS_PINID='B';
NODE_NAME     PC263_P0_5 2
 '@S9S_MB_2U_LIB.S9S_MB_2U(SCH_1):PAGE255_I56@PURE_QUANTA.Q_CAP(CHIPS)':
 'B': CDS_PINID='B';
NODE_NAME     PC267_P0_5 2
 '@S9S_MB_2U_LIB.S9S_MB_2U(SCH_1):PAGE255_I63@PURE_QUANTA.Q_CAP(CHIPS)':
 'B': CDS_PINID='B';
NODE_NAME     PC269_P0_5 2
 '@S9S_MB_2U_LIB.S9S_MB_2U(SCH_1):PAGE255_I64@PURE_QUANTA.Q_CAP(CHIPS)':
 'B': CDS_PINID='B';
NODE_NAME     PU9_P0_5 2
 '@S9S_MB_2U_LIB.S9S_MB_2U(SCH_1):PAGE255_I66@PURE_QUANTA.ISL99390FRZTR5935(CHIPS)':
 'AGND': CDS_PINID='AGND';
NODE_NAME     PU9_P0_5 5
 '@S9S_MB_2U_LIB.S9S_MB_2U(SCH_1):PAGE255_I66@PURE_QUANTA.ISL99390FRZTR5935(CHIPS)':
 'PGND1': CDS_PINID='PGND1';
NODE_NAME     PU9_P0_5 7_9-20_24
 '@S9S_MB_2U_LIB.S9S_MB_2U(SCH_1):PAGE255_I66@PURE_QUANTA.ISL99390FRZTR5935(CHIPS)':
 'PGND2': CDS_PINID='PGND2';
NODE_NAME     PU9_P0_5 40
 '@S9S_MB_2U_LIB.S9S_MB_2U(SCH_1):PAGE255_I66@PURE_QUANTA.ISL99390FRZTR5935(CHIPS)':
 'PGND3': CDS_PINID='PGND3';
NODE_NAME     PR132 2
 '@S9S_MB_2U_LIB.S9S_MB_2U(SCH_1):PAGE256_I4@PURE_QUANTA.Q_RES(CHIPS)':
 'B': CDS_PINID='B';
NODE_NAME     PC1344 1
 '@S9S_MB_2U_LIB.S9S_MB_2U(SCH_1):PAGE256_I7@PURE_QUANTA.Q_CAP(CHIPS)':
 'A': CDS_PINID='A';
NODE_NAME     PC226 2
 '@S9S_MB_2U_LIB.S9S_MB_2U(SCH_1):PAGE256_I11@PURE_QUANTA.Q_CAP(CHIPS)':
 'B': CDS_PINID='B';
NODE_NAME     PC228_P0_8 2
 '@S9S_MB_2U_LIB.S9S_MB_2U(SCH_1):PAGE256_I15@PURE_QUANTA.Q_CAP(CHIPS)':
 'B': CDS_PINID='B';
NODE_NAME     PC230_P0_8 2
 '@S9S_MB_2U_LIB.S9S_MB_2U(SCH_1):PAGE256_I17@PURE_QUANTA.Q_CAP(CHIPS)':
 'B': CDS_PINID='B';
NODE_NAME     PC236_P0_8 2
 '@S9S_MB_2U_LIB.S9S_MB_2U(SCH_1):PAGE256_I21@PURE_QUANTA.Q_CAP(CHIPS)':
 'B': CDS_PINID='B';
NODE_NAME     PR133 2
 '@S9S_MB_2U_LIB.S9S_MB_2U(SCH_1):PAGE256_I23@PURE_QUANTA.Q_RES(CHIPS)':
 'B': CDS_PINID='B';
NODE_NAME     PC1345 1
 '@S9S_MB_2U_LIB.S9S_MB_2U(SCH_1):PAGE256_I29@PURE_QUANTA.Q_CAP(CHIPS)':
 'A': CDS_PINID='A';
NODE_NAME     PC227 2
 '@S9S_MB_2U_LIB.S9S_MB_2U(SCH_1):PAGE256_I31@PURE_QUANTA.Q_CAP(CHIPS)':
 'B': CDS_PINID='B';
NODE_NAME     PU7_P0_7 2
 '@S9S_MB_2U_LIB.S9S_MB_2U(SCH_1):PAGE256_I32@PURE_QUANTA.ISL99390FRZTR5935(CHIPS)':
 'AGND': CDS_PINID='AGND';
NODE_NAME     PU7_P0_7 5
 '@S9S_MB_2U_LIB.S9S_MB_2U(SCH_1):PAGE256_I32@PURE_QUANTA.ISL99390FRZTR5935(CHIPS)':
 'PGND1': CDS_PINID='PGND1';
NODE_NAME     PU7_P0_7 7_9-20_24
 '@S9S_MB_2U_LIB.S9S_MB_2U(SCH_1):PAGE256_I32@PURE_QUANTA.ISL99390FRZTR5935(CHIPS)':
 'PGND2': CDS_PINID='PGND2';
NODE_NAME     PU7_P0_7 40
 '@S9S_MB_2U_LIB.S9S_MB_2U(SCH_1):PAGE256_I32@PURE_QUANTA.ISL99390FRZTR5935(CHIPS)':
 'PGND3': CDS_PINID='PGND3';
NODE_NAME     PC231_P0_7 2
 '@S9S_MB_2U_LIB.S9S_MB_2U(SCH_1):PAGE256_I41@PURE_QUANTA.Q_CAP(CHIPS)':
 'B': CDS_PINID='B';
NODE_NAME     PC233_P0_7 2
 '@S9S_MB_2U_LIB.S9S_MB_2U(SCH_1):PAGE256_I42@PURE_QUANTA.Q_CAP(CHIPS)':
 'B': CDS_PINID='B';
NODE_NAME     PC237_P0_7 2
 '@S9S_MB_2U_LIB.S9S_MB_2U(SCH_1):PAGE256_I43@PURE_QUANTA.Q_CAP(CHIPS)':
 'B': CDS_PINID='B';
NODE_NAME     PL7 3
 '@S9S_MB_2U_LIB.S9S_MB_2U(SCH_1):PAGE256_I44@PURE_QUANTA.Q_INDUCTOR4P_14(CHIPS)':
 '3': CDS_PINID='\3\';
NODE_NAME     PC238_P0_8 2
 '@S9S_MB_2U_LIB.S9S_MB_2U(SCH_1):PAGE256_I47@PURE_QUANTA.Q_CAP(CHIPS)':
 'B': CDS_PINID='B';
NODE_NAME     PC240_P0_8 2
 '@S9S_MB_2U_LIB.S9S_MB_2U(SCH_1):PAGE256_I48@PURE_QUANTA.Q_CAP(CHIPS)':
 'B': CDS_PINID='B';
NODE_NAME     PC244_P0_8 2
 '@S9S_MB_2U_LIB.S9S_MB_2U(SCH_1):PAGE256_I53@PURE_QUANTA.Q_CAP(CHIPS)':
 'B': CDS_PINID='B';
NODE_NAME     PC246_P0_8 2
 '@S9S_MB_2U_LIB.S9S_MB_2U(SCH_1):PAGE256_I54@PURE_QUANTA.Q_CAP(CHIPS)':
 'B': CDS_PINID='B';
NODE_NAME     PC243_P0_7 2
 '@S9S_MB_2U_LIB.S9S_MB_2U(SCH_1):PAGE256_I62@PURE_QUANTA.Q_CAP(CHIPS)':
 'B': CDS_PINID='B';
NODE_NAME     PC239_P0_7 2
 '@S9S_MB_2U_LIB.S9S_MB_2U(SCH_1):PAGE256_I63@PURE_QUANTA.Q_CAP(CHIPS)':
 'B': CDS_PINID='B';
NODE_NAME     PC245_P0_7 2
 '@S9S_MB_2U_LIB.S9S_MB_2U(SCH_1):PAGE256_I66@PURE_QUANTA.Q_CAP(CHIPS)':
 'B': CDS_PINID='B';
NODE_NAME     PC247_P0_7 2
 '@S9S_MB_2U_LIB.S9S_MB_2U(SCH_1):PAGE256_I67@PURE_QUANTA.Q_CAP(CHIPS)':
 'B': CDS_PINID='B';
NODE_NAME     PC608_P0_1 2
 '@S9S_MB_2U_LIB.S9S_MB_2U(SCH_1):PAGE257_I47@PURE_QUANTA.Q_CAP(CHIPS)':
 'B': CDS_PINID='B';
NODE_NAME     PC613_P0_2 2
 '@S9S_MB_2U_LIB.S9S_MB_2U(SCH_1):PAGE257_I51@PURE_QUANTA.Q_CAP(CHIPS)':
 'B': CDS_PINID='B';
NODE_NAME     PC1670 2
 '@S9S_MB_2U_LIB.S9S_MB_2U(SCH_1):PAGE257_I84@PURE_QUANTA.Q_CAP(CHIPS)':
 'B': CDS_PINID='B';
NODE_NAME     PR1298 2
 '@S9S_MB_2U_LIB.S9S_MB_2U(SCH_1):PAGE258_I15@PURE_QUANTA.Q_RES(CHIPS)':
 'B': CDS_PINID='B';
NODE_NAME     PC1351 1
 '@S9S_MB_2U_LIB.S9S_MB_2U(SCH_1):PAGE258_I25@PURE_QUANTA.Q_CAP(CHIPS)':
 'A': CDS_PINID='A';
NODE_NAME     PC1174_P0_4 2
 '@S9S_MB_2U_LIB.S9S_MB_2U(SCH_1):PAGE258_I31@PURE_QUANTA.Q_CAP(CHIPS)':
 'B': CDS_PINID='B';
NODE_NAME     PC1185_P0_3 2
 '@S9S_MB_2U_LIB.S9S_MB_2U(SCH_1):PAGE258_I72@PURE_QUANTA.Q_CAP(CHIPS)':
 'B': CDS_PINID='B';
NODE_NAME     PC1674 2
 '@S9S_MB_2U_LIB.S9S_MB_2U(SCH_1):PAGE258_I76@PURE_QUANTA.Q_CAP(CHIPS)':
 'B': CDS_PINID='B';
NODE_NAME     PU44_P0_2 2
 '@S9S_MB_2U_LIB.S9S_MB_2U(SCH_1):PAGE261_I12@PURE_QUANTA.ISL99390FRZTR5935(CHIPS)':
 'AGND': CDS_PINID='AGND';
NODE_NAME     PU44_P0_2 5
 '@S9S_MB_2U_LIB.S9S_MB_2U(SCH_1):PAGE261_I12@PURE_QUANTA.ISL99390FRZTR5935(CHIPS)':
 'PGND1': CDS_PINID='PGND1';
NODE_NAME     PU44_P0_2 7_9-20_24
 '@S9S_MB_2U_LIB.S9S_MB_2U(SCH_1):PAGE261_I12@PURE_QUANTA.ISL99390FRZTR5935(CHIPS)':
 'PGND2': CDS_PINID='PGND2';
NODE_NAME     PU44_P0_2 40
 '@S9S_MB_2U_LIB.S9S_MB_2U(SCH_1):PAGE261_I12@PURE_QUANTA.ISL99390FRZTR5935(CHIPS)':
 'PGND3': CDS_PINID='PGND3';
NODE_NAME     PC1347 1
 '@S9S_MB_2U_LIB.S9S_MB_2U(SCH_1):PAGE261_I25@PURE_QUANTA.Q_CAP(CHIPS)':
 'A': CDS_PINID='A';
NODE_NAME     PC190_P0_2 2
 '@S9S_MB_2U_LIB.S9S_MB_2U(SCH_1):PAGE261_I32@PURE_QUANTA.Q_CAP(CHIPS)':
 'B': CDS_PINID='B';
NODE_NAME     PC192_P0_2 2
 '@S9S_MB_2U_LIB.S9S_MB_2U(SCH_1):PAGE261_I35@PURE_QUANTA.Q_CAP(CHIPS)':
 'B': CDS_PINID='B';
NODE_NAME     PC196_P0_2 2
 '@S9S_MB_2U_LIB.S9S_MB_2U(SCH_1):PAGE261_I36@PURE_QUANTA.Q_CAP(CHIPS)':
 'B': CDS_PINID='B';
NODE_NAME     PC198_P0_2 2
 '@S9S_MB_2U_LIB.S9S_MB_2U(SCH_1):PAGE261_I37@PURE_QUANTA.Q_CAP(CHIPS)':
 'B': CDS_PINID='B';
NODE_NAME     PC203_P0_2 2
 '@S9S_MB_2U_LIB.S9S_MB_2U(SCH_1):PAGE261_I40@PURE_QUANTA.Q_CAP(CHIPS)':
 'B': CDS_PINID='B';
NODE_NAME     PC189_P0_1 2
 '@S9S_MB_2U_LIB.S9S_MB_2U(SCH_1):PAGE261_I45@PURE_QUANTA.Q_CAP(CHIPS)':
 'B': CDS_PINID='B';
NODE_NAME     PC191_P0_1 2
 '@S9S_MB_2U_LIB.S9S_MB_2U(SCH_1):PAGE261_I48@PURE_QUANTA.Q_CAP(CHIPS)':
 'B': CDS_PINID='B';
NODE_NAME     PC195_P0_1 2
 '@S9S_MB_2U_LIB.S9S_MB_2U(SCH_1):PAGE261_I49@PURE_QUANTA.Q_CAP(CHIPS)':
 'B': CDS_PINID='B';
NODE_NAME     PC197_P0_1 2
 '@S9S_MB_2U_LIB.S9S_MB_2U(SCH_1):PAGE261_I50@PURE_QUANTA.Q_CAP(CHIPS)':
 'B': CDS_PINID='B';
NODE_NAME     PC202_P0_1 2
 '@S9S_MB_2U_LIB.S9S_MB_2U(SCH_1):PAGE261_I56@PURE_QUANTA.Q_CAP(CHIPS)':
 'B': CDS_PINID='B';
NODE_NAME     PC1574 2
 '@S9S_MB_2U_LIB.S9S_MB_2U(SCH_1):PAGE261_I66@PURE_QUANTA.Q_CAPP(CHIPS)':
 'B': CDS_PINID='B';
NODE_NAME     PC1576 2
 '@S9S_MB_2U_LIB.S9S_MB_2U(SCH_1):PAGE261_I67@PURE_QUANTA.Q_CAPP(CHIPS)':
 'B': CDS_PINID='B';
NODE_NAME     PC1573 2
 '@S9S_MB_2U_LIB.S9S_MB_2U(SCH_1):PAGE261_I68@PURE_QUANTA.Q_CAPP(CHIPS)':
 'B': CDS_PINID='B';
NODE_NAME     PC207 2
 '@S9S_MB_2U_LIB.S9S_MB_2U(SCH_1):PAGE261_I74@PURE_QUANTA.Q_CAPP(CHIPS)':
 'B': CDS_PINID='B';
NODE_NAME     PC175 2
 '@S9S_MB_2U_LIB.S9S_MB_2U(SCH_1):PAGE262_I12@PURE_QUANTA.Q_CAP(CHIPS)':
 'B': CDS_PINID='B';
NODE_NAME     PC2180 2
 '@S9S_MB_2U_LIB.S9S_MB_2U(SCH_1):PAGE262_I33@PURE_QUANTA.Q_CAPP(CHIPS)':
 'B': CDS_PINID='B';
NODE_NAME     C626 2
 '@S9S_MB_2U_LIB.S9S_MB_2U(SCH_1):PAGE264_I47@PURE_QUANTA.Q_CAP(CHIPS)':
 'B': CDS_PINID='B';
NODE_NAME     PC628 2
 '@S9S_MB_2U_LIB.S9S_MB_2U(SCH_1):PAGE264_I50@PURE_QUANTA.Q_CAP(CHIPS)':
 'B': CDS_PINID='B';
NODE_NAME     PU35 20
 '@S9S_MB_2U_LIB.S9S_MB_2U(SCH_1):PAGE264_I53@PURE_QUANTA.ISL69260IRAZT(CHIPS)':
 'EN1': CDS_PINID='EN1';
NODE_NAME     PU35 31
 '@S9S_MB_2U_LIB.S9S_MB_2U(SCH_1):PAGE264_I53@PURE_QUANTA.ISL69260IRAZT(CHIPS)':
 'RGND1': CDS_PINID='RGND1';
NODE_NAME     PU35 TH
 '@S9S_MB_2U_LIB.S9S_MB_2U(SCH_1):PAGE264_I53@PURE_QUANTA.ISL69260IRAZT(CHIPS)':
 'TH_GND': CDS_PINID='TH_GND';
NODE_NAME     PU35 32
 '@S9S_MB_2U_LIB.S9S_MB_2U(SCH_1):PAGE264_I53@PURE_QUANTA.ISL69260IRAZT(CHIPS)':
 'VSEN1': CDS_PINID='VSEN1';
NODE_NAME     PR4236 2
 '@S9S_MB_2U_LIB.S9S_MB_2U(SCH_1):PAGE264_I61@PURE_QUANTA.Q_RES(CHIPS)':
 'B': CDS_PINID='B';
NODE_NAME     PR4235 2
 '@S9S_MB_2U_LIB.S9S_MB_2U(SCH_1):PAGE264_I62@PURE_QUANTA.Q_RES(CHIPS)':
 'B': CDS_PINID='B';
NODE_NAME     PR2718 2
 '@S9S_MB_2U_LIB.S9S_MB_2U(SCH_1):PAGE265_I3@PURE_QUANTA.Q_RES(CHIPS)':
 'B': CDS_PINID='B';
NODE_NAME     PU36 2
 '@S9S_MB_2U_LIB.S9S_MB_2U(SCH_1):PAGE265_I8@PURE_QUANTA.ISL99390FRZTR5935(CHIPS)':
 'AGND': CDS_PINID='AGND';
NODE_NAME     PU36 5
 '@S9S_MB_2U_LIB.S9S_MB_2U(SCH_1):PAGE265_I8@PURE_QUANTA.ISL99390FRZTR5935(CHIPS)':
 'PGND1': CDS_PINID='PGND1';
NODE_NAME     PU36 7_9-20_24
 '@S9S_MB_2U_LIB.S9S_MB_2U(SCH_1):PAGE265_I8@PURE_QUANTA.ISL99390FRZTR5935(CHIPS)':
 'PGND2': CDS_PINID='PGND2';
NODE_NAME     PU36 40
 '@S9S_MB_2U_LIB.S9S_MB_2U(SCH_1):PAGE265_I8@PURE_QUANTA.ISL99390FRZTR5935(CHIPS)':
 'PGND3': CDS_PINID='PGND3';
NODE_NAME     PC633 2
 '@S9S_MB_2U_LIB.S9S_MB_2U(SCH_1):PAGE265_I11@PURE_QUANTA.Q_CAP(CHIPS)':
 'B': CDS_PINID='B';
NODE_NAME     PC634 2
 '@S9S_MB_2U_LIB.S9S_MB_2U(SCH_1):PAGE265_I18@PURE_QUANTA.Q_CAP(CHIPS)':
 'B': CDS_PINID='B';
NODE_NAME     PC635 2
 '@S9S_MB_2U_LIB.S9S_MB_2U(SCH_1):PAGE265_I20@PURE_QUANTA.Q_CAP(CHIPS)':
 'B': CDS_PINID='B';
NODE_NAME     PC637 2
 '@S9S_MB_2U_LIB.S9S_MB_2U(SCH_1):PAGE265_I21@PURE_QUANTA.Q_CAP(CHIPS)':
 'B': CDS_PINID='B';
NODE_NAME     PC638 2
 '@S9S_MB_2U_LIB.S9S_MB_2U(SCH_1):PAGE265_I23@PURE_QUANTA.Q_CAP(CHIPS)':
 'B': CDS_PINID='B';
NODE_NAME     PC641 2
 '@S9S_MB_2U_LIB.S9S_MB_2U(SCH_1):PAGE265_I25@PURE_QUANTA.Q_CAP(CHIPS)':
 'B': CDS_PINID='B';
NODE_NAME     PC1910 2
 '@S9S_MB_2U_LIB.S9S_MB_2U(SCH_1):PAGE265_I26@PURE_QUANTA.Q_CAPP(CHIPS)':
 'B': CDS_PINID='B';
NODE_NAME     PC642 2
 '@S9S_MB_2U_LIB.S9S_MB_2U(SCH_1):PAGE265_I28@PURE_QUANTA.Q_CAP(CHIPS)':
 'B': CDS_PINID='B';
NODE_NAME     PC1 2
 '@S9S_MB_2U_LIB.S9S_MB_2U(SCH_1):PAGE265_I29@PURE_QUANTA.Q_CAP(CHIPS)':
 'B': CDS_PINID='B';
NODE_NAME     PC1645 2
 '@S9S_MB_2U_LIB.S9S_MB_2U(SCH_1):PAGE265_I34@PURE_QUANTA.Q_CAPP(CHIPS)':
 'B': CDS_PINID='B';
NODE_NAME     PR4237 2
 '@S9S_MB_2U_LIB.S9S_MB_2U(SCH_1):PAGE265_I37@PURE_QUANTA.Q_RES(CHIPS)':
 'B': CDS_PINID='B';
NODE_NAME     PC2643 2
 '@S9S_MB_2U_LIB.S9S_MB_2U(SCH_1):PAGE267_I4@PURE_QUANTA.Q_CAP(CHIPS)':
 'B': CDS_PINID='B';
NODE_NAME     C1301 2
 '@S9S_MB_2U_LIB.S9S_MB_2U(SCH_1):PAGE267_I30@PURE_QUANTA.Q_CAP(CHIPS)':
 'B': CDS_PINID='B';
NODE_NAME     PR1 1
 '@S9S_MB_2U_LIB.S9S_MB_2U(SCH_1):PAGE268_I19@PURE_QUANTA.Q_RES(CHIPS)':
 'A': CDS_PINID='A';
NODE_NAME     PR1 2
 '@S9S_MB_2U_LIB.S9S_MB_2U(SCH_1):PAGE268_I19@PURE_QUANTA.Q_RES(CHIPS)':
 'B': CDS_PINID='B';
NODE_NAME     C2859 2
 '@S9S_MB_2U_LIB.S9S_MB_2U(SCH_1):PAGE270_I68@PURE_QUANTA.Q_CAP(CHIPS)':
 'B': CDS_PINID='B';
NODE_NAME     PR637 2
 '@S9S_MB_2U_LIB.S9S_MB_2U(SCH_1):PAGE270_I74@PURE_QUANTA.Q_RES(CHIPS)':
 'B': CDS_PINID='B';
NODE_NAME     PC1194 2
 '@S9S_MB_2U_LIB.S9S_MB_2U(SCH_1):PAGE270_I121@PURE_QUANTA.Q_CAP(CHIPS)':
 'B': CDS_PINID='B';
NODE_NAME     PR325 2
 '@S9S_MB_2U_LIB.S9S_MB_2U(SCH_1):PAGE271_I3@PURE_QUANTA.Q_RES(CHIPS)':
 'B': CDS_PINID='B';
NODE_NAME     PC1338 1
 '@S9S_MB_2U_LIB.S9S_MB_2U(SCH_1):PAGE271_I6@PURE_QUANTA.Q_CAP(CHIPS)':
 'A': CDS_PINID='A';
NODE_NAME     PC556 2
 '@S9S_MB_2U_LIB.S9S_MB_2U(SCH_1):PAGE271_I11@PURE_QUANTA.Q_CAP(CHIPS)':
 'B': CDS_PINID='B';
NODE_NAME     PC568_P1_2 2
 '@S9S_MB_2U_LIB.S9S_MB_2U(SCH_1):PAGE271_I24@PURE_QUANTA.Q_CAP(CHIPS)':
 'B': CDS_PINID='B';
NODE_NAME     PC563_P1_1 2
 '@S9S_MB_2U_LIB.S9S_MB_2U(SCH_1):PAGE271_I47@PURE_QUANTA.Q_CAP(CHIPS)':
 'B': CDS_PINID='B';
NODE_NAME     PC567_P1_1 2
 '@S9S_MB_2U_LIB.S9S_MB_2U(SCH_1):PAGE271_I48@PURE_QUANTA.Q_CAP(CHIPS)':
 'B': CDS_PINID='B';
NODE_NAME     PC569_P1_1 2
 '@S9S_MB_2U_LIB.S9S_MB_2U(SCH_1):PAGE271_I50@PURE_QUANTA.Q_CAP(CHIPS)':
 'B': CDS_PINID='B';
NODE_NAME     PC575_P1_2 2
 '@S9S_MB_2U_LIB.S9S_MB_2U(SCH_1):PAGE271_I57@PURE_QUANTA.Q_CAP(CHIPS)':
 'B': CDS_PINID='B';
NODE_NAME     PC577_P1_2 2
 '@S9S_MB_2U_LIB.S9S_MB_2U(SCH_1):PAGE271_I58@PURE_QUANTA.Q_CAP(CHIPS)':
 'B': CDS_PINID='B';
NODE_NAME     PR4240 2
 '@S9S_MB_2U_LIB.S9S_MB_2U(SCH_1):PAGE271_I59@PURE_QUANTA.Q_RES(CHIPS)':
 'B': CDS_PINID='B';
NODE_NAME     PC580 2
 '@S9S_MB_2U_LIB.S9S_MB_2U(SCH_1):PAGE271_I63@PURE_QUANTA.Q_CAPP(CHIPS)':
 'B': CDS_PINID='B';
NODE_NAME     PC589 2
 '@S9S_MB_2U_LIB.S9S_MB_2U(SCH_1):PAGE271_I72@PURE_QUANTA.Q_CAPP(CHIPS)':
 'B': CDS_PINID='B';
NODE_NAME     PC574_P1_1 2
 '@S9S_MB_2U_LIB.S9S_MB_2U(SCH_1):PAGE271_I85@PURE_QUANTA.Q_CAP(CHIPS)':
 'B': CDS_PINID='B';
NODE_NAME     PR297 2
 '@S9S_MB_2U_LIB.S9S_MB_2U(SCH_1):PAGE272_I3@PURE_QUANTA.Q_RES(CHIPS)':
 'B': CDS_PINID='B';
NODE_NAME     PC1358 1
 '@S9S_MB_2U_LIB.S9S_MB_2U(SCH_1):PAGE272_I6@PURE_QUANTA.Q_CAP(CHIPS)':
 'A': CDS_PINID='A';
NODE_NAME     PU27_P1_4 2
 '@S9S_MB_2U_LIB.S9S_MB_2U(SCH_1):PAGE272_I10@PURE_QUANTA.ISL99390FRZTR5935(CHIPS)':
 'AGND': CDS_PINID='AGND';
NODE_NAME     PU27_P1_4 5
 '@S9S_MB_2U_LIB.S9S_MB_2U(SCH_1):PAGE272_I10@PURE_QUANTA.ISL99390FRZTR5935(CHIPS)':
 'PGND1': CDS_PINID='PGND1';
NODE_NAME     PU27_P1_4 7_9-20_24
 '@S9S_MB_2U_LIB.S9S_MB_2U(SCH_1):PAGE272_I10@PURE_QUANTA.ISL99390FRZTR5935(CHIPS)':
 'PGND2': CDS_PINID='PGND2';
NODE_NAME     PU27_P1_4 40
 '@S9S_MB_2U_LIB.S9S_MB_2U(SCH_1):PAGE272_I10@PURE_QUANTA.ISL99390FRZTR5935(CHIPS)':
 'PGND3': CDS_PINID='PGND3';
NODE_NAME     PR298 2
 '@S9S_MB_2U_LIB.S9S_MB_2U(SCH_1):PAGE272_I15@PURE_QUANTA.Q_RES(CHIPS)':
 'B': CDS_PINID='B';
NODE_NAME     PC525_P1_4 2
 '@S9S_MB_2U_LIB.S9S_MB_2U(SCH_1):PAGE272_I19@PURE_QUANTA.Q_CAP(CHIPS)':
 'B': CDS_PINID='B';
NODE_NAME     PC524 2
 '@S9S_MB_2U_LIB.S9S_MB_2U(SCH_1):PAGE272_I24@PURE_QUANTA.Q_CAP(CHIPS)':
 'B': CDS_PINID='B';
NODE_NAME     PC526_P1_3 2
 '@S9S_MB_2U_LIB.S9S_MB_2U(SCH_1):PAGE272_I29@PURE_QUANTA.Q_CAP(CHIPS)':
 'B': CDS_PINID='B';
NODE_NAME     PC527_P1_4 2
 '@S9S_MB_2U_LIB.S9S_MB_2U(SCH_1):PAGE272_I33@PURE_QUANTA.Q_CAP(CHIPS)':
 'B': CDS_PINID='B';
NODE_NAME     PC534_P1_3 2
 '@S9S_MB_2U_LIB.S9S_MB_2U(SCH_1):PAGE272_I50@PURE_QUANTA.Q_CAP(CHIPS)':
 'B': CDS_PINID='B';
NODE_NAME     PC538_P1_3 2
 '@S9S_MB_2U_LIB.S9S_MB_2U(SCH_1):PAGE272_I55@PURE_QUANTA.Q_CAP(CHIPS)':
 'B': CDS_PINID='B';
NODE_NAME     PC541_P1_4 2
 '@S9S_MB_2U_LIB.S9S_MB_2U(SCH_1):PAGE272_I58@PURE_QUANTA.Q_CAP(CHIPS)':
 'B': CDS_PINID='B';
NODE_NAME     PC543_P1_4 2
 '@S9S_MB_2U_LIB.S9S_MB_2U(SCH_1):PAGE272_I59@PURE_QUANTA.Q_CAP(CHIPS)':
 'B': CDS_PINID='B';
NODE_NAME     PC542_P1_3 2
 '@S9S_MB_2U_LIB.S9S_MB_2U(SCH_1):PAGE272_I63@PURE_QUANTA.Q_CAP(CHIPS)':
 'B': CDS_PINID='B';
NODE_NAME     PC544_P1_3 2
 '@S9S_MB_2U_LIB.S9S_MB_2U(SCH_1):PAGE272_I64@PURE_QUANTA.Q_CAP(CHIPS)':
 'B': CDS_PINID='B';
NODE_NAME     PU28_P1_3 2
 '@S9S_MB_2U_LIB.S9S_MB_2U(SCH_1):PAGE272_I66@PURE_QUANTA.ISL99390FRZTR5935(CHIPS)':
 'AGND': CDS_PINID='AGND';
NODE_NAME     PU28_P1_3 5
 '@S9S_MB_2U_LIB.S9S_MB_2U(SCH_1):PAGE272_I66@PURE_QUANTA.ISL99390FRZTR5935(CHIPS)':
 'PGND1': CDS_PINID='PGND1';
NODE_NAME     PU28_P1_3 7_9-20_24
 '@S9S_MB_2U_LIB.S9S_MB_2U(SCH_1):PAGE272_I66@PURE_QUANTA.ISL99390FRZTR5935(CHIPS)':
 'PGND2': CDS_PINID='PGND2';
NODE_NAME     PU28_P1_3 40
 '@S9S_MB_2U_LIB.S9S_MB_2U(SCH_1):PAGE272_I66@PURE_QUANTA.ISL99390FRZTR5935(CHIPS)':
 'PGND3': CDS_PINID='PGND3';
NODE_NAME     PR292 2
 '@S9S_MB_2U_LIB.S9S_MB_2U(SCH_1):PAGE273_I7@PURE_QUANTA.Q_RES(CHIPS)':
 'B': CDS_PINID='B';
NODE_NAME     PC1360 1
 '@S9S_MB_2U_LIB.S9S_MB_2U(SCH_1):PAGE273_I15@PURE_QUANTA.Q_CAP(CHIPS)':
 'A': CDS_PINID='A';
NODE_NAME     PU25_P1_6 2
 '@S9S_MB_2U_LIB.S9S_MB_2U(SCH_1):PAGE273_I16@PURE_QUANTA.ISL99390FRZTR5935(CHIPS)':
 'AGND': CDS_PINID='AGND';
NODE_NAME     PU25_P1_6 5
 '@S9S_MB_2U_LIB.S9S_MB_2U(SCH_1):PAGE273_I16@PURE_QUANTA.ISL99390FRZTR5935(CHIPS)':
 'PGND1': CDS_PINID='PGND1';
NODE_NAME     PU25_P1_6 7_9-20_24
 '@S9S_MB_2U_LIB.S9S_MB_2U(SCH_1):PAGE273_I16@PURE_QUANTA.ISL99390FRZTR5935(CHIPS)':
 'PGND2': CDS_PINID='PGND2';
NODE_NAME     PU25_P1_6 40
 '@S9S_MB_2U_LIB.S9S_MB_2U(SCH_1):PAGE273_I16@PURE_QUANTA.ISL99390FRZTR5935(CHIPS)':
 'PGND3': CDS_PINID='PGND3';
NODE_NAME     PC501 2
 '@S9S_MB_2U_LIB.S9S_MB_2U(SCH_1):PAGE273_I17@PURE_QUANTA.Q_CAP(CHIPS)':
 'B': CDS_PINID='B';
NODE_NAME     PC511_P1_6 2
 '@S9S_MB_2U_LIB.S9S_MB_2U(SCH_1):PAGE273_I33@PURE_QUANTA.Q_CAP(CHIPS)':
 'B': CDS_PINID='B';
NODE_NAME     PC515_P1_6 2
 '@S9S_MB_2U_LIB.S9S_MB_2U(SCH_1):PAGE273_I35@PURE_QUANTA.Q_CAP(CHIPS)':
 'B': CDS_PINID='B';
NODE_NAME     PC508_P1_5 2
 '@S9S_MB_2U_LIB.S9S_MB_2U(SCH_1):PAGE273_I46@PURE_QUANTA.Q_CAP(CHIPS)':
 'B': CDS_PINID='B';
NODE_NAME     PC514_P1_5 2
 '@S9S_MB_2U_LIB.S9S_MB_2U(SCH_1):PAGE273_I51@PURE_QUANTA.Q_CAP(CHIPS)':
 'B': CDS_PINID='B';
NODE_NAME     PC516_P1_5 2
 '@S9S_MB_2U_LIB.S9S_MB_2U(SCH_1):PAGE273_I52@PURE_QUANTA.Q_CAP(CHIPS)':
 'B': CDS_PINID='B';
NODE_NAME     PC521_P1_6 2
 '@S9S_MB_2U_LIB.S9S_MB_2U(SCH_1):PAGE273_I57@PURE_QUANTA.Q_CAP(CHIPS)':
 'B': CDS_PINID='B';
NODE_NAME     PC520_P1_5 2
 '@S9S_MB_2U_LIB.S9S_MB_2U(SCH_1):PAGE273_I64@PURE_QUANTA.Q_CAP(CHIPS)':
 'B': CDS_PINID='B';
NODE_NAME     PC522_P1_5 2
 '@S9S_MB_2U_LIB.S9S_MB_2U(SCH_1):PAGE273_I65@PURE_QUANTA.Q_CAP(CHIPS)':
 'B': CDS_PINID='B';
NODE_NAME     PR285 2
 '@S9S_MB_2U_LIB.S9S_MB_2U(SCH_1):PAGE274_I3@PURE_QUANTA.Q_RES(CHIPS)':
 'B': CDS_PINID='B';
NODE_NAME     PC1362 1
 '@S9S_MB_2U_LIB.S9S_MB_2U(SCH_1):PAGE274_I7@PURE_QUANTA.Q_CAP(CHIPS)':
 'A': CDS_PINID='A';
NODE_NAME     PU23_P1_8 2
 '@S9S_MB_2U_LIB.S9S_MB_2U(SCH_1):PAGE274_I11@PURE_QUANTA.ISL99390FRZTR5935(CHIPS)':
 'AGND': CDS_PINID='AGND';
NODE_NAME     PU23_P1_8 5
 '@S9S_MB_2U_LIB.S9S_MB_2U(SCH_1):PAGE274_I11@PURE_QUANTA.ISL99390FRZTR5935(CHIPS)':
 'PGND1': CDS_PINID='PGND1';
NODE_NAME     PU23_P1_8 7_9-20_24
 '@S9S_MB_2U_LIB.S9S_MB_2U(SCH_1):PAGE274_I11@PURE_QUANTA.ISL99390FRZTR5935(CHIPS)':
 'PGND2': CDS_PINID='PGND2';
NODE_NAME     PU23_P1_8 40
 '@S9S_MB_2U_LIB.S9S_MB_2U(SCH_1):PAGE274_I11@PURE_QUANTA.ISL99390FRZTR5935(CHIPS)':
 'PGND3': CDS_PINID='PGND3';
NODE_NAME     PR286 2
 '@S9S_MB_2U_LIB.S9S_MB_2U(SCH_1):PAGE274_I15@PURE_QUANTA.Q_RES(CHIPS)':
 'B': CDS_PINID='B';
NODE_NAME     PU24_P1_7 2
 '@S9S_MB_2U_LIB.S9S_MB_2U(SCH_1):PAGE274_I20@PURE_QUANTA.ISL99390FRZTR5935(CHIPS)':
 'AGND': CDS_PINID='AGND';
NODE_NAME     PU24_P1_7 5
 '@S9S_MB_2U_LIB.S9S_MB_2U(SCH_1):PAGE274_I20@PURE_QUANTA.ISL99390FRZTR5935(CHIPS)':
 'PGND1': CDS_PINID='PGND1';
NODE_NAME     PU24_P1_7 7_9-20_24
 '@S9S_MB_2U_LIB.S9S_MB_2U(SCH_1):PAGE274_I20@PURE_QUANTA.ISL99390FRZTR5935(CHIPS)':
 'PGND2': CDS_PINID='PGND2';
NODE_NAME     PU24_P1_7 40
 '@S9S_MB_2U_LIB.S9S_MB_2U(SCH_1):PAGE274_I20@PURE_QUANTA.ISL99390FRZTR5935(CHIPS)':
 'PGND3': CDS_PINID='PGND3';
NODE_NAME     PL106 2
 '@S9S_MB_2U_LIB.S9S_MB_2U(SCH_1):PAGE274_I23@PURE_QUANTA.Q_INDUCTOR(CHIPS)':
 '2': CDS_PINID='\2\';
NODE_NAME     PC483_P1_8 2
 '@S9S_MB_2U_LIB.S9S_MB_2U(SCH_1):PAGE274_I24@PURE_QUANTA.Q_CAP(CHIPS)':
 'B': CDS_PINID='B';
NODE_NAME     PC485_P1_8 2
 '@S9S_MB_2U_LIB.S9S_MB_2U(SCH_1):PAGE274_I27@PURE_QUANTA.Q_CAP(CHIPS)':
 'B': CDS_PINID='B';
NODE_NAME     PL25 3
 '@S9S_MB_2U_LIB.S9S_MB_2U(SCH_1):PAGE274_I58@PURE_QUANTA.Q_INDUCTOR4P_14(CHIPS)':
 '3': CDS_PINID='\3\';
NODE_NAME     PC492_P1_7 2
 '@S9S_MB_2U_LIB.S9S_MB_2U(SCH_1):PAGE274_I61@PURE_QUANTA.Q_CAP(CHIPS)':
 'B': CDS_PINID='B';
NODE_NAME     PC494_P1_7 2
 '@S9S_MB_2U_LIB.S9S_MB_2U(SCH_1):PAGE274_I62@PURE_QUANTA.Q_CAP(CHIPS)':
 'B': CDS_PINID='B';
NODE_NAME     PC496_P1_7 2
 '@S9S_MB_2U_LIB.S9S_MB_2U(SCH_1):PAGE274_I64@PURE_QUANTA.Q_CAP(CHIPS)':
 'B': CDS_PINID='B';
NODE_NAME     PC498_P1_7 2
 '@S9S_MB_2U_LIB.S9S_MB_2U(SCH_1):PAGE274_I65@PURE_QUANTA.Q_CAP(CHIPS)':
 'B': CDS_PINID='B';
NODE_NAME     PC500_P1_7 2
 '@S9S_MB_2U_LIB.S9S_MB_2U(SCH_1):PAGE274_I66@PURE_QUANTA.Q_CAP(CHIPS)':
 'B': CDS_PINID='B';
NODE_NAME     PC482_P1_7 2
 '@S9S_MB_2U_LIB.S9S_MB_2U(SCH_1):PAGE274_I69@PURE_QUANTA.Q_CAP(CHIPS)':
 'B': CDS_PINID='B';
NODE_NAME     PC1367 1
 '@S9S_MB_2U_LIB.S9S_MB_2U(SCH_1):PAGE275_I29@PURE_QUANTA.Q_CAP(CHIPS)':
 'A': CDS_PINID='A';
NODE_NAME     PC404_P1_2 2
 '@S9S_MB_2U_LIB.S9S_MB_2U(SCH_1):PAGE275_I40@PURE_QUANTA.Q_CAP(CHIPS)':
 'B': CDS_PINID='B';
NODE_NAME     PC399_P1_1 2
 '@S9S_MB_2U_LIB.S9S_MB_2U(SCH_1):PAGE275_I51@PURE_QUANTA.Q_CAP(CHIPS)':
 'B': CDS_PINID='B';
NODE_NAME     PC403_P1_1 2
 '@S9S_MB_2U_LIB.S9S_MB_2U(SCH_1):PAGE275_I52@PURE_QUANTA.Q_CAP(CHIPS)':
 'B': CDS_PINID='B';
NODE_NAME     PC411_P1_2 2
 '@S9S_MB_2U_LIB.S9S_MB_2U(SCH_1):PAGE275_I62@PURE_QUANTA.Q_CAP(CHIPS)':
 'B': CDS_PINID='B';
NODE_NAME     PC1678 2
 '@S9S_MB_2U_LIB.S9S_MB_2U(SCH_1):PAGE275_I83@PURE_QUANTA.Q_CAP(CHIPS)':
 'B': CDS_PINID='B';
NODE_NAME     PU78_P1_4 2
 '@S9S_MB_2U_LIB.S9S_MB_2U(SCH_1):PAGE276_I15@PURE_QUANTA.ISL99390FRZTR5935(CHIPS)':
 'AGND': CDS_PINID='AGND';
NODE_NAME     PU78_P1_4 5
 '@S9S_MB_2U_LIB.S9S_MB_2U(SCH_1):PAGE276_I15@PURE_QUANTA.ISL99390FRZTR5935(CHIPS)':
 'PGND1': CDS_PINID='PGND1';
NODE_NAME     PU78_P1_4 7_9-20_24
 '@S9S_MB_2U_LIB.S9S_MB_2U(SCH_1):PAGE276_I15@PURE_QUANTA.ISL99390FRZTR5935(CHIPS)':
 'PGND2': CDS_PINID='PGND2';
NODE_NAME     PU78_P1_4 40
 '@S9S_MB_2U_LIB.S9S_MB_2U(SCH_1):PAGE276_I15@PURE_QUANTA.ISL99390FRZTR5935(CHIPS)':
 'PGND3': CDS_PINID='PGND3';
NODE_NAME     PC1191 2
 '@S9S_MB_2U_LIB.S9S_MB_2U(SCH_1):PAGE276_I27@PURE_QUANTA.Q_CAP(CHIPS)':
 'B': CDS_PINID='B';
NODE_NAME     PC1202_P1_4 2
 '@S9S_MB_2U_LIB.S9S_MB_2U(SCH_1):PAGE276_I37@PURE_QUANTA.Q_CAP(CHIPS)':
 'B': CDS_PINID='B';
NODE_NAME     PC1195_P1_3 2
 '@S9S_MB_2U_LIB.S9S_MB_2U(SCH_1):PAGE276_I39@PURE_QUANTA.Q_CAP(CHIPS)':
 'B': CDS_PINID='B';
NODE_NAME     PC1201_P1_3 2
 '@S9S_MB_2U_LIB.S9S_MB_2U(SCH_1):PAGE276_I42@PURE_QUANTA.Q_CAP(CHIPS)':
 'B': CDS_PINID='B';
NODE_NAME     PC1206_P1_3 2
 '@S9S_MB_2U_LIB.S9S_MB_2U(SCH_1):PAGE276_I66@PURE_QUANTA.Q_CAP(CHIPS)':
 'B': CDS_PINID='B';
NODE_NAME     PC1684 2
 '@S9S_MB_2U_LIB.S9S_MB_2U(SCH_1):PAGE276_I80@PURE_QUANTA.Q_CAP(CHIPS)':
 'B': CDS_PINID='B';
NODE_NAME     PC475 2
 '@S9S_MB_2U_LIB.S9S_MB_2U(SCH_1):PAGE278_I66@PURE_QUANTA.Q_CAP(CHIPS)':
 'B': CDS_PINID='B';
NODE_NAME     PR1726 2
 '@S9S_MB_2U_LIB.S9S_MB_2U(SCH_1):PAGE279_I16@PURE_QUANTA.Q_RES(CHIPS)':
 'B': CDS_PINID='B';
NODE_NAME     PU51_P1_2 2
 '@S9S_MB_2U_LIB.S9S_MB_2U(SCH_1):PAGE279_I29@PURE_QUANTA.ISL99390FRZTR5935(CHIPS)':
 'AGND': CDS_PINID='AGND';
NODE_NAME     PU51_P1_2 5
 '@S9S_MB_2U_LIB.S9S_MB_2U(SCH_1):PAGE279_I29@PURE_QUANTA.ISL99390FRZTR5935(CHIPS)':
 'PGND1': CDS_PINID='PGND1';
NODE_NAME     PU51_P1_2 7_9-20_24
 '@S9S_MB_2U_LIB.S9S_MB_2U(SCH_1):PAGE279_I29@PURE_QUANTA.ISL99390FRZTR5935(CHIPS)':
 'PGND2': CDS_PINID='PGND2';
NODE_NAME     PU51_P1_2 40
 '@S9S_MB_2U_LIB.S9S_MB_2U(SCH_1):PAGE279_I29@PURE_QUANTA.ISL99390FRZTR5935(CHIPS)':
 'PGND3': CDS_PINID='PGND3';
NODE_NAME     PC456_P1_2 2
 '@S9S_MB_2U_LIB.S9S_MB_2U(SCH_1):PAGE279_I32@PURE_QUANTA.Q_CAP(CHIPS)':
 'B': CDS_PINID='B';
NODE_NAME     PC445_P1_2 2
 '@S9S_MB_2U_LIB.S9S_MB_2U(SCH_1):PAGE279_I37@PURE_QUANTA.Q_CAP(CHIPS)':
 'B': CDS_PINID='B';
NODE_NAME     PC451_P1_2 2
 '@S9S_MB_2U_LIB.S9S_MB_2U(SCH_1):PAGE279_I45@PURE_QUANTA.Q_CAP(CHIPS)':
 'B': CDS_PINID='B';
NODE_NAME     PC450_P1_1 2
 '@S9S_MB_2U_LIB.S9S_MB_2U(SCH_1):PAGE279_I53@PURE_QUANTA.Q_CAP(CHIPS)':
 'B': CDS_PINID='B';
NODE_NAME     PC1595 2
 '@S9S_MB_2U_LIB.S9S_MB_2U(SCH_1):PAGE279_I60@PURE_QUANTA.Q_CAPP(CHIPS)':
 'B': CDS_PINID='B';
NODE_NAME     PC1588 2
 '@S9S_MB_2U_LIB.S9S_MB_2U(SCH_1):PAGE279_I61@PURE_QUANTA.Q_CAPP(CHIPS)':
 'B': CDS_PINID='B';
NODE_NAME     PC455_P1_1 2
 '@S9S_MB_2U_LIB.S9S_MB_2U(SCH_1):PAGE279_I63@PURE_QUANTA.Q_CAP(CHIPS)':
 'B': CDS_PINID='B';
NODE_NAME     PC461 2
 '@S9S_MB_2U_LIB.S9S_MB_2U(SCH_1):PAGE279_I70@PURE_QUANTA.Q_CAPP(CHIPS)':
 'B': CDS_PINID='B';
NODE_NAME     PC430 2
 '@S9S_MB_2U_LIB.S9S_MB_2U(SCH_1):PAGE280_I26@PURE_QUANTA.Q_CAP(CHIPS)':
 'B': CDS_PINID='B';
NODE_NAME     PC433 2
 '@S9S_MB_2U_LIB.S9S_MB_2U(SCH_1):PAGE280_I28@PURE_QUANTA.Q_CAP(CHIPS)':
 'B': CDS_PINID='B';
NODE_NAME     PC434 2
 '@S9S_MB_2U_LIB.S9S_MB_2U(SCH_1):PAGE280_I29@PURE_QUANTA.Q_CAP(CHIPS)':
 'B': CDS_PINID='B';
NODE_NAME     PR218 2
 '@S9S_MB_2U_LIB.S9S_MB_2U(SCH_1):PAGE282_I48@PURE_QUANTA.Q_RES(CHIPS)':
 'B': CDS_PINID='B';
NODE_NAME     PC390 2
 '@S9S_MB_2U_LIB.S9S_MB_2U(SCH_1):PAGE282_I50@PURE_QUANTA.Q_CAP(CHIPS)':
 'B': CDS_PINID='B';
NODE_NAME     PU18 20
 '@S9S_MB_2U_LIB.S9S_MB_2U(SCH_1):PAGE282_I53@PURE_QUANTA.ISL69260IRAZT(CHIPS)':
 'EN1': CDS_PINID='EN1';
NODE_NAME     PU18 31
 '@S9S_MB_2U_LIB.S9S_MB_2U(SCH_1):PAGE282_I53@PURE_QUANTA.ISL69260IRAZT(CHIPS)':
 'RGND1': CDS_PINID='RGND1';
NODE_NAME     PU18 TH
 '@S9S_MB_2U_LIB.S9S_MB_2U(SCH_1):PAGE282_I53@PURE_QUANTA.ISL69260IRAZT(CHIPS)':
 'TH_GND': CDS_PINID='TH_GND';
NODE_NAME     PU18 32
 '@S9S_MB_2U_LIB.S9S_MB_2U(SCH_1):PAGE282_I53@PURE_QUANTA.ISL69260IRAZT(CHIPS)':
 'VSEN1': CDS_PINID='VSEN1';
NODE_NAME     PR1315 2
 '@S9S_MB_2U_LIB.S9S_MB_2U(SCH_1):PAGE282_I60@PURE_QUANTA.Q_RES(CHIPS)':
 'B': CDS_PINID='B';
NODE_NAME     PR4256 2
 '@S9S_MB_2U_LIB.S9S_MB_2U(SCH_1):PAGE282_I63@PURE_QUANTA.Q_RES(CHIPS)':
 'B': CDS_PINID='B';
NODE_NAME     PC375 2
 '@S9S_MB_2U_LIB.S9S_MB_2U(SCH_1):PAGE283_I22@PURE_QUANTA.Q_CAP(CHIPS)':
 'B': CDS_PINID='B';
NODE_NAME     PC1262 2
 '@S9S_MB_2U_LIB.S9S_MB_2U(SCH_1):PAGE285_I17@PURE_QUANTA.Q_CAP(CHIPS)':
 'B': CDS_PINID='B';
NODE_NAME     C1308 2
 '@S9S_MB_2U_LIB.S9S_MB_2U(SCH_1):PAGE286_I6@PURE_QUANTA.Q_CAP(CHIPS)':
 'B': CDS_PINID='B';
NODE_NAME     PR51 2
 '@S9S_MB_2U_LIB.S9S_MB_2U(SCH_1):PAGE286_I26@PURE_QUANTA.Q_RES(CHIPS)':
 'B': CDS_PINID='B';
NODE_NAME     C2358 2
 '@S9S_MB_2U_LIB.S9S_MB_2U(SCH_1):PAGE159_I100@PURE_QUANTA.Q_CAP(CHIPS)':
 'B': CDS_PINID='B';
NODE_NAME     C1273 2
 '@S9S_MB_2U_LIB.S9S_MB_2U(SCH_1):PAGE181_I151@PURE_QUANTA.Q_CAP(CHIPS)':
 'B': CDS_PINID='B';
NODE_NAME     C1244 2
 '@S9S_MB_2U_LIB.S9S_MB_2U(SCH_1):PAGE181_I152@PURE_QUANTA.Q_CAP(CHIPS)':
 'B': CDS_PINID='B';
NODE_NAME     C1246 2
 '@S9S_MB_2U_LIB.S9S_MB_2U(SCH_1):PAGE181_I153@PURE_QUANTA.Q_CAP(CHIPS)':
 'B': CDS_PINID='B';
NODE_NAME     C1247 2
 '@S9S_MB_2U_LIB.S9S_MB_2U(SCH_1):PAGE181_I154@PURE_QUANTA.Q_CAP(CHIPS)':
 'B': CDS_PINID='B';
NODE_NAME     C1248 2
 '@S9S_MB_2U_LIB.S9S_MB_2U(SCH_1):PAGE181_I155@PURE_QUANTA.Q_CAP(CHIPS)':
 'B': CDS_PINID='B';
NODE_NAME     C1249 2
 '@S9S_MB_2U_LIB.S9S_MB_2U(SCH_1):PAGE181_I156@PURE_QUANTA.Q_CAP(CHIPS)':
 'B': CDS_PINID='B';
NODE_NAME     C1258 2
 '@S9S_MB_2U_LIB.S9S_MB_2U(SCH_1):PAGE181_I157@PURE_QUANTA.Q_CAP(CHIPS)':
 'B': CDS_PINID='B';
NODE_NAME     C1259 2
 '@S9S_MB_2U_LIB.S9S_MB_2U(SCH_1):PAGE181_I158@PURE_QUANTA.Q_CAP(CHIPS)':
 'B': CDS_PINID='B';
NODE_NAME     C1272 2
 '@S9S_MB_2U_LIB.S9S_MB_2U(SCH_1):PAGE181_I159@PURE_QUANTA.Q_CAP(CHIPS)':
 'B': CDS_PINID='B';
NODE_NAME     J90 G1
 '@S9S_MB_2U_LIB.S9S_MB_2U(SCH_1):PAGE297_I318@PURE_QUANTA.SCONN56_123276793(CHIPS)':
 'G1': CDS_PINID='G1';
NODE_NAME     J90 G2
 '@S9S_MB_2U_LIB.S9S_MB_2U(SCH_1):PAGE297_I318@PURE_QUANTA.SCONN56_123276793(CHIPS)':
 'G2': CDS_PINID='G2';
NODE_NAME     J90 A1
 '@S9S_MB_2U_LIB.S9S_MB_2U(SCH_1):PAGE297_I318@PURE_QUANTA.SCONN56_123276793(CHIPS)':
 'GND_A1': CDS_PINID='GND_A1';
NODE_NAME     J90 A2
 '@S9S_MB_2U_LIB.S9S_MB_2U(SCH_1):PAGE297_I318@PURE_QUANTA.SCONN56_123276793(CHIPS)':
 'GND_A2': CDS_PINID='GND_A2';
NODE_NAME     J90 A3
 '@S9S_MB_2U_LIB.S9S_MB_2U(SCH_1):PAGE297_I318@PURE_QUANTA.SCONN56_123276793(CHIPS)':
 'GND_A3': CDS_PINID='GND_A3';
NODE_NAME     J90 A4
 '@S9S_MB_2U_LIB.S9S_MB_2U(SCH_1):PAGE297_I318@PURE_QUANTA.SCONN56_123276793(CHIPS)':
 'GND_A4': CDS_PINID='GND_A4';
NODE_NAME     J90 A5
 '@S9S_MB_2U_LIB.S9S_MB_2U(SCH_1):PAGE297_I318@PURE_QUANTA.SCONN56_123276793(CHIPS)':
 'GND_A5': CDS_PINID='GND_A5';
NODE_NAME     J90 A6
 '@S9S_MB_2U_LIB.S9S_MB_2U(SCH_1):PAGE297_I318@PURE_QUANTA.SCONN56_123276793(CHIPS)':
 'GND_A6': CDS_PINID='GND_A6';
NODE_NAME     J90 A13
 '@S9S_MB_2U_LIB.S9S_MB_2U(SCH_1):PAGE297_I318@PURE_QUANTA.SCONN56_123276793(CHIPS)':
 'GND_A13': CDS_PINID='GND_A13';
NODE_NAME     J90 A16
 '@S9S_MB_2U_LIB.S9S_MB_2U(SCH_1):PAGE297_I318@PURE_QUANTA.SCONN56_123276793(CHIPS)':
 'GND_A16': CDS_PINID='GND_A16';
NODE_NAME     J90 A19
 '@S9S_MB_2U_LIB.S9S_MB_2U(SCH_1):PAGE297_I318@PURE_QUANTA.SCONN56_123276793(CHIPS)':
 'GND_A19': CDS_PINID='GND_A19';
NODE_NAME     J90 A22
 '@S9S_MB_2U_LIB.S9S_MB_2U(SCH_1):PAGE297_I318@PURE_QUANTA.SCONN56_123276793(CHIPS)':
 'GND_A22': CDS_PINID='GND_A22';
NODE_NAME     J90 A25
 '@S9S_MB_2U_LIB.S9S_MB_2U(SCH_1):PAGE297_I318@PURE_QUANTA.SCONN56_123276793(CHIPS)':
 'GND_A25': CDS_PINID='GND_A25';
NODE_NAME     J90 A28
 '@S9S_MB_2U_LIB.S9S_MB_2U(SCH_1):PAGE297_I318@PURE_QUANTA.SCONN56_123276793(CHIPS)':
 'GND_A28': CDS_PINID='GND_A28';
NODE_NAME     J90 B13
 '@S9S_MB_2U_LIB.S9S_MB_2U(SCH_1):PAGE297_I318@PURE_QUANTA.SCONN56_123276793(CHIPS)':
 'GND_B13': CDS_PINID='GND_B13';
NODE_NAME     J90 B16
 '@S9S_MB_2U_LIB.S9S_MB_2U(SCH_1):PAGE297_I318@PURE_QUANTA.SCONN56_123276793(CHIPS)':
 'GND_B16': CDS_PINID='GND_B16';
NODE_NAME     J90 B19
 '@S9S_MB_2U_LIB.S9S_MB_2U(SCH_1):PAGE297_I318@PURE_QUANTA.SCONN56_123276793(CHIPS)':
 'GND_B19': CDS_PINID='GND_B19';
NODE_NAME     J90 B22
 '@S9S_MB_2U_LIB.S9S_MB_2U(SCH_1):PAGE297_I318@PURE_QUANTA.SCONN56_123276793(CHIPS)':
 'GND_B22': CDS_PINID='GND_B22';
NODE_NAME     J90 B25
 '@S9S_MB_2U_LIB.S9S_MB_2U(SCH_1):PAGE297_I318@PURE_QUANTA.SCONN56_123276793(CHIPS)':
 'GND_B25': CDS_PINID='GND_B25';
NODE_NAME     J90 B28
 '@S9S_MB_2U_LIB.S9S_MB_2U(SCH_1):PAGE297_I318@PURE_QUANTA.SCONN56_123276793(CHIPS)':
 'GND_B28': CDS_PINID='GND_B28';
NODE_NAME     U248 3
 '@S9S_MB_2U_LIB.S9S_MB_2U(SCH_1):PAGE201_I158@PURE_QUANTA.74LVC1G32GW(CHIPS)':
 'GND': CDS_PINID='GND';
NODE_NAME     R4095 2
 '@S9S_MB_2U_LIB.S9S_MB_2U(SCH_1):PAGE175_I284@PURE_QUANTA.Q_RES(CHIPS)':
 'B': CDS_PINID='B';
NODE_NAME     R4096 2
 '@S9S_MB_2U_LIB.S9S_MB_2U(SCH_1):PAGE175_I285@PURE_QUANTA.Q_RES(CHIPS)':
 'B': CDS_PINID='B';
NODE_NAME     R4097 2
 '@S9S_MB_2U_LIB.S9S_MB_2U(SCH_1):PAGE175_I286@PURE_QUANTA.Q_RES(CHIPS)':
 'B': CDS_PINID='B';
NODE_NAME     R4098 2
 '@S9S_MB_2U_LIB.S9S_MB_2U(SCH_1):PAGE175_I287@PURE_QUANTA.Q_RES(CHIPS)':
 'B': CDS_PINID='B';
NODE_NAME     R4099 2
 '@S9S_MB_2U_LIB.S9S_MB_2U(SCH_1):PAGE175_I288@PURE_QUANTA.Q_RES(CHIPS)':
 'B': CDS_PINID='B';
NODE_NAME     R4105 2
 '@S9S_MB_2U_LIB.S9S_MB_2U(SCH_1):PAGE176_I183@PURE_QUANTA.Q_RES(CHIPS)':
 'B': CDS_PINID='B';
NODE_NAME     R4106 2
 '@S9S_MB_2U_LIB.S9S_MB_2U(SCH_1):PAGE176_I184@PURE_QUANTA.Q_RES(CHIPS)':
 'B': CDS_PINID='B';
NODE_NAME     R4104 2
 '@S9S_MB_2U_LIB.S9S_MB_2U(SCH_1):PAGE176_I185@PURE_QUANTA.Q_RES(CHIPS)':
 'B': CDS_PINID='B';
NODE_NAME     R4103 2
 '@S9S_MB_2U_LIB.S9S_MB_2U(SCH_1):PAGE176_I186@PURE_QUANTA.Q_RES(CHIPS)':
 'B': CDS_PINID='B';
NODE_NAME     R4109 2
 '@S9S_MB_2U_LIB.S9S_MB_2U(SCH_1):PAGE176_I195@PURE_QUANTA.Q_RES(CHIPS)':
 'B': CDS_PINID='B';
NODE_NAME     R4108 2
 '@S9S_MB_2U_LIB.S9S_MB_2U(SCH_1):PAGE176_I196@PURE_QUANTA.Q_RES(CHIPS)':
 'B': CDS_PINID='B';
NODE_NAME     R4107 2
 '@S9S_MB_2U_LIB.S9S_MB_2U(SCH_1):PAGE176_I197@PURE_QUANTA.Q_RES(CHIPS)':
 'B': CDS_PINID='B';
NODE_NAME     R4115 2
 '@S9S_MB_2U_LIB.S9S_MB_2U(SCH_1):PAGE176_I201@PURE_QUANTA.Q_RES(CHIPS)':
 'B': CDS_PINID='B';
NODE_NAME     R4110 2
 '@S9S_MB_2U_LIB.S9S_MB_2U(SCH_1):PAGE176_I202@PURE_QUANTA.Q_RES(CHIPS)':
 'B': CDS_PINID='B';
NODE_NAME     R4112 2
 '@S9S_MB_2U_LIB.S9S_MB_2U(SCH_1):PAGE176_I203@PURE_QUANTA.Q_RES(CHIPS)':
 'B': CDS_PINID='B';
NODE_NAME     R4111 2
 '@S9S_MB_2U_LIB.S9S_MB_2U(SCH_1):PAGE176_I204@PURE_QUANTA.Q_RES(CHIPS)':
 'B': CDS_PINID='B';
NODE_NAME     R4114 2
 '@S9S_MB_2U_LIB.S9S_MB_2U(SCH_1):PAGE176_I205@PURE_QUANTA.Q_RES(CHIPS)':
 'B': CDS_PINID='B';
NODE_NAME     R4113 2
 '@S9S_MB_2U_LIB.S9S_MB_2U(SCH_1):PAGE176_I206@PURE_QUANTA.Q_RES(CHIPS)':
 'B': CDS_PINID='B';
NODE_NAME     R4116 2
 '@S9S_MB_2U_LIB.S9S_MB_2U(SCH_1):PAGE176_I207@PURE_QUANTA.Q_RES(CHIPS)':
 'B': CDS_PINID='B';
NODE_NAME     R4117 2
 '@S9S_MB_2U_LIB.S9S_MB_2U(SCH_1):PAGE176_I209@PURE_QUANTA.Q_RES(CHIPS)':
 'B': CDS_PINID='B';
NODE_NAME     R4102 2
 '@S9S_MB_2U_LIB.S9S_MB_2U(SCH_1):PAGE175_I298@PURE_QUANTA.Q_RES(CHIPS)':
 'B': CDS_PINID='B';
NODE_NAME     R4101 2
 '@S9S_MB_2U_LIB.S9S_MB_2U(SCH_1):PAGE175_I299@PURE_QUANTA.Q_RES(CHIPS)':
 'B': CDS_PINID='B';
NODE_NAME     R4100 2
 '@S9S_MB_2U_LIB.S9S_MB_2U(SCH_1):PAGE175_I300@PURE_QUANTA.Q_RES(CHIPS)':
 'B': CDS_PINID='B';
NODE_NAME     C2264 2
 '@S9S_MB_2U_LIB.S9S_MB_2U(SCH_1):PAGE143_I2@PURE_QUANTA.Q_CAP(CHIPS)':
 'B': CDS_PINID='B';
NODE_NAME     Q128 4
 '@S9S_MB_2U_LIB.S9S_MB_2U(SCH_1):PAGE143_I6@PURE_QUANTA.MOSFET_NCH_DUAL(CHIPS)':
 'S2': CDS_PINID='S2';
NODE_NAME     Q128 1
 '@S9S_MB_2U_LIB.S9S_MB_2U(SCH_1):PAGE143_I11@PURE_QUANTA.MOSFET_NCH_DUAL(CHIPS)':
 'S1': CDS_PINID='S1';
NODE_NAME     R4120 2
 '@S9S_MB_2U_LIB.S9S_MB_2U(SCH_1):PAGE143_I14@PURE_QUANTA.Q_RES(CHIPS)':
 'B': CDS_PINID='B';
NODE_NAME     Q131 4
 '@S9S_MB_2U_LIB.S9S_MB_2U(SCH_1):PAGE143_I19@PURE_QUANTA.MOSFET_NCH_DUAL(CHIPS)':
 'S2': CDS_PINID='S2';
NODE_NAME     C2266 2
 '@S9S_MB_2U_LIB.S9S_MB_2U(SCH_1):PAGE143_I23@PURE_QUANTA.Q_CAP(CHIPS)':
 'B': CDS_PINID='B';
NODE_NAME     Q131 1
 '@S9S_MB_2U_LIB.S9S_MB_2U(SCH_1):PAGE143_I29@PURE_QUANTA.MOSFET_NCH_DUAL(CHIPS)':
 'S1': CDS_PINID='S1';
NODE_NAME     R4124 2
 '@S9S_MB_2U_LIB.S9S_MB_2U(SCH_1):PAGE143_I32@PURE_QUANTA.Q_RES(CHIPS)':
 'B': CDS_PINID='B';
NODE_NAME     Q132 4
 '@S9S_MB_2U_LIB.S9S_MB_2U(SCH_1):PAGE143_I35@PURE_QUANTA.MOSFET_NCH_DUAL(CHIPS)':
 'S2': CDS_PINID='S2';
NODE_NAME     C2265 2
 '@S9S_MB_2U_LIB.S9S_MB_2U(SCH_1):PAGE143_I40@PURE_QUANTA.Q_CAP(CHIPS)':
 'B': CDS_PINID='B';
NODE_NAME     Q132 1
 '@S9S_MB_2U_LIB.S9S_MB_2U(SCH_1):PAGE143_I44@PURE_QUANTA.MOSFET_NCH_DUAL(CHIPS)':
 'S1': CDS_PINID='S1';
NODE_NAME     R4122 2
 '@S9S_MB_2U_LIB.S9S_MB_2U(SCH_1):PAGE143_I49@PURE_QUANTA.Q_RES(CHIPS)':
 'B': CDS_PINID='B';
NODE_NAME     C2267 2
 '@S9S_MB_2U_LIB.S9S_MB_2U(SCH_1):PAGE143_I55@PURE_QUANTA.Q_CAP(CHIPS)':
 'B': CDS_PINID='B';
NODE_NAME     C2269 2
 '@S9S_MB_2U_LIB.S9S_MB_2U(SCH_1):PAGE143_I57@PURE_QUANTA.Q_CAP(CHIPS)':
 'B': CDS_PINID='B';
NODE_NAME     C2268 2
 '@S9S_MB_2U_LIB.S9S_MB_2U(SCH_1):PAGE143_I66@PURE_QUANTA.Q_CAP(CHIPS)':
 'B': CDS_PINID='B';
NODE_NAME     Q130 4
 '@S9S_MB_2U_LIB.S9S_MB_2U(SCH_1):PAGE143_I70@PURE_QUANTA.MOSFET_NCH_DUAL(CHIPS)':
 'S2': CDS_PINID='S2';
NODE_NAME     Q133 4
 '@S9S_MB_2U_LIB.S9S_MB_2U(SCH_1):PAGE143_I71@PURE_QUANTA.MOSFET_NCH_DUAL(CHIPS)':
 'S2': CDS_PINID='S2';
NODE_NAME     Q130 1
 '@S9S_MB_2U_LIB.S9S_MB_2U(SCH_1):PAGE143_I74@PURE_QUANTA.MOSFET_NCH_DUAL(CHIPS)':
 'S1': CDS_PINID='S1';
NODE_NAME     Q129 4
 '@S9S_MB_2U_LIB.S9S_MB_2U(SCH_1):PAGE143_I77@PURE_QUANTA.MOSFET_NCH_DUAL(CHIPS)':
 'S2': CDS_PINID='S2';
NODE_NAME     Q133 1
 '@S9S_MB_2U_LIB.S9S_MB_2U(SCH_1):PAGE143_I78@PURE_QUANTA.MOSFET_NCH_DUAL(CHIPS)':
 'S1': CDS_PINID='S1';
NODE_NAME     Q129 1
 '@S9S_MB_2U_LIB.S9S_MB_2U(SCH_1):PAGE143_I83@PURE_QUANTA.MOSFET_NCH_DUAL(CHIPS)':
 'S1': CDS_PINID='S1';
NODE_NAME     R4132 2
 '@S9S_MB_2U_LIB.S9S_MB_2U(SCH_1):PAGE143_I86@PURE_QUANTA.Q_RES(CHIPS)':
 'B': CDS_PINID='B';
NODE_NAME     R4136 2
 '@S9S_MB_2U_LIB.S9S_MB_2U(SCH_1):PAGE143_I91@PURE_QUANTA.Q_RES(CHIPS)':
 'B': CDS_PINID='B';
NODE_NAME     R4134 2
 '@S9S_MB_2U_LIB.S9S_MB_2U(SCH_1):PAGE143_I96@PURE_QUANTA.Q_RES(CHIPS)':
 'B': CDS_PINID='B';
NODE_NAME     Q134 1
 '@S9S_MB_2U_LIB.S9S_MB_2U(SCH_1):PAGE143_I99@PURE_QUANTA.MOSFET_NCH_DUAL(CHIPS)':
 'S1': CDS_PINID='S1';
NODE_NAME     C2270 2
 '@S9S_MB_2U_LIB.S9S_MB_2U(SCH_1):PAGE143_I105@PURE_QUANTA.Q_CAP(CHIPS)':
 'B': CDS_PINID='B';
NODE_NAME     Q134 4
 '@S9S_MB_2U_LIB.S9S_MB_2U(SCH_1):PAGE143_I107@PURE_QUANTA.MOSFET_NCH_DUAL(CHIPS)':
 'S2': CDS_PINID='S2';
NODE_NAME     R4154 2
 '@S9S_MB_2U_LIB.S9S_MB_2U(SCH_1):PAGE143_I113@PURE_QUANTA.Q_RES(CHIPS)':
 'B': CDS_PINID='B';
NODE_NAME     R4161 2
 '@S9S_MB_2U_LIB.S9S_MB_2U(SCH_1):PAGE139_I2@PURE_QUANTA.Q_RES(CHIPS)':
 'B': CDS_PINID='B';
NODE_NAME     R4163 2
 '@S9S_MB_2U_LIB.S9S_MB_2U(SCH_1):PAGE139_I8@PURE_QUANTA.Q_RES(CHIPS)':
 'B': CDS_PINID='B';
NODE_NAME     R4159 2
 '@S9S_MB_2U_LIB.S9S_MB_2U(SCH_1):PAGE139_I13@PURE_QUANTA.Q_RES(CHIPS)':
 'B': CDS_PINID='B';
NODE_NAME     Q136 1
 '@S9S_MB_2U_LIB.S9S_MB_2U(SCH_1):PAGE139_I17@PURE_QUANTA.MOSFET_NCH_DUAL(CHIPS)':
 'S1': CDS_PINID='S1';
NODE_NAME     Q137 1
 '@S9S_MB_2U_LIB.S9S_MB_2U(SCH_1):PAGE139_I21@PURE_QUANTA.MOSFET_NCH_DUAL(CHIPS)':
 'S1': CDS_PINID='S1';
NODE_NAME     Q136 4
 '@S9S_MB_2U_LIB.S9S_MB_2U(SCH_1):PAGE139_I22@PURE_QUANTA.MOSFET_NCH_DUAL(CHIPS)':
 'S2': CDS_PINID='S2';
NODE_NAME     Q135 1
 '@S9S_MB_2U_LIB.S9S_MB_2U(SCH_1):PAGE139_I25@PURE_QUANTA.MOSFET_NCH_DUAL(CHIPS)':
 'S1': CDS_PINID='S1';
NODE_NAME     Q137 4
 '@S9S_MB_2U_LIB.S9S_MB_2U(SCH_1):PAGE139_I28@PURE_QUANTA.MOSFET_NCH_DUAL(CHIPS)':
 'S2': CDS_PINID='S2';
NODE_NAME     Q135 4
 '@S9S_MB_2U_LIB.S9S_MB_2U(SCH_1):PAGE139_I29@PURE_QUANTA.MOSFET_NCH_DUAL(CHIPS)':
 'S2': CDS_PINID='S2';
NODE_NAME     C2272 2
 '@S9S_MB_2U_LIB.S9S_MB_2U(SCH_1):PAGE139_I33@PURE_QUANTA.Q_CAP(CHIPS)':
 'B': CDS_PINID='B';
NODE_NAME     C2273 2
 '@S9S_MB_2U_LIB.S9S_MB_2U(SCH_1):PAGE139_I42@PURE_QUANTA.Q_CAP(CHIPS)':
 'B': CDS_PINID='B';
NODE_NAME     C2271 2
 '@S9S_MB_2U_LIB.S9S_MB_2U(SCH_1):PAGE139_I44@PURE_QUANTA.Q_CAP(CHIPS)':
 'B': CDS_PINID='B';
NODE_NAME     U307 S
 '@S9S_MB_2U_LIB.S9S_MB_2U(SCH_1):PAGE243_I15@PURE_QUANTA.MOSFET_N(CHIPS)':
 'SOURCE': CDS_PINID='SOURCE';
NODE_NAME     Y2 2
 '@S9S_MB_2U_LIB.S9S_MB_2U(SCH_1):PAGE197_I391@PURE_QUANTA.Q_XTAL_4P_13BI_24GND(CHIPS)':
 'G1': CDS_PINID='G1';
NODE_NAME     Y2 4
 '@S9S_MB_2U_LIB.S9S_MB_2U(SCH_1):PAGE197_I391@PURE_QUANTA.Q_XTAL_4P_13BI_24GND(CHIPS)':
 'G2': CDS_PINID='G2';
NODE_NAME     Y3 2
 '@S9S_MB_2U_LIB.S9S_MB_2U(SCH_1):PAGE201_I159@PURE_QUANTA.Q_XTAL_4P_13BI_24GND(CHIPS)':
 'G1': CDS_PINID='G1';
NODE_NAME     Y3 4
 '@S9S_MB_2U_LIB.S9S_MB_2U(SCH_1):PAGE201_I159@PURE_QUANTA.Q_XTAL_4P_13BI_24GND(CHIPS)':
 'G2': CDS_PINID='G2';
NODE_NAME     R4199 2
 '@S9S_MB_2U_LIB.S9S_MB_2U(SCH_1):PAGE161_I81@PURE_QUANTA.Q_RES(CHIPS)':
 'B': CDS_PINID='B';
NODE_NAME     R4207 2
 '@S9S_MB_2U_LIB.S9S_MB_2U(SCH_1):PAGE161_I85@PURE_QUANTA.Q_RES(CHIPS)':
 'B': CDS_PINID='B';
NODE_NAME     R4191 2
 '@S9S_MB_2U_LIB.S9S_MB_2U(SCH_1):PAGE161_I89@PURE_QUANTA.Q_RES(CHIPS)':
 'B': CDS_PINID='B';
NODE_NAME     R4205 2
 '@S9S_MB_2U_LIB.S9S_MB_2U(SCH_1):PAGE161_I96@PURE_QUANTA.Q_RES(CHIPS)':
 'B': CDS_PINID='B';
NODE_NAME     R4197 2
 '@S9S_MB_2U_LIB.S9S_MB_2U(SCH_1):PAGE161_I98@PURE_QUANTA.Q_RES(CHIPS)':
 'B': CDS_PINID='B';
NODE_NAME     R4189 2
 '@S9S_MB_2U_LIB.S9S_MB_2U(SCH_1):PAGE161_I102@PURE_QUANTA.Q_RES(CHIPS)':
 'B': CDS_PINID='B';
NODE_NAME     C2276 2
 '@S9S_MB_2U_LIB.S9S_MB_2U(SCH_1):PAGE161_I104@PURE_QUANTA.Q_CAP(CHIPS)':
 'B': CDS_PINID='B';
NODE_NAME     C2275 2
 '@S9S_MB_2U_LIB.S9S_MB_2U(SCH_1):PAGE161_I119@PURE_QUANTA.Q_CAP(CHIPS)':
 'B': CDS_PINID='B';
NODE_NAME     R4187 2
 '@S9S_MB_2U_LIB.S9S_MB_2U(SCH_1):PAGE161_I121@PURE_QUANTA.Q_RES(CHIPS)':
 'B': CDS_PINID='B';
NODE_NAME     R4195 2
 '@S9S_MB_2U_LIB.S9S_MB_2U(SCH_1):PAGE161_I125@PURE_QUANTA.Q_RES(CHIPS)':
 'B': CDS_PINID='B';
NODE_NAME     R4203 2
 '@S9S_MB_2U_LIB.S9S_MB_2U(SCH_1):PAGE161_I127@PURE_QUANTA.Q_RES(CHIPS)':
 'B': CDS_PINID='B';
NODE_NAME     C2274 2
 '@S9S_MB_2U_LIB.S9S_MB_2U(SCH_1):PAGE161_I139@PURE_QUANTA.Q_CAP(CHIPS)':
 'B': CDS_PINID='B';
NODE_NAME     R4185 2
 '@S9S_MB_2U_LIB.S9S_MB_2U(SCH_1):PAGE161_I141@PURE_QUANTA.Q_RES(CHIPS)':
 'B': CDS_PINID='B';
NODE_NAME     R4193 2
 '@S9S_MB_2U_LIB.S9S_MB_2U(SCH_1):PAGE161_I145@PURE_QUANTA.Q_RES(CHIPS)':
 'B': CDS_PINID='B';
NODE_NAME     R4201 2
 '@S9S_MB_2U_LIB.S9S_MB_2U(SCH_1):PAGE161_I147@PURE_QUANTA.Q_RES(CHIPS)':
 'B': CDS_PINID='B';
NODE_NAME     PR3337 2
 '@S9S_MB_2U_LIB.S9S_MB_2U(SCH_1):PAGE244_I10@PURE_QUANTA.Q_RES(CHIPS)':
 'B': CDS_PINID='B';
NODE_NAME     PR89 2
 '@S9S_MB_2U_LIB.S9S_MB_2U(SCH_1):PAGE244_I16@PURE_QUANTA.Q_RES(CHIPS)':
 'B': CDS_PINID='B';
NODE_NAME     PR158 2
 '@S9S_MB_2U_LIB.S9S_MB_2U(SCH_1):PAGE252_I51@PURE_QUANTA.Q_RES(CHIPS)':
 'B': CDS_PINID='B';
NODE_NAME     PU14 TH
 '@S9S_MB_2U_LIB.S9S_MB_2U(SCH_1):PAGE252_I63@PURE_QUANTA.RAA229126GNPHA0(CHIPS)':
 'TH_GND': CDS_PINID='TH_GND';
NODE_NAME     PR150 2
 '@S9S_MB_2U_LIB.S9S_MB_2U(SCH_1):PAGE253_I2@PURE_QUANTA.Q_RES(CHIPS)':
 'B': CDS_PINID='B';
NODE_NAME     PC296_P0_2 2
 '@S9S_MB_2U_LIB.S9S_MB_2U(SCH_1):PAGE253_I19@PURE_QUANTA.Q_CAP(CHIPS)':
 'B': CDS_PINID='B';
NODE_NAME     PC1356 1
 '@S9S_MB_2U_LIB.S9S_MB_2U(SCH_1):PAGE253_I34@PURE_QUANTA.Q_CAP(CHIPS)':
 'A': CDS_PINID='A';
NODE_NAME     PC303_P0_1 2
 '@S9S_MB_2U_LIB.S9S_MB_2U(SCH_1):PAGE253_I49@PURE_QUANTA.Q_CAP(CHIPS)':
 'B': CDS_PINID='B';
NODE_NAME     PR4219 2
 '@S9S_MB_2U_LIB.S9S_MB_2U(SCH_1):PAGE253_I59@PURE_QUANTA.Q_RES(CHIPS)':
 'B': CDS_PINID='B';
NODE_NAME     PC1920 2
 '@S9S_MB_2U_LIB.S9S_MB_2U(SCH_1):PAGE253_I63@PURE_QUANTA.Q_CAPP(CHIPS)':
 'B': CDS_PINID='B';
NODE_NAME     PC326 2
 '@S9S_MB_2U_LIB.S9S_MB_2U(SCH_1):PAGE253_I66@PURE_QUANTA.Q_CAPP(CHIPS)':
 'B': CDS_PINID='B';
NODE_NAME     PC322 2
 '@S9S_MB_2U_LIB.S9S_MB_2U(SCH_1):PAGE253_I67@PURE_QUANTA.Q_CAPP(CHIPS)':
 'B': CDS_PINID='B';
NODE_NAME     PC307_P0_1 2
 '@S9S_MB_2U_LIB.S9S_MB_2U(SCH_1):PAGE253_I75@PURE_QUANTA.Q_CAP(CHIPS)':
 'B': CDS_PINID='B';
NODE_NAME     PR354 2
 '@S9S_MB_2U_LIB.S9S_MB_2U(SCH_1):PAGE257_I8@PURE_QUANTA.Q_RES(CHIPS)':
 'B': CDS_PINID='B';
NODE_NAME     PU70_P0_2 2
 '@S9S_MB_2U_LIB.S9S_MB_2U(SCH_1):PAGE257_I16@PURE_QUANTA.ISL99390FRZTR5935(CHIPS)':
 'AGND': CDS_PINID='AGND';
NODE_NAME     PU70_P0_2 5
 '@S9S_MB_2U_LIB.S9S_MB_2U(SCH_1):PAGE257_I16@PURE_QUANTA.ISL99390FRZTR5935(CHIPS)':
 'PGND1': CDS_PINID='PGND1';
NODE_NAME     PU70_P0_2 7_9-20_24
 '@S9S_MB_2U_LIB.S9S_MB_2U(SCH_1):PAGE257_I16@PURE_QUANTA.ISL99390FRZTR5935(CHIPS)':
 'PGND2': CDS_PINID='PGND2';
NODE_NAME     PU70_P0_2 40
 '@S9S_MB_2U_LIB.S9S_MB_2U(SCH_1):PAGE257_I16@PURE_QUANTA.ISL99390FRZTR5935(CHIPS)':
 'PGND3': CDS_PINID='PGND3';
NODE_NAME     PC615_P0_1 2
 '@S9S_MB_2U_LIB.S9S_MB_2U(SCH_1):PAGE257_I77@PURE_QUANTA.Q_CAP(CHIPS)':
 'B': CDS_PINID='B';
NODE_NAME     PC221 2
 '@S9S_MB_2U_LIB.S9S_MB_2U(SCH_1):PAGE260_I63@PURE_QUANTA.Q_CAP(CHIPS)':
 'B': CDS_PINID='B';
NODE_NAME     PC2947 2
 '@S9S_MB_2U_LIB.S9S_MB_2U(SCH_1):PAGE261_I29@PURE_QUANTA.Q_CAP(CHIPS)':
 'B': CDS_PINID='B';
NODE_NAME     PC205_P0_2 2
 '@S9S_MB_2U_LIB.S9S_MB_2U(SCH_1):PAGE261_I41@PURE_QUANTA.Q_CAP(CHIPS)':
 'B': CDS_PINID='B';
NODE_NAME     PC1655 2
 '@S9S_MB_2U_LIB.S9S_MB_2U(SCH_1):PAGE261_I60@PURE_QUANTA.Q_CAP(CHIPS)':
 'B': CDS_PINID='B';
NODE_NAME     PC1575 2
 '@S9S_MB_2U_LIB.S9S_MB_2U(SCH_1):PAGE261_I69@PURE_QUANTA.Q_CAPP(CHIPS)':
 'B': CDS_PINID='B';
NODE_NAME     PC208 2
 '@S9S_MB_2U_LIB.S9S_MB_2U(SCH_1):PAGE261_I75@PURE_QUANTA.Q_CAPP(CHIPS)':
 'B': CDS_PINID='B';
NODE_NAME     PU43_P0_1 2
 '@S9S_MB_2U_LIB.S9S_MB_2U(SCH_1):PAGE261_I79@PURE_QUANTA.ISL99390FRZTR5935(CHIPS)':
 'AGND': CDS_PINID='AGND';
NODE_NAME     PU43_P0_1 5
 '@S9S_MB_2U_LIB.S9S_MB_2U(SCH_1):PAGE261_I79@PURE_QUANTA.ISL99390FRZTR5935(CHIPS)':
 'PGND1': CDS_PINID='PGND1';
NODE_NAME     PU43_P0_1 7_9-20_24
 '@S9S_MB_2U_LIB.S9S_MB_2U(SCH_1):PAGE261_I79@PURE_QUANTA.ISL99390FRZTR5935(CHIPS)':
 'PGND2': CDS_PINID='PGND2';
NODE_NAME     PU43_P0_1 40
 '@S9S_MB_2U_LIB.S9S_MB_2U(SCH_1):PAGE261_I79@PURE_QUANTA.ISL99390FRZTR5935(CHIPS)':
 'PGND3': CDS_PINID='PGND3';
NODE_NAME     PC179 2
 '@S9S_MB_2U_LIB.S9S_MB_2U(SCH_1):PAGE262_I26@PURE_QUANTA.Q_CAP(CHIPS)':
 'B': CDS_PINID='B';
NODE_NAME     PC186 2
 '@S9S_MB_2U_LIB.S9S_MB_2U(SCH_1):PAGE262_I32@PURE_QUANTA.Q_CAP(CHIPS)':
 'B': CDS_PINID='B';
NODE_NAME     PC1900 2
 '@S9S_MB_2U_LIB.S9S_MB_2U(SCH_1):PAGE262_I34@PURE_QUANTA.Q_CAPP(CHIPS)':
 'B': CDS_PINID='B';
NODE_NAME     PR4229 2
 '@S9S_MB_2U_LIB.S9S_MB_2U(SCH_1):PAGE262_I36@PURE_QUANTA.Q_RES(CHIPS)':
 'B': CDS_PINID='B';
NODE_NAME     PR591 2
 '@S9S_MB_2U_LIB.S9S_MB_2U(SCH_1):PAGE264_I30@PURE_QUANTA.Q_RES(CHIPS)':
 'B': CDS_PINID='B';
NODE_NAME     PR634 2
 '@S9S_MB_2U_LIB.S9S_MB_2U(SCH_1):PAGE264_I57@PURE_QUANTA.Q_RES(CHIPS)':
 'B': CDS_PINID='B';
NODE_NAME     PR1311 2
 '@S9S_MB_2U_LIB.S9S_MB_2U(SCH_1):PAGE264_I59@PURE_QUANTA.Q_RES(CHIPS)':
 'B': CDS_PINID='B';
NODE_NAME     PC2948 2
 '@S9S_MB_2U_LIB.S9S_MB_2U(SCH_1):PAGE265_I14@PURE_QUANTA.Q_CAP(CHIPS)':
 'B': CDS_PINID='B';
NODE_NAME     PC639 2
 '@S9S_MB_2U_LIB.S9S_MB_2U(SCH_1):PAGE265_I24@PURE_QUANTA.Q_CAP(CHIPS)':
 'B': CDS_PINID='B';
NODE_NAME     PC1644 2
 '@S9S_MB_2U_LIB.S9S_MB_2U(SCH_1):PAGE265_I27@PURE_QUANTA.Q_CAPP(CHIPS)':
 'B': CDS_PINID='B';
NODE_NAME     PC1258 2
 '@S9S_MB_2U_LIB.S9S_MB_2U(SCH_1):PAGE267_I49@PURE_QUANTA.Q_CAPP(CHIPS)':
 'B': CDS_PINID='B';
NODE_NAME     PR560 2
 '@S9S_MB_2U_LIB.S9S_MB_2U(SCH_1):PAGE270_I12@PURE_QUANTA.Q_RES(CHIPS)':
 'B': CDS_PINID='B';
NODE_NAME     PC547 2
 '@S9S_MB_2U_LIB.S9S_MB_2U(SCH_1):PAGE270_I28@PURE_QUANTA.Q_CAP(CHIPS)':
 'B': CDS_PINID='B';
NODE_NAME     PR313 2
 '@S9S_MB_2U_LIB.S9S_MB_2U(SCH_1):PAGE270_I29@PURE_QUANTA.Q_RES(CHIPS)':
 'B': CDS_PINID='B';
NODE_NAME     PC548 2
 '@S9S_MB_2U_LIB.S9S_MB_2U(SCH_1):PAGE270_I31@PURE_QUANTA.Q_CAP(CHIPS)':
 'B': CDS_PINID='B';
NODE_NAME     C2446 2
 '@S9S_MB_2U_LIB.S9S_MB_2U(SCH_1):PAGE270_I34@PURE_QUANTA.Q_CAP(CHIPS)':
 'B': CDS_PINID='B';
NODE_NAME     C2447 2
 '@S9S_MB_2U_LIB.S9S_MB_2U(SCH_1):PAGE270_I35@PURE_QUANTA.Q_CAP(CHIPS)':
 'B': CDS_PINID='B';
NODE_NAME     PC552 2
 '@S9S_MB_2U_LIB.S9S_MB_2U(SCH_1):PAGE270_I120@PURE_QUANTA.Q_CAP(CHIPS)':
 'B': CDS_PINID='B';
NODE_NAME     PC396 2
 '@S9S_MB_2U_LIB.S9S_MB_2U(SCH_1):PAGE275_I11@PURE_QUANTA.Q_CAP(CHIPS)':
 'B': CDS_PINID='B';
NODE_NAME     PC405_P1_1 2
 '@S9S_MB_2U_LIB.S9S_MB_2U(SCH_1):PAGE275_I56@PURE_QUANTA.Q_CAP(CHIPS)':
 'B': CDS_PINID='B';
NODE_NAME     PC408_P1_2 2
 '@S9S_MB_2U_LIB.S9S_MB_2U(SCH_1):PAGE275_I61@PURE_QUANTA.Q_CAP(CHIPS)':
 'B': CDS_PINID='B';
NODE_NAME     PR4241 2
 '@S9S_MB_2U_LIB.S9S_MB_2U(SCH_1):PAGE275_I64@PURE_QUANTA.Q_RES(CHIPS)':
 'B': CDS_PINID='B';
NODE_NAME     PC418 2
 '@S9S_MB_2U_LIB.S9S_MB_2U(SCH_1):PAGE275_I70@PURE_QUANTA.Q_CAPP(CHIPS)':
 'B': CDS_PINID='B';
NODE_NAME     PC2172 2
 '@S9S_MB_2U_LIB.S9S_MB_2U(SCH_1):PAGE275_I72@PURE_QUANTA.Q_CAPP(CHIPS)':
 'B': CDS_PINID='B';
NODE_NAME     PC1677 2
 '@S9S_MB_2U_LIB.S9S_MB_2U(SCH_1):PAGE275_I80@PURE_QUANTA.Q_CAP(CHIPS)':
 'B': CDS_PINID='B';
NODE_NAME     C2453 2
 '@S9S_MB_2U_LIB.S9S_MB_2U(SCH_1):PAGE278_I32@PURE_QUANTA.Q_CAP(CHIPS)':
 'B': CDS_PINID='B';
NODE_NAME     C2452 2
 '@S9S_MB_2U_LIB.S9S_MB_2U(SCH_1):PAGE278_I33@PURE_QUANTA.Q_CAP(CHIPS)':
 'B': CDS_PINID='B';
NODE_NAME     C2454 2
 '@S9S_MB_2U_LIB.S9S_MB_2U(SCH_1):PAGE282_I45@PURE_QUANTA.Q_CAP(CHIPS)':
 'B': CDS_PINID='B';
NODE_NAME     PR705 2
 '@S9S_MB_2U_LIB.S9S_MB_2U(SCH_1):PAGE282_I81@PURE_QUANTA.Q_RES(CHIPS)':
 'B': CDS_PINID='B';
NODE_NAME     PC558_P1_2 2
 '@S9S_MB_2U_LIB.S9S_MB_2U(SCH_1):PAGE271_I15@PURE_QUANTA.Q_CAP(CHIPS)':
 'B': CDS_PINID='B';
NODE_NAME     PC560_P1_2 2
 '@S9S_MB_2U_LIB.S9S_MB_2U(SCH_1):PAGE271_I19@PURE_QUANTA.Q_CAP(CHIPS)':
 'B': CDS_PINID='B';
NODE_NAME     PC562_P1_2 2
 '@S9S_MB_2U_LIB.S9S_MB_2U(SCH_1):PAGE271_I21@PURE_QUANTA.Q_CAP(CHIPS)':
 'B': CDS_PINID='B';
NODE_NAME     PC559_P1_1 2
 '@S9S_MB_2U_LIB.S9S_MB_2U(SCH_1):PAGE271_I39@PURE_QUANTA.Q_CAP(CHIPS)':
 'B': CDS_PINID='B';
NODE_NAME     PU31_P1_1 2
 '@S9S_MB_2U_LIB.S9S_MB_2U(SCH_1):PAGE271_I40@PURE_QUANTA.ISL99390FRZTR5935(CHIPS)':
 'AGND': CDS_PINID='AGND';
NODE_NAME     PU31_P1_1 5
 '@S9S_MB_2U_LIB.S9S_MB_2U(SCH_1):PAGE271_I40@PURE_QUANTA.ISL99390FRZTR5935(CHIPS)':
 'PGND1': CDS_PINID='PGND1';
NODE_NAME     PU31_P1_1 7_9-20_24
 '@S9S_MB_2U_LIB.S9S_MB_2U(SCH_1):PAGE271_I40@PURE_QUANTA.ISL99390FRZTR5935(CHIPS)':
 'PGND2': CDS_PINID='PGND2';
NODE_NAME     PU31_P1_1 40
 '@S9S_MB_2U_LIB.S9S_MB_2U(SCH_1):PAGE271_I40@PURE_QUANTA.ISL99390FRZTR5935(CHIPS)':
 'PGND3': CDS_PINID='PGND3';
NODE_NAME     PC83 2
 '@S9S_MB_2U_LIB.S9S_MB_2U(SCH_1):PAGE271_I56@PURE_QUANTA.Q_CAPP(CHIPS)':
 'B': CDS_PINID='B';
NODE_NAME     PC189 2
 '@S9S_MB_2U_LIB.S9S_MB_2U(SCH_1):PAGE271_I62@PURE_QUANTA.Q_CAPP(CHIPS)':
 'B': CDS_PINID='B';
NODE_NAME     PC582 2
 '@S9S_MB_2U_LIB.S9S_MB_2U(SCH_1):PAGE271_I87@PURE_QUANTA.Q_CAPP(CHIPS)':
 'B': CDS_PINID='B';
NODE_NAME     PC576_P1_1 2
 '@S9S_MB_2U_LIB.S9S_MB_2U(SCH_1):PAGE271_I88@PURE_QUANTA.Q_CAP(CHIPS)':
 'B': CDS_PINID='B';
NODE_NAME     PC578_P1_1 2
 '@S9S_MB_2U_LIB.S9S_MB_2U(SCH_1):PAGE271_I91@PURE_QUANTA.Q_CAP(CHIPS)':
 'B': CDS_PINID='B';
NODE_NAME     PC2346 2
 '@S9S_MB_2U_LIB.S9S_MB_2U(SCH_1):PAGE271_I96@PURE_QUANTA.Q_CAPP(CHIPS)':
 'B': CDS_PINID='B';
NODE_NAME     PC441 2
 '@S9S_MB_2U_LIB.S9S_MB_2U(SCH_1):PAGE279_I10@PURE_QUANTA.Q_CAP(CHIPS)':
 'B': CDS_PINID='B';
NODE_NAME     PC440 2
 '@S9S_MB_2U_LIB.S9S_MB_2U(SCH_1):PAGE279_I24@PURE_QUANTA.Q_CAP(CHIPS)':
 'B': CDS_PINID='B';
NODE_NAME     PC442_P1_1 2
 '@S9S_MB_2U_LIB.S9S_MB_2U(SCH_1):PAGE279_I40@PURE_QUANTA.Q_CAP(CHIPS)':
 'B': CDS_PINID='B';
NODE_NAME     PC1366 1
 '@S9S_MB_2U_LIB.S9S_MB_2U(SCH_1):PAGE280_I9@PURE_QUANTA.Q_CAP(CHIPS)':
 'A': CDS_PINID='A';
NODE_NAME     PC2199 2
 '@S9S_MB_2U_LIB.S9S_MB_2U(SCH_1):PAGE280_I32@PURE_QUANTA.Q_CAPP(CHIPS)':
 'B': CDS_PINID='B';
NODE_NAME     PC373 2
 '@S9S_MB_2U_LIB.S9S_MB_2U(SCH_1):PAGE283_I15@PURE_QUANTA.Q_CAP(CHIPS)':
 'B': CDS_PINID='B';
NODE_NAME     PC382 2
 '@S9S_MB_2U_LIB.S9S_MB_2U(SCH_1):PAGE283_I29@PURE_QUANTA.Q_CAP(CHIPS)':
 'B': CDS_PINID='B';
NODE_NAME     PJ67 2
 '@S9S_MB_2U_LIB.S9S_MB_2U(SCH_1):PAGE285_I44@PURE_QUANTA.Q_SHORT(CHIPS)':
 '2': CDS_PINID='\2\';
NODE_NAME     PC1282 2
 '@S9S_MB_2U_LIB.S9S_MB_2U(SCH_1):PAGE286_I16@PURE_QUANTA.Q_CAP(CHIPS)':
 'B': CDS_PINID='B';
NODE_NAME     PC1218 2
 '@S9S_MB_2U_LIB.S9S_MB_2U(SCH_1):PAGE248_I29@PURE_QUANTA.Q_CAP(CHIPS)':
 'B': CDS_PINID='B';
NODE_NAME     PJ63 2
 '@S9S_MB_2U_LIB.S9S_MB_2U(SCH_1):PAGE248_I42@PURE_QUANTA.Q_SHORT(CHIPS)':
 '2': CDS_PINID='\2\';
NODE_NAME     U308 2
 '@S9S_MB_2U_LIB.S9S_MB_2U(SCH_1):PAGE230_I37@PURE_QUANTA.74LVC2G07DW7(CHIPS)':
 'GND': CDS_PINID='GND';
NODE_NAME     C2283 2
 '@S9S_MB_2U_LIB.S9S_MB_2U(SCH_1):PAGE230_I40@PURE_QUANTA.Q_CAP(CHIPS)':
 'B': CDS_PINID='B';
NODE_NAME     R4265 2
 '@S9S_MB_2U_LIB.S9S_MB_2U(SCH_1):PAGE230_I43@PURE_QUANTA.Q_RES(CHIPS)':
 'B': CDS_PINID='B';
NODE_NAME     R293 2
 '@S9S_MB_2U_LIB.S9S_MB_2U(SCH_1):PAGE119_I211@PURE_QUANTA.Q_RES(CHIPS)':
 'B': CDS_PINID='B';
NODE_NAME     R4263 2
 '@S9S_MB_2U_LIB.S9S_MB_2U(SCH_1):PAGE119_I216@PURE_QUANTA.Q_RES(CHIPS)':
 'B': CDS_PINID='B';
NODE_NAME     R4261 2
 '@S9S_MB_2U_LIB.S9S_MB_2U(SCH_1):PAGE119_I220@PURE_QUANTA.Q_RES(CHIPS)':
 'B': CDS_PINID='B';
NODE_NAME     R289 2
 '@S9S_MB_2U_LIB.S9S_MB_2U(SCH_1):PAGE119_I225@PURE_QUANTA.Q_RES(CHIPS)':
 'B': CDS_PINID='B';
NODE_NAME     U270 4
 '@S9S_MB_2U_LIB.S9S_MB_2U(SCH_1):PAGE161_I164@PURE_QUANTA.LM75BD(CHIPS)':
 'GND': CDS_PINID='GND';
NODE_NAME     U271 4
 '@S9S_MB_2U_LIB.S9S_MB_2U(SCH_1):PAGE161_I165@PURE_QUANTA.LM75BD(CHIPS)':
 'GND': CDS_PINID='GND';
NODE_NAME     U272 4
 '@S9S_MB_2U_LIB.S9S_MB_2U(SCH_1):PAGE161_I166@PURE_QUANTA.LM75BD(CHIPS)':
 'GND': CDS_PINID='GND';
NODE_NAME     U273 4
 '@S9S_MB_2U_LIB.S9S_MB_2U(SCH_1):PAGE161_I167@PURE_QUANTA.LM75BD(CHIPS)':
 'GND': CDS_PINID='GND';
NODE_NAME     H44 1
 '@S9S_MB_2U_LIB.S9S_MB_2U(SCH_1):PAGE289_I216@PURE_QUANTA.HOLE(CHIPS)':
 '1': CDS_PINID='\1\';
NODE_NAME     H45 1
 '@S9S_MB_2U_LIB.S9S_MB_2U(SCH_1):PAGE289_I217@PURE_QUANTA.HOLE(CHIPS)':
 '1': CDS_PINID='\1\';
NODE_NAME     H47 1
 '@S9S_MB_2U_LIB.S9S_MB_2U(SCH_1):PAGE289_I218@PURE_QUANTA.HOLE(CHIPS)':
 '1': CDS_PINID='\1\';
NODE_NAME     H49 1
 '@S9S_MB_2U_LIB.S9S_MB_2U(SCH_1):PAGE289_I219@PURE_QUANTA.HOLE(CHIPS)':
 '1': CDS_PINID='\1\';
NODE_NAME     R4274 2
 '@S9S_MB_2U_LIB.S9S_MB_2U(SCH_1):PAGE162_I11@PURE_QUANTA.Q_RES(CHIPS)':
 'B': CDS_PINID='B';
NODE_NAME     R4280 2
 '@S9S_MB_2U_LIB.S9S_MB_2U(SCH_1):PAGE162_I17@PURE_QUANTA.Q_RES(CHIPS)':
 'B': CDS_PINID='B';
NODE_NAME     R4637 2
 '@S9S_MB_2U_LIB.S9S_MB_2U(SCH_1):PAGE162_I24@PURE_QUANTA.Q_RES(CHIPS)':
 'B': CDS_PINID='B';
NODE_NAME     R4292 2
 '@S9S_MB_2U_LIB.S9S_MB_2U(SCH_1):PAGE162_I63@PURE_QUANTA.Q_RES(CHIPS)':
 'B': CDS_PINID='B';
NODE_NAME     R4290 2
 '@S9S_MB_2U_LIB.S9S_MB_2U(SCH_1):PAGE162_I68@PURE_QUANTA.Q_RES(CHIPS)':
 'B': CDS_PINID='B';
NODE_NAME     R148 2
 '@S9S_MB_2U_LIB.S9S_MB_2U(SCH_1):PAGE185_I49@PURE_QUANTA.Q_RES(CHIPS)':
 'B': CDS_PINID='B';
NODE_NAME     R147 2
 '@S9S_MB_2U_LIB.S9S_MB_2U(SCH_1):PAGE185_I50@PURE_QUANTA.Q_RES(CHIPS)':
 'B': CDS_PINID='B';
NODE_NAME     R4039 2
 '@S9S_MB_2U_LIB.S9S_MB_2U(SCH_1):PAGE322_I129@PURE_QUANTA.Q_RES(CHIPS)':
 'B': CDS_PINID='B';
NODE_NAME     R4040 2
 '@S9S_MB_2U_LIB.S9S_MB_2U(SCH_1):PAGE322_I131@PURE_QUANTA.Q_RES(CHIPS)':
 'B': CDS_PINID='B';
NODE_NAME     PR1746 2
 '@S9S_MB_2U_LIB.S9S_MB_2U(SCH_1):PAGE283_I3@PURE_QUANTA.Q_RES(CHIPS)':
 'B': CDS_PINID='B';
NODE_NAME     PU17 2
 '@S9S_MB_2U_LIB.S9S_MB_2U(SCH_1):PAGE283_I10@PURE_QUANTA.ISL99390FRZTR5935(CHIPS)':
 'AGND': CDS_PINID='AGND';
NODE_NAME     PU17 5
 '@S9S_MB_2U_LIB.S9S_MB_2U(SCH_1):PAGE283_I10@PURE_QUANTA.ISL99390FRZTR5935(CHIPS)':
 'PGND1': CDS_PINID='PGND1';
NODE_NAME     PU17 7_9-20_24
 '@S9S_MB_2U_LIB.S9S_MB_2U(SCH_1):PAGE283_I10@PURE_QUANTA.ISL99390FRZTR5935(CHIPS)':
 'PGND2': CDS_PINID='PGND2';
NODE_NAME     PU17 40
 '@S9S_MB_2U_LIB.S9S_MB_2U(SCH_1):PAGE283_I10@PURE_QUANTA.ISL99390FRZTR5935(CHIPS)':
 'PGND3': CDS_PINID='PGND3';
NODE_NAME     PC2 2
 '@S9S_MB_2U_LIB.S9S_MB_2U(SCH_1):PAGE283_I30@PURE_QUANTA.Q_CAP(CHIPS)':
 'B': CDS_PINID='B';
NODE_NAME     PC385 2
 '@S9S_MB_2U_LIB.S9S_MB_2U(SCH_1):PAGE283_I32@PURE_QUANTA.Q_CAPP(CHIPS)':
 'B': CDS_PINID='B';
NODE_NAME     C1296 2
 '@S9S_MB_2U_LIB.S9S_MB_2U(SCH_1):PAGE268_I31@PURE_QUANTA.Q_CAP(CHIPS)':
 'B': CDS_PINID='B';
NODE_NAME     PC28 2
 '@S9S_MB_2U_LIB.S9S_MB_2U(SCH_1):PAGE286_I23@PURE_QUANTA.Q_CAP(CHIPS)':
 'B': CDS_PINID='B';
NODE_NAME     PC1287 2
 '@S9S_MB_2U_LIB.S9S_MB_2U(SCH_1):PAGE286_I44@PURE_QUANTA.Q_CAP(CHIPS)':
 'B': CDS_PINID='B';
NODE_NAME     PC2201 2
 '@S9S_MB_2U_LIB.S9S_MB_2U(SCH_1):PAGE323_I30@PURE_QUANTA.Q_CAP(CHIPS)':
 'B': CDS_PINID='B';
NODE_NAME     PC2203 2
 '@S9S_MB_2U_LIB.S9S_MB_2U(SCH_1):PAGE323_I32@PURE_QUANTA.Q_CAP(CHIPS)':
 'B': CDS_PINID='B';
NODE_NAME     PR3844 2
 '@S9S_MB_2U_LIB.S9S_MB_2U(SCH_1):PAGE236_I43@PURE_QUANTA.Q_RES(CHIPS)':
 'B': CDS_PINID='B';
NODE_NAME     PC2161 2
 '@S9S_MB_2U_LIB.S9S_MB_2U(SCH_1):PAGE236_I49@PURE_QUANTA.Q_CAP(CHIPS)':
 'B': CDS_PINID='B';
NODE_NAME     PU205 3
 '@S9S_MB_2U_LIB.S9S_MB_2U(SCH_1):PAGE236_I50@PURE_QUANTA.MP5016GQHLZ(CHIPS)':
 'GND': CDS_PINID='GND';
NODE_NAME     PC2159 2
 '@S9S_MB_2U_LIB.S9S_MB_2U(SCH_1):PAGE236_I55@PURE_QUANTA.Q_CAP(CHIPS)':
 'B': CDS_PINID='B';
NODE_NAME     PR3855 2
 '@S9S_MB_2U_LIB.S9S_MB_2U(SCH_1):PAGE237_I43@PURE_QUANTA.Q_RES(CHIPS)':
 'B': CDS_PINID='B';
NODE_NAME     PC2169 2
 '@S9S_MB_2U_LIB.S9S_MB_2U(SCH_1):PAGE237_I48@PURE_QUANTA.Q_CAP(CHIPS)':
 'B': CDS_PINID='B';
NODE_NAME     PC1322 2
 '@S9S_MB_2U_LIB.S9S_MB_2U(SCH_1):PAGE237_I54@PURE_QUANTA.Q_CAP(CHIPS)':
 'B': CDS_PINID='B';
NODE_NAME     R4019 2
 '@S9S_MB_2U_LIB.S9S_MB_2U(SCH_1):PAGE321_I98@PURE_QUANTA.Q_RES(CHIPS)':
 'B': CDS_PINID='B';
NODE_NAME     R4041 2
 '@S9S_MB_2U_LIB.S9S_MB_2U(SCH_1):PAGE322_I181@PURE_QUANTA.Q_RES(CHIPS)':
 'B': CDS_PINID='B';
NODE_NAME     R4391 2
 '@S9S_MB_2U_LIB.S9S_MB_2U(SCH_1):PAGE322_I190@PURE_QUANTA.Q_RES(CHIPS)':
 'B': CDS_PINID='B';
NODE_NAME     H128 1
 '@S9S_MB_2U_LIB.S9S_MB_2U(SCH_1):PAGE289_I232@PURE_QUANTA.HOLE(CHIPS)':
 '1': CDS_PINID='\1\';
NODE_NAME     C2321 2
 '@S9S_MB_2U_LIB.S9S_MB_2U(SCH_1):PAGE194_I2@PURE_QUANTA.Q_CAP(CHIPS)':
 'B': CDS_PINID='B';
NODE_NAME     R4465 2
 '@S9S_MB_2U_LIB.S9S_MB_2U(SCH_1):PAGE194_I4@PURE_QUANTA.Q_RES(CHIPS)':
 'B': CDS_PINID='B';
NODE_NAME     R4449 2
 '@S9S_MB_2U_LIB.S9S_MB_2U(SCH_1):PAGE194_I8@PURE_QUANTA.Q_RES(CHIPS)':
 'B': CDS_PINID='B';
NODE_NAME     C2317 2
 '@S9S_MB_2U_LIB.S9S_MB_2U(SCH_1):PAGE194_I15@PURE_QUANTA.Q_CAP(CHIPS)':
 'B': CDS_PINID='B';
NODE_NAME     U312 10
 '@S9S_MB_2U_LIB.S9S_MB_2U(SCH_1):PAGE194_I20@PURE_QUANTA.TUSB211IRWBR(CHIPS)':
 'GND': CDS_PINID='GND';
NODE_NAME     R4453 1
 '@S9S_MB_2U_LIB.S9S_MB_2U(SCH_1):PAGE194_I26@PURE_QUANTA.Q_RES(CHIPS)':
 'A': CDS_PINID='A';
NODE_NAME     R4463 2
 '@S9S_MB_2U_LIB.S9S_MB_2U(SCH_1):PAGE194_I37@PURE_QUANTA.Q_RES(CHIPS)':
 'B': CDS_PINID='B';
NODE_NAME     R4464 2
 '@S9S_MB_2U_LIB.S9S_MB_2U(SCH_1):PAGE194_I38@PURE_QUANTA.Q_RES(CHIPS)':
 'B': CDS_PINID='B';
NODE_NAME     U313 TH
 '@S9S_MB_2U_LIB.S9S_MB_2U(SCH_1):PAGE194_I40@PURE_QUANTA.GL852GOHY60(CHIPS)':
 'TH': CDS_PINID='TH';
NODE_NAME     C2313 2
 '@S9S_MB_2U_LIB.S9S_MB_2U(SCH_1):PAGE194_I43@PURE_QUANTA.Q_CAP(CHIPS)':
 'B': CDS_PINID='B';
NODE_NAME     C2314 2
 '@S9S_MB_2U_LIB.S9S_MB_2U(SCH_1):PAGE194_I45@PURE_QUANTA.Q_CAP(CHIPS)':
 'B': CDS_PINID='B';
NODE_NAME     C2315 2
 '@S9S_MB_2U_LIB.S9S_MB_2U(SCH_1):PAGE194_I46@PURE_QUANTA.Q_CAP(CHIPS)':
 'B': CDS_PINID='B';
NODE_NAME     C2316 2
 '@S9S_MB_2U_LIB.S9S_MB_2U(SCH_1):PAGE194_I47@PURE_QUANTA.Q_CAP(CHIPS)':
 'B': CDS_PINID='B';
NODE_NAME     C2318 2
 '@S9S_MB_2U_LIB.S9S_MB_2U(SCH_1):PAGE194_I49@PURE_QUANTA.Q_CAP(CHIPS)':
 'B': CDS_PINID='B';
NODE_NAME     C2319 2
 '@S9S_MB_2U_LIB.S9S_MB_2U(SCH_1):PAGE194_I51@PURE_QUANTA.Q_CAP(CHIPS)':
 'B': CDS_PINID='B';
NODE_NAME     C2320 2
 '@S9S_MB_2U_LIB.S9S_MB_2U(SCH_1):PAGE194_I52@PURE_QUANTA.Q_CAP(CHIPS)':
 'B': CDS_PINID='B';
NODE_NAME     C2322 2
 '@S9S_MB_2U_LIB.S9S_MB_2U(SCH_1):PAGE194_I53@PURE_QUANTA.Q_CAP(CHIPS)':
 'B': CDS_PINID='B';
NODE_NAME     C2325 2
 '@S9S_MB_2U_LIB.S9S_MB_2U(SCH_1):PAGE194_I55@PURE_QUANTA.Q_CAP(CHIPS)':
 'B': CDS_PINID='B';
NODE_NAME     C2323 2
 '@S9S_MB_2U_LIB.S9S_MB_2U(SCH_1):PAGE194_I56@PURE_QUANTA.Q_CAP(CHIPS)':
 'B': CDS_PINID='B';
NODE_NAME     C2324 2
 '@S9S_MB_2U_LIB.S9S_MB_2U(SCH_1):PAGE194_I58@PURE_QUANTA.Q_CAP(CHIPS)':
 'B': CDS_PINID='B';
NODE_NAME     R4466 2
 '@S9S_MB_2U_LIB.S9S_MB_2U(SCH_1):PAGE194_I75@PURE_QUANTA.Q_RES(CHIPS)':
 'B': CDS_PINID='B';
NODE_NAME     C2326 2
 '@S9S_MB_2U_LIB.S9S_MB_2U(SCH_1):PAGE194_I81@PURE_QUANTA.Q_CAP(CHIPS)':
 'B': CDS_PINID='B';
NODE_NAME     Y9 2
 '@S9S_MB_2U_LIB.S9S_MB_2U(SCH_1):PAGE194_I83@PURE_QUANTA.Q_XTAL_4P_13BI_24GND(CHIPS)':
 'G1': CDS_PINID='G1';
NODE_NAME     Y9 4
 '@S9S_MB_2U_LIB.S9S_MB_2U(SCH_1):PAGE194_I83@PURE_QUANTA.Q_XTAL_4P_13BI_24GND(CHIPS)':
 'G2': CDS_PINID='G2';
NODE_NAME     C2327 2
 '@S9S_MB_2U_LIB.S9S_MB_2U(SCH_1):PAGE194_I85@PURE_QUANTA.Q_CAP(CHIPS)':
 'B': CDS_PINID='B';
NODE_NAME     R3907 2
 '@S9S_MB_2U_LIB.S9S_MB_2U(SCH_1):PAGE303_I4@PURE_QUANTA.Q_RES(CHIPS)':
 'B': CDS_PINID='B';
NODE_NAME     U290 S
 '@S9S_MB_2U_LIB.S9S_MB_2U(SCH_1):PAGE303_I5@PURE_QUANTA.MOSFET_NCH_GDS_ESD_PROTECTED(CHIPS)':
 'S': CDS_PINID='S';
NODE_NAME     R4420 2
 '@S9S_MB_2U_LIB.S9S_MB_2U(SCH_1):PAGE155_I202@PURE_QUANTA.Q_RES(CHIPS)':
 'B': CDS_PINID='B';
NODE_NAME     R4419 2
 '@S9S_MB_2U_LIB.S9S_MB_2U(SCH_1):PAGE155_I203@PURE_QUANTA.Q_RES(CHIPS)':
 'B': CDS_PINID='B';
NODE_NAME     R422 2
 '@S9S_MB_2U_LIB.S9S_MB_2U(SCH_1):PAGE150_I215@PURE_QUANTA.Q_RES(CHIPS)':
 'B': CDS_PINID='B';
NODE_NAME     R3175 2
 '@S9S_MB_2U_LIB.S9S_MB_2U(SCH_1):PAGE146_I334@PURE_QUANTA.Q_RES(CHIPS)':
 'B': CDS_PINID='B';
NODE_NAME     U314 33
 '@S9S_MB_2U_LIB.S9S_MB_2U(SCH_1):PAGE200_I1@PURE_QUANTA.9ZXL0451EKILFT(CHIPS)':
 'EPAD_GND': CDS_PINID='EPAD_GND';
NODE_NAME     C2328 2
 '@S9S_MB_2U_LIB.S9S_MB_2U(SCH_1):PAGE200_I17@PURE_QUANTA.Q_CAP(CHIPS)':
 'B': CDS_PINID='B';
NODE_NAME     R4490 2
 '@S9S_MB_2U_LIB.S9S_MB_2U(SCH_1):PAGE200_I31@PURE_QUANTA.Q_RES(CHIPS)':
 'B': CDS_PINID='B';
NODE_NAME     R4492 2
 '@S9S_MB_2U_LIB.S9S_MB_2U(SCH_1):PAGE200_I49@PURE_QUANTA.Q_RES(CHIPS)':
 'B': CDS_PINID='B';
NODE_NAME     C2329 2
 '@S9S_MB_2U_LIB.S9S_MB_2U(SCH_1):PAGE200_I54@PURE_QUANTA.Q_CAP(CHIPS)':
 'B': CDS_PINID='B';
NODE_NAME     C2330 2
 '@S9S_MB_2U_LIB.S9S_MB_2U(SCH_1):PAGE200_I55@PURE_QUANTA.Q_CAP(CHIPS)':
 'B': CDS_PINID='B';
NODE_NAME     C2333 2
 '@S9S_MB_2U_LIB.S9S_MB_2U(SCH_1):PAGE200_I56@PURE_QUANTA.Q_CAP(CHIPS)':
 'B': CDS_PINID='B';
NODE_NAME     C2336 2
 '@S9S_MB_2U_LIB.S9S_MB_2U(SCH_1):PAGE200_I57@PURE_QUANTA.Q_CAP(CHIPS)':
 'B': CDS_PINID='B';
NODE_NAME     C2334 2
 '@S9S_MB_2U_LIB.S9S_MB_2U(SCH_1):PAGE200_I58@PURE_QUANTA.Q_CAP(CHIPS)':
 'B': CDS_PINID='B';
NODE_NAME     C2335 2
 '@S9S_MB_2U_LIB.S9S_MB_2U(SCH_1):PAGE200_I59@PURE_QUANTA.Q_CAP(CHIPS)':
 'B': CDS_PINID='B';
NODE_NAME     R4482 2
 '@S9S_MB_2U_LIB.S9S_MB_2U(SCH_1):PAGE155_I208@PURE_QUANTA.Q_RES(CHIPS)':
 'B': CDS_PINID='B';
NODE_NAME     R4486 2
 '@S9S_MB_2U_LIB.S9S_MB_2U(SCH_1):PAGE194_I90@PURE_QUANTA.Q_RES(CHIPS)':
 'B': CDS_PINID='B';
NODE_NAME     R4483 2
 '@S9S_MB_2U_LIB.S9S_MB_2U(SCH_1):PAGE155_I206@PURE_QUANTA.Q_RES(CHIPS)':
 'B': CDS_PINID='B';
NODE_NAME     R4487 2
 '@S9S_MB_2U_LIB.S9S_MB_2U(SCH_1):PAGE194_I88@PURE_QUANTA.Q_RES(CHIPS)':
 'B': CDS_PINID='B';
NODE_NAME     C2339 2
 '@S9S_MB_2U_LIB.S9S_MB_2U(SCH_1):PAGE200_I71@PURE_QUANTA.Q_CAP(CHIPS)':
 'B': CDS_PINID='B';
NODE_NAME     C2337 2
 '@S9S_MB_2U_LIB.S9S_MB_2U(SCH_1):PAGE225_I5@PURE_QUANTA.Q_CAP(CHIPS)':
 'B': CDS_PINID='B';
NODE_NAME     C2338 2
 '@S9S_MB_2U_LIB.S9S_MB_2U(SCH_1):PAGE225_I8@PURE_QUANTA.Q_CAP(CHIPS)':
 'B': CDS_PINID='B';
NODE_NAME     U315 4
 '@S9S_MB_2U_LIB.S9S_MB_2U(SCH_1):PAGE225_I17@PURE_QUANTA.PCA9617ADP(CHIPS)':
 'GND': CDS_PINID='GND';
NODE_NAME     PC1181_P0_3 2
 '@S9S_MB_2U_LIB.S9S_MB_2U(SCH_1):PAGE258_I48@PURE_QUANTA.Q_CAP(CHIPS)':
 'B': CDS_PINID='B';
NODE_NAME     PC1654 2
 '@S9S_MB_2U_LIB.S9S_MB_2U(SCH_1):PAGE258_I57@PURE_QUANTA.Q_CAP(CHIPS)':
 'B': CDS_PINID='B';
NODE_NAME     PC1186_P0_4 2
 '@S9S_MB_2U_LIB.S9S_MB_2U(SCH_1):PAGE258_I60@PURE_QUANTA.Q_CAP(CHIPS)':
 'B': CDS_PINID='B';
NODE_NAME     PC1673 2
 '@S9S_MB_2U_LIB.S9S_MB_2U(SCH_1):PAGE258_I75@PURE_QUANTA.Q_CAP(CHIPS)':
 'B': CDS_PINID='B';
NODE_NAME     PC1189 2
 '@S9S_MB_2U_LIB.S9S_MB_2U(SCH_1):PAGE258_I80@PURE_QUANTA.Q_CAPP(CHIPS)':
 'B': CDS_PINID='B';
NODE_NAME     PU71_P0_3 2
 '@S9S_MB_2U_LIB.S9S_MB_2U(SCH_1):PAGE258_I82@PURE_QUANTA.ISL99390FRZTR5935(CHIPS)':
 'AGND': CDS_PINID='AGND';
NODE_NAME     PU71_P0_3 5
 '@S9S_MB_2U_LIB.S9S_MB_2U(SCH_1):PAGE258_I82@PURE_QUANTA.ISL99390FRZTR5935(CHIPS)':
 'PGND1': CDS_PINID='PGND1';
NODE_NAME     PU71_P0_3 7_9-20_24
 '@S9S_MB_2U_LIB.S9S_MB_2U(SCH_1):PAGE258_I82@PURE_QUANTA.ISL99390FRZTR5935(CHIPS)':
 'PGND2': CDS_PINID='PGND2';
NODE_NAME     PU71_P0_3 40
 '@S9S_MB_2U_LIB.S9S_MB_2U(SCH_1):PAGE258_I82@PURE_QUANTA.ISL99390FRZTR5935(CHIPS)':
 'PGND3': CDS_PINID='PGND3';
NODE_NAME     C3275 2
 '@S9S_MB_2U_LIB.S9S_MB_2U(SCH_1):PAGE260_I23@PURE_QUANTA.Q_CAP(CHIPS)':
 'B': CDS_PINID='B';
NODE_NAME     PR4224 2
 '@S9S_MB_2U_LIB.S9S_MB_2U(SCH_1):PAGE260_I84@PURE_QUANTA.Q_RES(CHIPS)':
 'B': CDS_PINID='B';
NODE_NAME     PR4223 2
 '@S9S_MB_2U_LIB.S9S_MB_2U(SCH_1):PAGE260_I85@PURE_QUANTA.Q_RES(CHIPS)':
 'B': CDS_PINID='B';
NODE_NAME     PR4222 2
 '@S9S_MB_2U_LIB.S9S_MB_2U(SCH_1):PAGE260_I86@PURE_QUANTA.Q_RES(CHIPS)':
 'B': CDS_PINID='B';
NODE_NAME     PC224 2
 '@S9S_MB_2U_LIB.S9S_MB_2U(SCH_1):PAGE260_I92@PURE_QUANTA.Q_CAP(CHIPS)':
 'B': CDS_PINID='B';
NODE_NAME     PR4234 2
 '@S9S_MB_2U_LIB.S9S_MB_2U(SCH_1):PAGE264_I66@PURE_QUANTA.Q_RES(CHIPS)':
 'B': CDS_PINID='B';
NODE_NAME     PR4233 2
 '@S9S_MB_2U_LIB.S9S_MB_2U(SCH_1):PAGE264_I67@PURE_QUANTA.Q_RES(CHIPS)':
 'B': CDS_PINID='B';
NODE_NAME     PR4232 2
 '@S9S_MB_2U_LIB.S9S_MB_2U(SCH_1):PAGE264_I68@PURE_QUANTA.Q_RES(CHIPS)':
 'B': CDS_PINID='B';
NODE_NAME     PR4238 2
 '@S9S_MB_2U_LIB.S9S_MB_2U(SCH_1):PAGE270_I81@PURE_QUANTA.Q_RES(CHIPS)':
 'B': CDS_PINID='B';
NODE_NAME     C2449 2
 '@S9S_MB_2U_LIB.S9S_MB_2U(SCH_1):PAGE270_I104@PURE_QUANTA.Q_CAP(CHIPS)':
 'B': CDS_PINID='B';
NODE_NAME     PC555 2
 '@S9S_MB_2U_LIB.S9S_MB_2U(SCH_1):PAGE270_I122@PURE_QUANTA.Q_CAP(CHIPS)':
 'B': CDS_PINID='B';
NODE_NAME     C3268 2
 '@S9S_MB_2U_LIB.S9S_MB_2U(SCH_1):PAGE252_I58@PURE_QUANTA.Q_CAP(CHIPS)':
 'B': CDS_PINID='B';
NODE_NAME     PR166 2
 '@S9S_MB_2U_LIB.S9S_MB_2U(SCH_1):PAGE252_I60@PURE_QUANTA.Q_RES(CHIPS)':
 'B': CDS_PINID='B';
NODE_NAME     PC330 2
 '@S9S_MB_2U_LIB.S9S_MB_2U(SCH_1):PAGE252_I61@PURE_QUANTA.Q_CAP(CHIPS)':
 'B': CDS_PINID='B';
NODE_NAME     PC335 2
 '@S9S_MB_2U_LIB.S9S_MB_2U(SCH_1):PAGE252_I86@PURE_QUANTA.Q_CAP(CHIPS)':
 'B': CDS_PINID='B';
NODE_NAME     PC1369 1
 '@S9S_MB_2U_LIB.S9S_MB_2U(SCH_1):PAGE276_I23@PURE_QUANTA.Q_CAP(CHIPS)':
 'A': CDS_PINID='A';
NODE_NAME     PU77_P1_3 2
 '@S9S_MB_2U_LIB.S9S_MB_2U(SCH_1):PAGE276_I24@PURE_QUANTA.ISL99390FRZTR5935(CHIPS)':
 'AGND': CDS_PINID='AGND';
NODE_NAME     PU77_P1_3 5
 '@S9S_MB_2U_LIB.S9S_MB_2U(SCH_1):PAGE276_I24@PURE_QUANTA.ISL99390FRZTR5935(CHIPS)':
 'PGND1': CDS_PINID='PGND1';
NODE_NAME     PU77_P1_3 7_9-20_24
 '@S9S_MB_2U_LIB.S9S_MB_2U(SCH_1):PAGE276_I24@PURE_QUANTA.ISL99390FRZTR5935(CHIPS)':
 'PGND2': CDS_PINID='PGND2';
NODE_NAME     PU77_P1_3 40
 '@S9S_MB_2U_LIB.S9S_MB_2U(SCH_1):PAGE276_I24@PURE_QUANTA.ISL99390FRZTR5935(CHIPS)':
 'PGND3': CDS_PINID='PGND3';
NODE_NAME     PC1244_P1_3 2
 '@S9S_MB_2U_LIB.S9S_MB_2U(SCH_1):PAGE276_I31@PURE_QUANTA.Q_CAP(CHIPS)':
 'B': CDS_PINID='B';
NODE_NAME     PC1196_P1_4 2
 '@S9S_MB_2U_LIB.S9S_MB_2U(SCH_1):PAGE276_I35@PURE_QUANTA.Q_CAP(CHIPS)':
 'B': CDS_PINID='B';
NODE_NAME     PC1209_P1_4 2
 '@S9S_MB_2U_LIB.S9S_MB_2U(SCH_1):PAGE276_I50@PURE_QUANTA.Q_CAP(CHIPS)':
 'B': CDS_PINID='B';
NODE_NAME     PC727_P1_4 2
 '@S9S_MB_2U_LIB.S9S_MB_2U(SCH_1):PAGE276_I52@PURE_QUANTA.Q_CAP(CHIPS)':
 'B': CDS_PINID='B';
NODE_NAME     PC1204 2
 '@S9S_MB_2U_LIB.S9S_MB_2U(SCH_1):PAGE276_I70@PURE_QUANTA.Q_CAPP(CHIPS)':
 'B': CDS_PINID='B';
NODE_NAME     PC1205 2
 '@S9S_MB_2U_LIB.S9S_MB_2U(SCH_1):PAGE276_I72@PURE_QUANTA.Q_CAPP(CHIPS)':
 'B': CDS_PINID='B';
NODE_NAME     PC467 2
 '@S9S_MB_2U_LIB.S9S_MB_2U(SCH_1):PAGE278_I28@PURE_QUANTA.Q_CAP(CHIPS)':
 'B': CDS_PINID='B';
NODE_NAME     PC1292 2
 '@S9S_MB_2U_LIB.S9S_MB_2U(SCH_1):PAGE278_I69@PURE_QUANTA.Q_CAP(CHIPS)':
 'B': CDS_PINID='B';
NODE_NAME     PR4246 2
 '@S9S_MB_2U_LIB.S9S_MB_2U(SCH_1):PAGE278_I78@PURE_QUANTA.Q_RES(CHIPS)':
 'B': CDS_PINID='B';
NODE_NAME     PR4245 2
 '@S9S_MB_2U_LIB.S9S_MB_2U(SCH_1):PAGE278_I79@PURE_QUANTA.Q_RES(CHIPS)':
 'B': CDS_PINID='B';
NODE_NAME     PR4244 2
 '@S9S_MB_2U_LIB.S9S_MB_2U(SCH_1):PAGE278_I80@PURE_QUANTA.Q_RES(CHIPS)':
 'B': CDS_PINID='B';
NODE_NAME     PR4243 2
 '@S9S_MB_2U_LIB.S9S_MB_2U(SCH_1):PAGE278_I81@PURE_QUANTA.Q_RES(CHIPS)':
 'B': CDS_PINID='B';
NODE_NAME     PC476 2
 '@S9S_MB_2U_LIB.S9S_MB_2U(SCH_1):PAGE278_I93@PURE_QUANTA.Q_CAP(CHIPS)':
 'B': CDS_PINID='B';
NODE_NAME     PC478 2
 '@S9S_MB_2U_LIB.S9S_MB_2U(SCH_1):PAGE278_I97@PURE_QUANTA.Q_CAP(CHIPS)':
 'B': CDS_PINID='B';
NODE_NAME     PC386 2
 '@S9S_MB_2U_LIB.S9S_MB_2U(SCH_1):PAGE282_I13@PURE_QUANTA.Q_CAP(CHIPS)':
 'B': CDS_PINID='B';
NODE_NAME     C1337 2
 '@S9S_MB_2U_LIB.S9S_MB_2U(SCH_1):PAGE282_I28@PURE_QUANTA.Q_CAP(CHIPS)':
 'B': CDS_PINID='B';
NODE_NAME     PC393 2
 '@S9S_MB_2U_LIB.S9S_MB_2U(SCH_1):PAGE282_I57@PURE_QUANTA.Q_CAP(CHIPS)':
 'B': CDS_PINID='B';
NODE_NAME     PC392 2
 '@S9S_MB_2U_LIB.S9S_MB_2U(SCH_1):PAGE282_I68@PURE_QUANTA.Q_CAP(CHIPS)':
 'B': CDS_PINID='B';
NODE_NAME     PC391 2
 '@S9S_MB_2U_LIB.S9S_MB_2U(SCH_1):PAGE282_I69@PURE_QUANTA.Q_CAP(CHIPS)':
 'B': CDS_PINID='B';
NODE_NAME     PR4251 2
 '@S9S_MB_2U_LIB.S9S_MB_2U(SCH_1):PAGE282_I70@PURE_QUANTA.Q_RES(CHIPS)':
 'B': CDS_PINID='B';
NODE_NAME     PC1289 2
 '@S9S_MB_2U_LIB.S9S_MB_2U(SCH_1):PAGE282_I74@PURE_QUANTA.Q_CAP(CHIPS)':
 'B': CDS_PINID='B';
NODE_NAME     R4514 2
 '@S9S_MB_2U_LIB.S9S_MB_2U(SCH_1):PAGE201_I161@PURE_QUANTA.Q_RES(CHIPS)':
 'B': CDS_PINID='B';
NODE_NAME     C2340 2
 '@S9S_MB_2U_LIB.S9S_MB_2U(SCH_1):PAGE139_I52@PURE_QUANTA.Q_CAP(CHIPS)':
 'B': CDS_PINID='B';
NODE_NAME     Q148 4
 '@S9S_MB_2U_LIB.S9S_MB_2U(SCH_1):PAGE139_I55@PURE_QUANTA.MOSFET_NCH_DUAL(CHIPS)':
 'S2': CDS_PINID='S2';
NODE_NAME     Q148 1
 '@S9S_MB_2U_LIB.S9S_MB_2U(SCH_1):PAGE139_I61@PURE_QUANTA.MOSFET_NCH_DUAL(CHIPS)':
 'S1': CDS_PINID='S1';
NODE_NAME     R4544 2
 '@S9S_MB_2U_LIB.S9S_MB_2U(SCH_1):PAGE139_I62@PURE_QUANTA.Q_RES(CHIPS)':
 'B': CDS_PINID='B';
NODE_NAME     R4552 2
 '@S9S_MB_2U_LIB.S9S_MB_2U(SCH_1):PAGE230_I50@PURE_QUANTA.Q_RES(CHIPS)':
 'B': CDS_PINID='B';
NODE_NAME     Q145 1
 '@S9S_MB_2U_LIB.S9S_MB_2U(SCH_1):PAGE230_I53@PURE_QUANTA.MOSFET_NCH_DUAL(CHIPS)':
 'S1': CDS_PINID='S1';
NODE_NAME     Q145 4
 '@S9S_MB_2U_LIB.S9S_MB_2U(SCH_1):PAGE230_I58@PURE_QUANTA.MOSFET_NCH_DUAL(CHIPS)':
 'S2': CDS_PINID='S2';
NODE_NAME     C2342 2
 '@S9S_MB_2U_LIB.S9S_MB_2U(SCH_1):PAGE230_I62@PURE_QUANTA.Q_CAP(CHIPS)':
 'B': CDS_PINID='B';
NODE_NAME     PC2188 2
 '@S9S_MB_2U_LIB.S9S_MB_2U(SCH_1):PAGE303_I51@PURE_QUANTA.Q_CAP(CHIPS)':
 'B': CDS_PINID='B';
NODE_NAME     Q123 4
 '@S9S_MB_2U_LIB.S9S_MB_2U(SCH_1):PAGE153_I17@PURE_QUANTA.MOSFET_NCH_DUAL(CHIPS)':
 'S2': CDS_PINID='S2';
NODE_NAME     R4069 2
 '@S9S_MB_2U_LIB.S9S_MB_2U(SCH_1):PAGE153_I20@PURE_QUANTA.Q_RES(CHIPS)':
 'B': CDS_PINID='B';
NODE_NAME     U212 2
 '@S9S_MB_2U_LIB.S9S_MB_2U(SCH_1):PAGE153_I23@PURE_QUANTA.74LVC2G07DW7(CHIPS)':
 'GND': CDS_PINID='GND';
NODE_NAME     U211 2
 '@S9S_MB_2U_LIB.S9S_MB_2U(SCH_1):PAGE153_I26@PURE_QUANTA.74LVC2G07DW7(CHIPS)':
 'GND': CDS_PINID='GND';
NODE_NAME     C593 2
 '@S9S_MB_2U_LIB.S9S_MB_2U(SCH_1):PAGE153_I27@PURE_QUANTA.Q_CAP(CHIPS)':
 'B': CDS_PINID='B';
NODE_NAME     PD101 A
 '@S9S_MB_2U_LIB.S9S_MB_2U(SCH_1):PAGE153_I38@PURE_QUANTA.DIODE_TVS(CHIPS)':
 'A': CDS_PINID='A';
NODE_NAME     PR3791 2
 '@S9S_MB_2U_LIB.S9S_MB_2U(SCH_1):PAGE153_I58@PURE_QUANTA.Q_RES(CHIPS)':
 'B': CDS_PINID='B';
NODE_NAME     PC2086 2
 '@S9S_MB_2U_LIB.S9S_MB_2U(SCH_1):PAGE153_I71@PURE_QUANTA.Q_CAP(CHIPS)':
 'B': CDS_PINID='B';
NODE_NAME     PC2093 1
 '@S9S_MB_2U_LIB.S9S_MB_2U(SCH_1):PAGE153_I72@PURE_QUANTA.Q_CAP(CHIPS)':
 'A': CDS_PINID='A';
NODE_NAME     PR5481 2
 '@S9S_MB_2U_LIB.S9S_MB_2U(SCH_1):PAGE153_I102@PURE_QUANTA.Q_RES(CHIPS)':
 'B': CDS_PINID='B';
NODE_NAME     PD103 A
 '@S9S_MB_2U_LIB.S9S_MB_2U(SCH_1):PAGE153_I104@PURE_QUANTA.SCHOTTKY_AC(CHIPS)':
 'A': CDS_PINID='A';
NODE_NAME     PR3846 1
 '@S9S_MB_2U_LIB.S9S_MB_2U(SCH_1):PAGE236_I45@PURE_QUANTA.Q_RES(CHIPS)':
 'A': CDS_PINID='A';
NODE_NAME     PC2163 2
 '@S9S_MB_2U_LIB.S9S_MB_2U(SCH_1):PAGE236_I54@PURE_QUANTA.Q_CAP(CHIPS)':
 'B': CDS_PINID='B';
NODE_NAME     Q118 4
 '@S9S_MB_2U_LIB.S9S_MB_2U(SCH_1):PAGE131_I16@PURE_QUANTA.MOSFET_NCH_DUAL(CHIPS)':
 'S2': CDS_PINID='S2';
NODE_NAME     U59 2
 '@S9S_MB_2U_LIB.S9S_MB_2U(SCH_1):PAGE131_I19@PURE_QUANTA.74LVC2G07DW7(CHIPS)':
 'GND': CDS_PINID='GND';
NODE_NAME     U58 2
 '@S9S_MB_2U_LIB.S9S_MB_2U(SCH_1):PAGE131_I25@PURE_QUANTA.74LVC2G07DW7(CHIPS)':
 'GND': CDS_PINID='GND';
NODE_NAME     Q119 4
 '@S9S_MB_2U_LIB.S9S_MB_2U(SCH_1):PAGE131_I42@PURE_QUANTA.MOSFET_NCH_DUAL(CHIPS)':
 'S2': CDS_PINID='S2';
NODE_NAME     PC2140 2
 '@S9S_MB_2U_LIB.S9S_MB_2U(SCH_1):PAGE131_I52@PURE_QUANTA.Q_CAP(CHIPS)':
 'B': CDS_PINID='B';
NODE_NAME     PU201 A7
 '@S9S_MB_2U_LIB.S9S_MB_2U(SCH_1):PAGE131_I63@PURE_QUANTA.MAX15090BEWIT(CHIPS)':
 'CDLY': CDS_PINID='CDLY';
NODE_NAME     PU201 B7
 '@S9S_MB_2U_LIB.S9S_MB_2U(SCH_1):PAGE131_I63@PURE_QUANTA.MAX15090BEWIT(CHIPS)':
 'EN#': CDS_PINID='\en#\';
NODE_NAME     PU201 B2
 '@S9S_MB_2U_LIB.S9S_MB_2U(SCH_1):PAGE131_I63@PURE_QUANTA.MAX15090BEWIT(CHIPS)':
 'GND_B2': CDS_PINID='GND_B2';
NODE_NAME     PU201 C1
 '@S9S_MB_2U_LIB.S9S_MB_2U(SCH_1):PAGE131_I63@PURE_QUANTA.MAX15090BEWIT(CHIPS)':
 'GND_C1': CDS_PINID='GND_C1';
NODE_NAME     PU201 C2
 '@S9S_MB_2U_LIB.S9S_MB_2U(SCH_1):PAGE131_I63@PURE_QUANTA.MAX15090BEWIT(CHIPS)':
 'GND_C2': CDS_PINID='GND_C2';
NODE_NAME     PR3822 2
 '@S9S_MB_2U_LIB.S9S_MB_2U(SCH_1):PAGE131_I89@PURE_QUANTA.Q_RES(CHIPS)':
 'B': CDS_PINID='B';
NODE_NAME     PU200 A7
 '@S9S_MB_2U_LIB.S9S_MB_2U(SCH_1):PAGE131_I90@PURE_QUANTA.MAX15090BEWIT(CHIPS)':
 'CDLY': CDS_PINID='CDLY';
NODE_NAME     PU200 B7
 '@S9S_MB_2U_LIB.S9S_MB_2U(SCH_1):PAGE131_I90@PURE_QUANTA.MAX15090BEWIT(CHIPS)':
 'EN#': CDS_PINID='\en#\';
NODE_NAME     PU200 B2
 '@S9S_MB_2U_LIB.S9S_MB_2U(SCH_1):PAGE131_I90@PURE_QUANTA.MAX15090BEWIT(CHIPS)':
 'GND_B2': CDS_PINID='GND_B2';
NODE_NAME     PU200 C1
 '@S9S_MB_2U_LIB.S9S_MB_2U(SCH_1):PAGE131_I90@PURE_QUANTA.MAX15090BEWIT(CHIPS)':
 'GND_C1': CDS_PINID='GND_C1';
NODE_NAME     PU200 C2
 '@S9S_MB_2U_LIB.S9S_MB_2U(SCH_1):PAGE131_I90@PURE_QUANTA.MAX15090BEWIT(CHIPS)':
 'GND_C2': CDS_PINID='GND_C2';
NODE_NAME     PD108 A
 '@S9S_MB_2U_LIB.S9S_MB_2U(SCH_1):PAGE131_I93@PURE_QUANTA.SCHOTTKY_AC(CHIPS)':
 'A': CDS_PINID='A';
NODE_NAME     PC2151 2
 '@S9S_MB_2U_LIB.S9S_MB_2U(SCH_1):PAGE131_I96@PURE_QUANTA.Q_CAP(CHIPS)':
 'B': CDS_PINID='B';
NODE_NAME     PC2141 2
 '@S9S_MB_2U_LIB.S9S_MB_2U(SCH_1):PAGE131_I100@PURE_QUANTA.Q_CAP(CHIPS)':
 'B': CDS_PINID='B';
NODE_NAME     PC2143 2
 '@S9S_MB_2U_LIB.S9S_MB_2U(SCH_1):PAGE131_I102@PURE_QUANTA.Q_CAP(CHIPS)':
 'B': CDS_PINID='B';
NODE_NAME     PD109 A
 '@S9S_MB_2U_LIB.S9S_MB_2U(SCH_1):PAGE131_I107@PURE_QUANTA.SCHOTTKY_AC(CHIPS)':
 'A': CDS_PINID='A';
NODE_NAME     PC2137 2
 '@S9S_MB_2U_LIB.S9S_MB_2U(SCH_1):PAGE131_I109@PURE_QUANTA.Q_CAP(CHIPS)':
 'B': CDS_PINID='B';
NODE_NAME     PC2168 2
 '@S9S_MB_2U_LIB.S9S_MB_2U(SCH_1):PAGE237_I35@PURE_QUANTA.Q_CAP(CHIPS)':
 'B': CDS_PINID='B';
NODE_NAME     PR3856 1
 '@S9S_MB_2U_LIB.S9S_MB_2U(SCH_1):PAGE237_I46@PURE_QUANTA.Q_RES(CHIPS)':
 'A': CDS_PINID='A';
NODE_NAME     PC1321 2
 '@S9S_MB_2U_LIB.S9S_MB_2U(SCH_1):PAGE237_I50@PURE_QUANTA.Q_CAP(CHIPS)':
 'B': CDS_PINID='B';
NODE_NAME     PU207 3
 '@S9S_MB_2U_LIB.S9S_MB_2U(SCH_1):PAGE237_I51@PURE_QUANTA.MP5016GQHLZ(CHIPS)':
 'GND': CDS_PINID='GND';
NODE_NAME     PC2173 2
 '@S9S_MB_2U_LIB.S9S_MB_2U(SCH_1):PAGE237_I56@PURE_QUANTA.Q_CAP(CHIPS)':
 'B': CDS_PINID='B';
NODE_NAME     PR3962 2
 '@S9S_MB_2U_LIB.S9S_MB_2U(SCH_1):PAGE324_I28@PURE_QUANTA.Q_RES(CHIPS)':
 'B': CDS_PINID='B';
NODE_NAME     PC2207 2
 '@S9S_MB_2U_LIB.S9S_MB_2U(SCH_1):PAGE324_I31@PURE_QUANTA.Q_CAP(CHIPS)':
 'B': CDS_PINID='B';
NODE_NAME     PC2210 2
 '@S9S_MB_2U_LIB.S9S_MB_2U(SCH_1):PAGE324_I37@PURE_QUANTA.Q_CAP(CHIPS)':
 'B': CDS_PINID='B';
NODE_NAME     PR3971 2
 '@S9S_MB_2U_LIB.S9S_MB_2U(SCH_1):PAGE324_I41@PURE_QUANTA.Q_RES(CHIPS)':
 'B': CDS_PINID='B';
NODE_NAME     PC2217 2
 '@S9S_MB_2U_LIB.S9S_MB_2U(SCH_1):PAGE324_I75@PURE_QUANTA.Q_CAP(CHIPS)':
 'B': CDS_PINID='B';
NODE_NAME     PC2219 2
 '@S9S_MB_2U_LIB.S9S_MB_2U(SCH_1):PAGE324_I78@PURE_QUANTA.Q_CAP(CHIPS)':
 'B': CDS_PINID='B';
NODE_NAME     PU293 3
 '@S9S_MB_2U_LIB.S9S_MB_2U(SCH_1):PAGE323_I31@PURE_QUANTA.MP5016GQHLZ(CHIPS)':
 'GND': CDS_PINID='GND';
NODE_NAME     PC2196 2
 '@S9S_MB_2U_LIB.S9S_MB_2U(SCH_1):PAGE323_I37@PURE_QUANTA.Q_CAP(CHIPS)':
 'B': CDS_PINID='B';
NODE_NAME     PR3944 2
 '@S9S_MB_2U_LIB.S9S_MB_2U(SCH_1):PAGE323_I40@PURE_QUANTA.Q_RES(CHIPS)':
 'B': CDS_PINID='B';
NODE_NAME     PC2341 2
 '@S9S_MB_2U_LIB.S9S_MB_2U(SCH_1):PAGE323_I42@PURE_QUANTA.Q_CAP(CHIPS)':
 'B': CDS_PINID='B';
NODE_NAME     PC2281 2
 '@S9S_MB_2U_LIB.S9S_MB_2U(SCH_1):PAGE323_I47@PURE_QUANTA.Q_CAP(CHIPS)':
 'B': CDS_PINID='B';
NODE_NAME     PU292 3
 '@S9S_MB_2U_LIB.S9S_MB_2U(SCH_1):PAGE323_I49@PURE_QUANTA.RS31312R(CHIPS)':
 'ENTM': CDS_PINID='ENTM';
NODE_NAME     PU292 7
 '@S9S_MB_2U_LIB.S9S_MB_2U(SCH_1):PAGE323_I49@PURE_QUANTA.RS31312R(CHIPS)':
 'GND': CDS_PINID='GND';
NODE_NAME     PU292 2
 '@S9S_MB_2U_LIB.S9S_MB_2U(SCH_1):PAGE323_I49@PURE_QUANTA.RS31312R(CHIPS)':
 'LOADEN': CDS_PINID='LOADEN';
NODE_NAME     PC2198 2
 '@S9S_MB_2U_LIB.S9S_MB_2U(SCH_1):PAGE323_I51@PURE_QUANTA.Q_CAP(CHIPS)':
 'B': CDS_PINID='B';
NODE_NAME     PC2202 2
 '@S9S_MB_2U_LIB.S9S_MB_2U(SCH_1):PAGE323_I56@PURE_QUANTA.Q_CAP(CHIPS)':
 'B': CDS_PINID='B';
NODE_NAME     PC2229 2
 '@S9S_MB_2U_LIB.S9S_MB_2U(SCH_1):PAGE229_I8@PURE_QUANTA.Q_CAP(CHIPS)':
 'B': CDS_PINID='B';
NODE_NAME     PR3999 2
 '@S9S_MB_2U_LIB.S9S_MB_2U(SCH_1):PAGE229_I11@PURE_QUANTA.Q_RES(CHIPS)':
 'B': CDS_PINID='B';
NODE_NAME     PD115 A
 '@S9S_MB_2U_LIB.S9S_MB_2U(SCH_1):PAGE229_I29@PURE_QUANTA.DIODE_TVS(CHIPS)':
 'A': CDS_PINID='A';
NODE_NAME     PC2230 2
 '@S9S_MB_2U_LIB.S9S_MB_2U(SCH_1):PAGE229_I31@PURE_QUANTA.Q_CAP(CHIPS)':
 'B': CDS_PINID='B';
NODE_NAME     PC2232 2
 '@S9S_MB_2U_LIB.S9S_MB_2U(SCH_1):PAGE229_I33@PURE_QUANTA.Q_CAP(CHIPS)':
 'B': CDS_PINID='B';
NODE_NAME     PC2239 2
 '@S9S_MB_2U_LIB.S9S_MB_2U(SCH_1):PAGE229_I53@PURE_QUANTA.Q_CAP(CHIPS)':
 'B': CDS_PINID='B';
NODE_NAME     PC2234 1
 '@S9S_MB_2U_LIB.S9S_MB_2U(SCH_1):PAGE229_I66@PURE_QUANTA.Q_CAP(CHIPS)':
 'A': CDS_PINID='A';
NODE_NAME     PC2233 2
 '@S9S_MB_2U_LIB.S9S_MB_2U(SCH_1):PAGE229_I68@PURE_QUANTA.Q_CAP(CHIPS)':
 'B': CDS_PINID='B';
NODE_NAME     PC1898 2
 '@S9S_MB_2U_LIB.S9S_MB_2U(SCH_1):PAGE244_I12@PURE_QUANTA.Q_CAP(CHIPS)':
 'B': CDS_PINID='B';
NODE_NAME     PC1226 2
 '@S9S_MB_2U_LIB.S9S_MB_2U(SCH_1):PAGE248_I45@PURE_QUANTA.Q_CAP(CHIPS)':
 'B': CDS_PINID='B';
NODE_NAME     PR1336 2
 '@S9S_MB_2U_LIB.S9S_MB_2U(SCH_1):PAGE267_I15@PURE_QUANTA.Q_RES(CHIPS)':
 'B': CDS_PINID='B';
NODE_NAME     PJ65 2
 '@S9S_MB_2U_LIB.S9S_MB_2U(SCH_1):PAGE267_I33@PURE_QUANTA.Q_SHORT(CHIPS)':
 '2': CDS_PINID='\2\';
NODE_NAME     R1445 2
 '@S9S_MB_2U_LIB.S9S_MB_2U(SCH_1):PAGE268_I11@PURE_QUANTA.Q_RES(CHIPS)':
 'B': CDS_PINID='B';
NODE_NAME     PC27 2
 '@S9S_MB_2U_LIB.S9S_MB_2U(SCH_1):PAGE268_I25@PURE_QUANTA.Q_CAP(CHIPS)':
 'B': CDS_PINID='B';
NODE_NAME     PC1278 2
 '@S9S_MB_2U_LIB.S9S_MB_2U(SCH_1):PAGE268_I42@PURE_QUANTA.Q_CAP(CHIPS)':
 'B': CDS_PINID='B';
NODE_NAME     C2445 2
 '@S9S_MB_2U_LIB.S9S_MB_2U(SCH_1):PAGE285_I11@PURE_QUANTA.Q_CAP(CHIPS)':
 'B': CDS_PINID='B';
NODE_NAME     R2374 2
 '@S9S_MB_2U_LIB.S9S_MB_2U(SCH_1):PAGE285_I13@PURE_QUANTA.Q_RES(CHIPS)':
 'B': CDS_PINID='B';
NODE_NAME     PU80 2
 '@S9S_MB_2U_LIB.S9S_MB_2U(SCH_1):PAGE285_I25@PURE_QUANTA.RS53318LR(CHIPS)':
 'AGND': CDS_PINID='AGND';
NODE_NAME     PU80 11_18
 '@S9S_MB_2U_LIB.S9S_MB_2U(SCH_1):PAGE285_I25@PURE_QUANTA.RS53318LR(CHIPS)':
 'PGND': CDS_PINID='PGND';
NODE_NAME     PC1280 2
 '@S9S_MB_2U_LIB.S9S_MB_2U(SCH_1):PAGE286_I9@PURE_QUANTA.Q_CAP(CHIPS)':
 'B': CDS_PINID='B';
NODE_NAME     PU82 7
 '@S9S_MB_2U_LIB.S9S_MB_2U(SCH_1):PAGE286_I20@PURE_QUANTA.RS53317LR(CHIPS)':
 'AGND': CDS_PINID='AGND';
NODE_NAME     PU82 1
 '@S9S_MB_2U_LIB.S9S_MB_2U(SCH_1):PAGE286_I20@PURE_QUANTA.RS53317LR(CHIPS)':
 'PGND1': CDS_PINID='PGND1';
NODE_NAME     PU82 14
 '@S9S_MB_2U_LIB.S9S_MB_2U(SCH_1):PAGE286_I20@PURE_QUANTA.RS53317LR(CHIPS)':
 'PGND2': CDS_PINID='PGND2';
NODE_NAME     PC1285 2
 '@S9S_MB_2U_LIB.S9S_MB_2U(SCH_1):PAGE286_I36@PURE_QUANTA.Q_CAP(CHIPS)':
 'B': CDS_PINID='B';
NODE_NAME     PC2340 2
 '@S9S_MB_2U_LIB.S9S_MB_2U(SCH_1):PAGE229_I7@PURE_QUANTA.Q_CAP(CHIPS)':
 'B': CDS_PINID='B';
NODE_NAME     PC2238 2
 '@S9S_MB_2U_LIB.S9S_MB_2U(SCH_1):PAGE229_I83@PURE_QUANTA.Q_CAP(CHIPS)':
 'B': CDS_PINID='B';
NODE_NAME     U316 3
 '@S9S_MB_2U_LIB.S9S_MB_2U(SCH_1):PAGE139_I86@PURE_QUANTA.74LVC2G17GW(CHIPS)':
 'A1': CDS_PINID='A1';
NODE_NAME     U316 2
 '@S9S_MB_2U_LIB.S9S_MB_2U(SCH_1):PAGE139_I86@PURE_QUANTA.74LVC2G17GW(CHIPS)':
 'GND': CDS_PINID='GND';
NODE_NAME     R4548 2
 '@S9S_MB_2U_LIB.S9S_MB_2U(SCH_1):PAGE139_I87@PURE_QUANTA.Q_RES(CHIPS)':
 'B': CDS_PINID='B';
NODE_NAME     C2341 2
 '@S9S_MB_2U_LIB.S9S_MB_2U(SCH_1):PAGE139_I93@PURE_QUANTA.Q_CAP(CHIPS)':
 'B': CDS_PINID='B';
NODE_NAME     R4555 2
 '@S9S_MB_2U_LIB.S9S_MB_2U(SCH_1):PAGE139_I99@PURE_QUANTA.Q_RES(CHIPS)':
 'B': CDS_PINID='B';
NODE_NAME     R2927 2
 '@S9S_MB_2U_LIB.S9S_MB_2U(SCH_1):PAGE140_I203@PURE_QUANTA.Q_RES(CHIPS)':
 'B': CDS_PINID='B';
NODE_NAME     U39 12
 '@S9S_MB_2U_LIB.S9S_MB_2U(SCH_1):PAGE221_I103@PURE_QUANTA.TCA9548APWR(CHIPS)':
 'GND': CDS_PINID='GND';
NODE_NAME     C2056 2
 '@S9S_MB_2U_LIB.S9S_MB_2U(SCH_1):PAGE221_I106@PURE_QUANTA.Q_CAP(CHIPS)':
 'B': CDS_PINID='B';
NODE_NAME     C2343 2
 '@S9S_MB_2U_LIB.S9S_MB_2U(SCH_1):PAGE143_I118@PURE_QUANTA.Q_CAP(CHIPS)':
 'B': CDS_PINID='B';
NODE_NAME     Q146 4
 '@S9S_MB_2U_LIB.S9S_MB_2U(SCH_1):PAGE143_I121@PURE_QUANTA.MOSFET_NCH_DUAL(CHIPS)':
 'S2': CDS_PINID='S2';
NODE_NAME     Q146 1
 '@S9S_MB_2U_LIB.S9S_MB_2U(SCH_1):PAGE143_I126@PURE_QUANTA.MOSFET_NCH_DUAL(CHIPS)':
 'S1': CDS_PINID='S1';
NODE_NAME     R4559 2
 '@S9S_MB_2U_LIB.S9S_MB_2U(SCH_1):PAGE143_I129@PURE_QUANTA.Q_RES(CHIPS)':
 'B': CDS_PINID='B';
NODE_NAME     R4564 2
 '@S9S_MB_2U_LIB.S9S_MB_2U(SCH_1):PAGE176_I239@PURE_QUANTA.Q_RES(CHIPS)':
 'B': CDS_PINID='B';
NODE_NAME     R4565 2
 '@S9S_MB_2U_LIB.S9S_MB_2U(SCH_1):PAGE176_I240@PURE_QUANTA.Q_RES(CHIPS)':
 'B': CDS_PINID='B';
NODE_NAME     R4568 2
 '@S9S_MB_2U_LIB.S9S_MB_2U(SCH_1):PAGE239_I346@PURE_QUANTA.Q_RES(CHIPS)':
 'B': CDS_PINID='B';
NODE_NAME     C2344 2
 '@S9S_MB_2U_LIB.S9S_MB_2U(SCH_1):PAGE152_I87@PURE_QUANTA.Q_CAP(CHIPS)':
 'B': CDS_PINID='B';
NODE_NAME     C2345 2
 '@S9S_MB_2U_LIB.S9S_MB_2U(SCH_1):PAGE156_I81@PURE_QUANTA.Q_CAP(CHIPS)':
 'B': CDS_PINID='B';
NODE_NAME     R4581 2
 '@S9S_MB_2U_LIB.S9S_MB_2U(SCH_1):PAGE184_I1@PURE_QUANTA.Q_RES(CHIPS)':
 'B': CDS_PINID='B';
NODE_NAME     R4583 2
 '@S9S_MB_2U_LIB.S9S_MB_2U(SCH_1):PAGE184_I18@PURE_QUANTA.Q_RES(CHIPS)':
 'B': CDS_PINID='B';
NODE_NAME     R4585 2
 '@S9S_MB_2U_LIB.S9S_MB_2U(SCH_1):PAGE184_I20@PURE_QUANTA.Q_RES(CHIPS)':
 'B': CDS_PINID='B';
NODE_NAME     R2243 2
 '@S9S_MB_2U_LIB.S9S_MB_2U(SCH_1):PAGE184_I30@PURE_QUANTA.Q_RES(CHIPS)':
 'B': CDS_PINID='B';
NODE_NAME     R4588 2
 '@S9S_MB_2U_LIB.S9S_MB_2U(SCH_1):PAGE184_I58@PURE_QUANTA.Q_RES(CHIPS)':
 'B': CDS_PINID='B';
NODE_NAME     R4590 2
 '@S9S_MB_2U_LIB.S9S_MB_2U(SCH_1):PAGE184_I59@PURE_QUANTA.Q_RES(CHIPS)':
 'B': CDS_PINID='B';
NODE_NAME     D6 C
 '@S9S_MB_2U_LIB.S9S_MB_2U(SCH_1):PAGE207_I279@PURE_QUANTA.Q_LED(CHIPS)':
 'C': CDS_PINID='C';
NODE_NAME     U209 12
 '@S9S_MB_2U_LIB.S9S_MB_2U(SCH_1):PAGE154_I206@PURE_QUANTA.PCA9555APW(CHIPS)':
 'VSS': CDS_PINID='VSS';
NODE_NAME     U51 12
 '@S9S_MB_2U_LIB.S9S_MB_2U(SCH_1):PAGE132_I66@PURE_QUANTA.PCA9555APW(CHIPS)':
 'VSS': CDS_PINID='VSS';
NODE_NAME     Q144 4
 '@S9S_MB_2U_LIB.S9S_MB_2U(SCH_1):PAGE213_I21@PURE_QUANTA.MOSFET_NCH_DUAL(CHIPS)':
 'S2': CDS_PINID='S2';
NODE_NAME     Q144 1
 '@S9S_MB_2U_LIB.S9S_MB_2U(SCH_1):PAGE213_I27@PURE_QUANTA.MOSFET_NCH_DUAL(CHIPS)':
 'S1': CDS_PINID='S1';
NODE_NAME     C1243 2
 '@S9S_MB_2U_LIB.S9S_MB_2U(SCH_1):PAGE181_I162@PURE_QUANTA.Q_CAP(CHIPS)':
 'B': CDS_PINID='B';
NODE_NAME     C1245 2
 '@S9S_MB_2U_LIB.S9S_MB_2U(SCH_1):PAGE181_I163@PURE_QUANTA.Q_CAP(CHIPS)':
 'B': CDS_PINID='B';
NODE_NAME     U16 3
 '@S9S_MB_2U_LIB.S9S_MB_2U(SCH_1):PAGE135_I115@PURE_QUANTA.74LVC1G66GV(CHIPS)':
 'GND': CDS_PINID='GND';
NODE_NAME     R1495 2
 '@S9S_MB_2U_LIB.S9S_MB_2U(SCH_1):PAGE312_I190@PURE_QUANTA.Q_RES(CHIPS)':
 'B': CDS_PINID='B';
NODE_NAME     U322 3
 '@S9S_MB_2U_LIB.S9S_MB_2U(SCH_1):PAGE154_I221@PURE_QUANTA.74LVC1G08W57(CHIPS)':
 'GND': CDS_PINID='GND';
NODE_NAME     C2346 2
 '@S9S_MB_2U_LIB.S9S_MB_2U(SCH_1):PAGE154_I223@PURE_QUANTA.Q_CAP(CHIPS)':
 'B': CDS_PINID='B';
NODE_NAME     U52 1
 '@S9S_MB_2U_LIB.S9S_MB_2U(SCH_1):PAGE154_I228@PURE_QUANTA.APX80929SAG7(CHIPS)':
 'GND': CDS_PINID='GND';
NODE_NAME     C580 2
 '@S9S_MB_2U_LIB.S9S_MB_2U(SCH_1):PAGE154_I229@PURE_QUANTA.Q_CAP(CHIPS)':
 'B': CDS_PINID='B';
NODE_NAME     U216 1
 '@S9S_MB_2U_LIB.S9S_MB_2U(SCH_1):PAGE132_I85@PURE_QUANTA.APX80929SAG7(CHIPS)':
 'GND': CDS_PINID='GND';
NODE_NAME     C1819 2
 '@S9S_MB_2U_LIB.S9S_MB_2U(SCH_1):PAGE132_I87@PURE_QUANTA.Q_CAP(CHIPS)':
 'B': CDS_PINID='B';
NODE_NAME     C2347 2
 '@S9S_MB_2U_LIB.S9S_MB_2U(SCH_1):PAGE132_I90@PURE_QUANTA.Q_CAP(CHIPS)':
 'B': CDS_PINID='B';
NODE_NAME     U323 3
 '@S9S_MB_2U_LIB.S9S_MB_2U(SCH_1):PAGE132_I92@PURE_QUANTA.74LVC1G08W57(CHIPS)':
 'GND': CDS_PINID='GND';
NODE_NAME     PC1368 1
 '@S9S_MB_2U_LIB.S9S_MB_2U(SCH_1):PAGE275_I8@PURE_QUANTA.Q_CAP(CHIPS)':
 'A': CDS_PINID='A';
NODE_NAME     PC1243_P1_2 2
 '@S9S_MB_2U_LIB.S9S_MB_2U(SCH_1):PAGE275_I16@PURE_QUANTA.Q_CAP(CHIPS)':
 'B': CDS_PINID='B';
NODE_NAME     PR225 2
 '@S9S_MB_2U_LIB.S9S_MB_2U(SCH_1):PAGE275_I20@PURE_QUANTA.Q_RES(CHIPS)':
 'B': CDS_PINID='B';
NODE_NAME     PC1242_P1_1 2
 '@S9S_MB_2U_LIB.S9S_MB_2U(SCH_1):PAGE275_I31@PURE_QUANTA.Q_CAP(CHIPS)':
 'B': CDS_PINID='B';
NODE_NAME     PC406_P1_2 2
 '@S9S_MB_2U_LIB.S9S_MB_2U(SCH_1):PAGE275_I42@PURE_QUANTA.Q_CAP(CHIPS)':
 'B': CDS_PINID='B';
NODE_NAME     PC724_P1_1 2
 '@S9S_MB_2U_LIB.S9S_MB_2U(SCH_1):PAGE275_I58@PURE_QUANTA.Q_CAP(CHIPS)':
 'B': CDS_PINID='B';
NODE_NAME     PC414 2
 '@S9S_MB_2U_LIB.S9S_MB_2U(SCH_1):PAGE275_I66@PURE_QUANTA.Q_CAPP(CHIPS)':
 'B': CDS_PINID='B';
NODE_NAME     PC415 2
 '@S9S_MB_2U_LIB.S9S_MB_2U(SCH_1):PAGE275_I67@PURE_QUANTA.Q_CAPP(CHIPS)':
 'B': CDS_PINID='B';
NODE_NAME     PC410_P1_1 2
 '@S9S_MB_2U_LIB.S9S_MB_2U(SCH_1):PAGE275_I74@PURE_QUANTA.Q_CAP(CHIPS)':
 'B': CDS_PINID='B';
NODE_NAME     PC412_P1_1 2
 '@S9S_MB_2U_LIB.S9S_MB_2U(SCH_1):PAGE275_I75@PURE_QUANTA.Q_CAP(CHIPS)':
 'B': CDS_PINID='B';
NODE_NAME     PC1657 2
 '@S9S_MB_2U_LIB.S9S_MB_2U(SCH_1):PAGE275_I77@PURE_QUANTA.Q_CAP(CHIPS)':
 'B': CDS_PINID='B';
NODE_NAME     PC1680 2
 '@S9S_MB_2U_LIB.S9S_MB_2U(SCH_1):PAGE275_I85@PURE_QUANTA.Q_CAP(CHIPS)':
 'B': CDS_PINID='B';
NODE_NAME     PC417 2
 '@S9S_MB_2U_LIB.S9S_MB_2U(SCH_1):PAGE275_I87@PURE_QUANTA.Q_CAPP(CHIPS)':
 'B': CDS_PINID='B';
NODE_NAME     PU75_P1_1 2
 '@S9S_MB_2U_LIB.S9S_MB_2U(SCH_1):PAGE275_I89@PURE_QUANTA.ISL99390FRZTR5935(CHIPS)':
 'AGND': CDS_PINID='AGND';
NODE_NAME     PU75_P1_1 5
 '@S9S_MB_2U_LIB.S9S_MB_2U(SCH_1):PAGE275_I89@PURE_QUANTA.ISL99390FRZTR5935(CHIPS)':
 'PGND1': CDS_PINID='PGND1';
NODE_NAME     PU75_P1_1 7_9-20_24
 '@S9S_MB_2U_LIB.S9S_MB_2U(SCH_1):PAGE275_I89@PURE_QUANTA.ISL99390FRZTR5935(CHIPS)':
 'PGND2': CDS_PINID='PGND2';
NODE_NAME     PU75_P1_1 40
 '@S9S_MB_2U_LIB.S9S_MB_2U(SCH_1):PAGE275_I89@PURE_QUANTA.ISL99390FRZTR5935(CHIPS)':
 'PGND3': CDS_PINID='PGND3';
NODE_NAME     PC1350 1
 '@S9S_MB_2U_LIB.S9S_MB_2U(SCH_1):PAGE257_I15@PURE_QUANTA.Q_CAP(CHIPS)':
 'A': CDS_PINID='A';
NODE_NAME     PC601 2
 '@S9S_MB_2U_LIB.S9S_MB_2U(SCH_1):PAGE257_I18@PURE_QUANTA.Q_CAP(CHIPS)':
 'B': CDS_PINID='B';
NODE_NAME     PC1212_P0_2 2
 '@S9S_MB_2U_LIB.S9S_MB_2U(SCH_1):PAGE257_I21@PURE_QUANTA.Q_CAP(CHIPS)':
 'B': CDS_PINID='B';
NODE_NAME     PC609_P0_2 2
 '@S9S_MB_2U_LIB.S9S_MB_2U(SCH_1):PAGE257_I31@PURE_QUANTA.Q_CAP(CHIPS)':
 'B': CDS_PINID='B';
NODE_NAME     PC616_P0_2 2
 '@S9S_MB_2U_LIB.S9S_MB_2U(SCH_1):PAGE257_I52@PURE_QUANTA.Q_CAP(CHIPS)':
 'B': CDS_PINID='B';
NODE_NAME     PC619 2
 '@S9S_MB_2U_LIB.S9S_MB_2U(SCH_1):PAGE257_I57@PURE_QUANTA.Q_CAPP(CHIPS)':
 'B': CDS_PINID='B';
NODE_NAME     PC620 2
 '@S9S_MB_2U_LIB.S9S_MB_2U(SCH_1):PAGE257_I58@PURE_QUANTA.Q_CAPP(CHIPS)':
 'B': CDS_PINID='B';
NODE_NAME     PC1669 2
 '@S9S_MB_2U_LIB.S9S_MB_2U(SCH_1):PAGE257_I83@PURE_QUANTA.Q_CAP(CHIPS)':
 'B': CDS_PINID='B';
NODE_NAME     PC1671 2
 '@S9S_MB_2U_LIB.S9S_MB_2U(SCH_1):PAGE257_I85@PURE_QUANTA.Q_CAP(CHIPS)':
 'B': CDS_PINID='B';
NODE_NAME     PR3947 1
 '@S9S_MB_2U_LIB.S9S_MB_2U(SCH_1):PAGE323_I6@PURE_QUANTA.Q_RES(CHIPS)':
 'A': CDS_PINID='A';
NODE_NAME     PR1728 2
 '@S9S_MB_2U_LIB.S9S_MB_2U(SCH_1):PAGE280_I1@PURE_QUANTA.Q_RES(CHIPS)':
 'B': CDS_PINID='B';
NODE_NAME     PC428 2
 '@S9S_MB_2U_LIB.S9S_MB_2U(SCH_1):PAGE280_I11@PURE_QUANTA.Q_CAP(CHIPS)':
 'B': CDS_PINID='B';
NODE_NAME     PR1709 2
 '@S9S_MB_2U_LIB.S9S_MB_2U(SCH_1):PAGE262_I2@PURE_QUANTA.Q_RES(CHIPS)':
 'B': CDS_PINID='B';
NODE_NAME     PC1348 1
 '@S9S_MB_2U_LIB.S9S_MB_2U(SCH_1):PAGE262_I10@PURE_QUANTA.Q_CAP(CHIPS)':
 'A': CDS_PINID='A';
NODE_NAME     PU42 6_7-13_15-29
 '@S9S_MB_2U_LIB.S9S_MB_2U(SCH_1):PAGE262_I14@PURE_QUANTA.RAA2213404GNPHB0(CHIPS)':
 'GND1': CDS_PINID='GND1';
NODE_NAME     PU42 23
 '@S9S_MB_2U_LIB.S9S_MB_2U(SCH_1):PAGE262_I14@PURE_QUANTA.RAA2213404GNPHB0(CHIPS)':
 'GND2': CDS_PINID='GND2';
NODE_NAME     PU42 26
 '@S9S_MB_2U_LIB.S9S_MB_2U(SCH_1):PAGE262_I14@PURE_QUANTA.RAA2213404GNPHB0(CHIPS)':
 'GND3': CDS_PINID='GND3';
NODE_NAME     PC1642 2
 '@S9S_MB_2U_LIB.S9S_MB_2U(SCH_1):PAGE249_I4@PURE_QUANTA.Q_CAP(CHIPS)':
 'B': CDS_PINID='B';
NODE_NAME     PC1234 2
 '@S9S_MB_2U_LIB.S9S_MB_2U(SCH_1):PAGE249_I21@PURE_QUANTA.Q_CAP(CHIPS)':
 'B': CDS_PINID='B';
NODE_NAME     PC1237 2
 '@S9S_MB_2U_LIB.S9S_MB_2U(SCH_1):PAGE249_I29@PURE_QUANTA.Q_CAP(CHIPS)':
 'B': CDS_PINID='B';
NODE_NAME     C2287 2
 '@S9S_MB_2U_LIB.S9S_MB_2U(SCH_1):PAGE249_I36@PURE_QUANTA.Q_CAP(CHIPS)':
 'B': CDS_PINID='B';
NODE_NAME     PC1238 2
 '@S9S_MB_2U_LIB.S9S_MB_2U(SCH_1):PAGE249_I37@PURE_QUANTA.Q_CAP(CHIPS)':
 'B': CDS_PINID='B';
NODE_NAME     PC1239 2
 '@S9S_MB_2U_LIB.S9S_MB_2U(SCH_1):PAGE249_I38@PURE_QUANTA.Q_CAP(CHIPS)':
 'B': CDS_PINID='B';
NODE_NAME     PR214 2
 '@S9S_MB_2U_LIB.S9S_MB_2U(SCH_1):PAGE282_I11@PURE_QUANTA.Q_RES(CHIPS)':
 'B': CDS_PINID='B';
NODE_NAME     PR558 2
 '@S9S_MB_2U_LIB.S9S_MB_2U(SCH_1):PAGE282_I15@PURE_QUANTA.Q_RES(CHIPS)':
 'B': CDS_PINID='B';
NODE_NAME     C1336 2
 '@S9S_MB_2U_LIB.S9S_MB_2U(SCH_1):PAGE282_I24@PURE_QUANTA.Q_CAP(CHIPS)':
 'B': CDS_PINID='B';
NODE_NAME     PR4257 2
 '@S9S_MB_2U_LIB.S9S_MB_2U(SCH_1):PAGE282_I59@PURE_QUANTA.Q_RES(CHIPS)':
 'B': CDS_PINID='B';
NODE_NAME     PR4255 2
 '@S9S_MB_2U_LIB.S9S_MB_2U(SCH_1):PAGE282_I62@PURE_QUANTA.Q_RES(CHIPS)':
 'B': CDS_PINID='B';
NODE_NAME     PR4252 2
 '@S9S_MB_2U_LIB.S9S_MB_2U(SCH_1):PAGE282_I64@PURE_QUANTA.Q_RES(CHIPS)':
 'B': CDS_PINID='B';
NODE_NAME     PR4253 2
 '@S9S_MB_2U_LIB.S9S_MB_2U(SCH_1):PAGE282_I65@PURE_QUANTA.Q_RES(CHIPS)':
 'B': CDS_PINID='B';
NODE_NAME     PR4254 2
 '@S9S_MB_2U_LIB.S9S_MB_2U(SCH_1):PAGE282_I66@PURE_QUANTA.Q_RES(CHIPS)':
 'B': CDS_PINID='B';
NODE_NAME     PC394 2
 '@S9S_MB_2U_LIB.S9S_MB_2U(SCH_1):PAGE282_I77@PURE_QUANTA.Q_CAP(CHIPS)':
 'B': CDS_PINID='B';
NODE_NAME     PC378 2
 '@S9S_MB_2U_LIB.S9S_MB_2U(SCH_1):PAGE283_I24@PURE_QUANTA.Q_CAP(CHIPS)':
 'B': CDS_PINID='B';
NODE_NAME     PC1940 2
 '@S9S_MB_2U_LIB.S9S_MB_2U(SCH_1):PAGE283_I25@PURE_QUANTA.Q_CAPP(CHIPS)':
 'B': CDS_PINID='B';
NODE_NAME     PC384 2
 '@S9S_MB_2U_LIB.S9S_MB_2U(SCH_1):PAGE283_I26@PURE_QUANTA.Q_CAPP(CHIPS)':
 'B': CDS_PINID='B';
NODE_NAME     PR4258 2
 '@S9S_MB_2U_LIB.S9S_MB_2U(SCH_1):PAGE283_I35@PURE_QUANTA.Q_RES(CHIPS)':
 'B': CDS_PINID='B';
NODE_NAME     PR276 2
 '@S9S_MB_2U_LIB.S9S_MB_2U(SCH_1):PAGE278_I35@PURE_QUANTA.Q_RES(CHIPS)':
 'B': CDS_PINID='B';
NODE_NAME     PC474 2
 '@S9S_MB_2U_LIB.S9S_MB_2U(SCH_1):PAGE278_I36@PURE_QUANTA.Q_CAP(CHIPS)':
 'B': CDS_PINID='B';
NODE_NAME     PU22 TH
 '@S9S_MB_2U_LIB.S9S_MB_2U(SCH_1):PAGE278_I38@PURE_QUANTA.ISL69260IRAZT(CHIPS)':
 'TH_GND': CDS_PINID='TH_GND';
NODE_NAME     PR567 2
 '@S9S_MB_2U_LIB.S9S_MB_2U(SCH_1):PAGE278_I41@PURE_QUANTA.Q_RES(CHIPS)':
 'B': CDS_PINID='B';
NODE_NAME     PR566 2
 '@S9S_MB_2U_LIB.S9S_MB_2U(SCH_1):PAGE278_I46@PURE_QUANTA.Q_RES(CHIPS)':
 'B': CDS_PINID='B';
NODE_NAME     C2451 2
 '@S9S_MB_2U_LIB.S9S_MB_2U(SCH_1):PAGE278_I63@PURE_QUANTA.Q_CAP(CHIPS)':
 'B': CDS_PINID='B';
NODE_NAME     PR665 2
 '@S9S_MB_2U_LIB.S9S_MB_2U(SCH_1):PAGE278_I67@PURE_QUANTA.Q_RES(CHIPS)':
 'B': CDS_PINID='B';
NODE_NAME     PR667 2
 '@S9S_MB_2U_LIB.S9S_MB_2U(SCH_1):PAGE278_I75@PURE_QUANTA.Q_RES(CHIPS)':
 'B': CDS_PINID='B';
NODE_NAME     PR4242 2
 '@S9S_MB_2U_LIB.S9S_MB_2U(SCH_1):PAGE278_I89@PURE_QUANTA.Q_RES(CHIPS)':
 'B': CDS_PINID='B';
NODE_NAME     PC477 2
 '@S9S_MB_2U_LIB.S9S_MB_2U(SCH_1):PAGE278_I92@PURE_QUANTA.Q_CAP(CHIPS)':
 'B': CDS_PINID='B';
NODE_NAME     PC1193 2
 '@S9S_MB_2U_LIB.S9S_MB_2U(SCH_1):PAGE278_I96@PURE_QUANTA.Q_CAP(CHIPS)':
 'B': CDS_PINID='B';
NODE_NAME     C2450 2
 '@S9S_MB_2U_LIB.S9S_MB_2U(SCH_1):PAGE278_I106@PURE_QUANTA.Q_CAP(CHIPS)':
 'B': CDS_PINID='B';
NODE_NAME     PU12_P0_2 2
 '@S9S_MB_2U_LIB.S9S_MB_2U(SCH_1):PAGE253_I6@PURE_QUANTA.ISL99390FRZTR5935(CHIPS)':
 'AGND': CDS_PINID='AGND';
NODE_NAME     PU12_P0_2 5
 '@S9S_MB_2U_LIB.S9S_MB_2U(SCH_1):PAGE253_I6@PURE_QUANTA.ISL99390FRZTR5935(CHIPS)':
 'PGND1': CDS_PINID='PGND1';
NODE_NAME     PU12_P0_2 7_9-20_24
 '@S9S_MB_2U_LIB.S9S_MB_2U(SCH_1):PAGE253_I6@PURE_QUANTA.ISL99390FRZTR5935(CHIPS)':
 'PGND2': CDS_PINID='PGND2';
NODE_NAME     PU12_P0_2 40
 '@S9S_MB_2U_LIB.S9S_MB_2U(SCH_1):PAGE253_I6@PURE_QUANTA.ISL99390FRZTR5935(CHIPS)':
 'PGND3': CDS_PINID='PGND3';
NODE_NAME     PC292 2
 '@S9S_MB_2U_LIB.S9S_MB_2U(SCH_1):PAGE253_I9@PURE_QUANTA.Q_CAP(CHIPS)':
 'B': CDS_PINID='B';
NODE_NAME     PC294_P0_2 2
 '@S9S_MB_2U_LIB.S9S_MB_2U(SCH_1):PAGE253_I15@PURE_QUANTA.Q_CAP(CHIPS)':
 'B': CDS_PINID='B';
NODE_NAME     PC302_P0_2 2
 '@S9S_MB_2U_LIB.S9S_MB_2U(SCH_1):PAGE253_I23@PURE_QUANTA.Q_CAP(CHIPS)':
 'B': CDS_PINID='B';
NODE_NAME     PR151 2
 '@S9S_MB_2U_LIB.S9S_MB_2U(SCH_1):PAGE253_I29@PURE_QUANTA.Q_RES(CHIPS)':
 'B': CDS_PINID='B';
NODE_NAME     PC297_P0_1 2
 '@S9S_MB_2U_LIB.S9S_MB_2U(SCH_1):PAGE253_I44@PURE_QUANTA.Q_CAP(CHIPS)':
 'B': CDS_PINID='B';
NODE_NAME     PC299_P0_1 2
 '@S9S_MB_2U_LIB.S9S_MB_2U(SCH_1):PAGE253_I47@PURE_QUANTA.Q_CAP(CHIPS)':
 'B': CDS_PINID='B';
NODE_NAME     PC311_P0_2 2
 '@S9S_MB_2U_LIB.S9S_MB_2U(SCH_1):PAGE253_I57@PURE_QUANTA.Q_CAP(CHIPS)':
 'B': CDS_PINID='B';
NODE_NAME     PC313_P0_2 2
 '@S9S_MB_2U_LIB.S9S_MB_2U(SCH_1):PAGE253_I58@PURE_QUANTA.Q_CAP(CHIPS)':
 'B': CDS_PINID='B';
NODE_NAME     PC2336 2
 '@S9S_MB_2U_LIB.S9S_MB_2U(SCH_1):PAGE253_I60@PURE_QUANTA.Q_CAPP(CHIPS)':
 'B': CDS_PINID='B';
NODE_NAME     PC1652 2
 '@S9S_MB_2U_LIB.S9S_MB_2U(SCH_1):PAGE253_I80@PURE_QUANTA.Q_CAP(CHIPS)':
 'B': CDS_PINID='B';
NODE_NAME     PC308_P0_1 2
 '@S9S_MB_2U_LIB.S9S_MB_2U(SCH_1):PAGE253_I83@PURE_QUANTA.Q_CAP(CHIPS)':
 'B': CDS_PINID='B';
NODE_NAME     PC312_P0_1 2
 '@S9S_MB_2U_LIB.S9S_MB_2U(SCH_1):PAGE253_I85@PURE_QUANTA.Q_CAP(CHIPS)':
 'B': CDS_PINID='B';
NODE_NAME     PC321 2
 '@S9S_MB_2U_LIB.S9S_MB_2U(SCH_1):PAGE253_I93@PURE_QUANTA.Q_CAPP(CHIPS)':
 'B': CDS_PINID='B';
NODE_NAME     PC324 2
 '@S9S_MB_2U_LIB.S9S_MB_2U(SCH_1):PAGE253_I94@PURE_QUANTA.Q_CAPP(CHIPS)':
 'B': CDS_PINID='B';
NODE_NAME     PU69_P0_1 2
 '@S9S_MB_2U_LIB.S9S_MB_2U(SCH_1):PAGE257_I25@PURE_QUANTA.ISL99390FRZTR5935(CHIPS)':
 'AGND': CDS_PINID='AGND';
NODE_NAME     PU69_P0_1 5
 '@S9S_MB_2U_LIB.S9S_MB_2U(SCH_1):PAGE257_I25@PURE_QUANTA.ISL99390FRZTR5935(CHIPS)':
 'PGND1': CDS_PINID='PGND1';
NODE_NAME     PU69_P0_1 7_9-20_24
 '@S9S_MB_2U_LIB.S9S_MB_2U(SCH_1):PAGE257_I25@PURE_QUANTA.ISL99390FRZTR5935(CHIPS)':
 'PGND2': CDS_PINID='PGND2';
NODE_NAME     PU69_P0_1 40
 '@S9S_MB_2U_LIB.S9S_MB_2U(SCH_1):PAGE257_I25@PURE_QUANTA.ISL99390FRZTR5935(CHIPS)':
 'PGND3': CDS_PINID='PGND3';
NODE_NAME     PC605_P0_2 2
 '@S9S_MB_2U_LIB.S9S_MB_2U(SCH_1):PAGE257_I28@PURE_QUANTA.Q_CAP(CHIPS)':
 'B': CDS_PINID='B';
NODE_NAME     PC611_P0_2 2
 '@S9S_MB_2U_LIB.S9S_MB_2U(SCH_1):PAGE257_I32@PURE_QUANTA.Q_CAP(CHIPS)':
 'B': CDS_PINID='B';
NODE_NAME     PC1349 1
 '@S9S_MB_2U_LIB.S9S_MB_2U(SCH_1):PAGE257_I35@PURE_QUANTA.Q_CAP(CHIPS)':
 'A': CDS_PINID='A';
NODE_NAME     PC600 2
 '@S9S_MB_2U_LIB.S9S_MB_2U(SCH_1):PAGE257_I37@PURE_QUANTA.Q_CAP(CHIPS)':
 'B': CDS_PINID='B';
NODE_NAME     PC1211_P0_1 2
 '@S9S_MB_2U_LIB.S9S_MB_2U(SCH_1):PAGE257_I42@PURE_QUANTA.Q_CAP(CHIPS)':
 'B': CDS_PINID='B';
NODE_NAME     PC721_P0_2 2
 '@S9S_MB_2U_LIB.S9S_MB_2U(SCH_1):PAGE257_I55@PURE_QUANTA.Q_CAP(CHIPS)':
 'B': CDS_PINID='B';
NODE_NAME     PR4265 2
 '@S9S_MB_2U_LIB.S9S_MB_2U(SCH_1):PAGE257_I60@PURE_QUANTA.Q_RES(CHIPS)':
 'B': CDS_PINID='B';
NODE_NAME     PC623 2
 '@S9S_MB_2U_LIB.S9S_MB_2U(SCH_1):PAGE257_I63@PURE_QUANTA.Q_CAPP(CHIPS)':
 'B': CDS_PINID='B';
NODE_NAME     PC2645 2
 '@S9S_MB_2U_LIB.S9S_MB_2U(SCH_1):PAGE257_I67@PURE_QUANTA.Q_CAPP(CHIPS)':
 'B': CDS_PINID='B';
NODE_NAME     PC720_P0_1 2
 '@S9S_MB_2U_LIB.S9S_MB_2U(SCH_1):PAGE257_I73@PURE_QUANTA.Q_CAP(CHIPS)':
 'B': CDS_PINID='B';
NODE_NAME     PC612_P0_1 2
 '@S9S_MB_2U_LIB.S9S_MB_2U(SCH_1):PAGE257_I75@PURE_QUANTA.Q_CAP(CHIPS)':
 'B': CDS_PINID='B';
NODE_NAME     PC1653 2
 '@S9S_MB_2U_LIB.S9S_MB_2U(SCH_1):PAGE257_I78@PURE_QUANTA.Q_CAP(CHIPS)':
 'B': CDS_PINID='B';
NODE_NAME     PC617_P0_1 2
 '@S9S_MB_2U_LIB.S9S_MB_2U(SCH_1):PAGE257_I81@PURE_QUANTA.Q_CAP(CHIPS)':
 'B': CDS_PINID='B';
NODE_NAME     PC1672 2
 '@S9S_MB_2U_LIB.S9S_MB_2U(SCH_1):PAGE257_I86@PURE_QUANTA.Q_CAP(CHIPS)':
 'B': CDS_PINID='B';
NODE_NAME     PC622 2
 '@S9S_MB_2U_LIB.S9S_MB_2U(SCH_1):PAGE257_I88@PURE_QUANTA.Q_CAPP(CHIPS)':
 'B': CDS_PINID='B';
NODE_NAME     PR1297 2
 '@S9S_MB_2U_LIB.S9S_MB_2U(SCH_1):PAGE258_I3@PURE_QUANTA.Q_RES(CHIPS)':
 'B': CDS_PINID='B';
NODE_NAME     PC1352 1
 '@S9S_MB_2U_LIB.S9S_MB_2U(SCH_1):PAGE258_I9@PURE_QUANTA.Q_CAP(CHIPS)':
 'A': CDS_PINID='A';
NODE_NAME     PU72_P0_4 2
 '@S9S_MB_2U_LIB.S9S_MB_2U(SCH_1):PAGE258_I10@PURE_QUANTA.ISL99390FRZTR5935(CHIPS)':
 'AGND': CDS_PINID='AGND';
NODE_NAME     PU72_P0_4 5
 '@S9S_MB_2U_LIB.S9S_MB_2U(SCH_1):PAGE258_I10@PURE_QUANTA.ISL99390FRZTR5935(CHIPS)':
 'PGND1': CDS_PINID='PGND1';
NODE_NAME     PU72_P0_4 7_9-20_24
 '@S9S_MB_2U_LIB.S9S_MB_2U(SCH_1):PAGE258_I10@PURE_QUANTA.ISL99390FRZTR5935(CHIPS)':
 'PGND2': CDS_PINID='PGND2';
NODE_NAME     PU72_P0_4 40
 '@S9S_MB_2U_LIB.S9S_MB_2U(SCH_1):PAGE258_I10@PURE_QUANTA.ISL99390FRZTR5935(CHIPS)':
 'PGND3': CDS_PINID='PGND3';
NODE_NAME     PC1172 2
 '@S9S_MB_2U_LIB.S9S_MB_2U(SCH_1):PAGE258_I13@PURE_QUANTA.Q_CAP(CHIPS)':
 'B': CDS_PINID='B';
NODE_NAME     PC1214_P0_4 2
 '@S9S_MB_2U_LIB.S9S_MB_2U(SCH_1):PAGE258_I18@PURE_QUANTA.Q_CAP(CHIPS)':
 'B': CDS_PINID='B';
NODE_NAME     PC1213_P0_3 2
 '@S9S_MB_2U_LIB.S9S_MB_2U(SCH_1):PAGE258_I28@PURE_QUANTA.Q_CAP(CHIPS)':
 'B': CDS_PINID='B';
NODE_NAME     PC1176_P0_4 2
 '@S9S_MB_2U_LIB.S9S_MB_2U(SCH_1):PAGE258_I34@PURE_QUANTA.Q_CAP(CHIPS)':
 'B': CDS_PINID='B';
NODE_NAME     PC1180_P0_4 2
 '@S9S_MB_2U_LIB.S9S_MB_2U(SCH_1):PAGE258_I35@PURE_QUANTA.Q_CAP(CHIPS)':
 'B': CDS_PINID='B';
NODE_NAME     PC1179_P0_3 2
 '@S9S_MB_2U_LIB.S9S_MB_2U(SCH_1):PAGE258_I47@PURE_QUANTA.Q_CAP(CHIPS)':
 'B': CDS_PINID='B';
NODE_NAME     PC722_P0_3 2
 '@S9S_MB_2U_LIB.S9S_MB_2U(SCH_1):PAGE258_I53@PURE_QUANTA.Q_CAP(CHIPS)':
 'B': CDS_PINID='B';
NODE_NAME     PC1183 2
 '@S9S_MB_2U_LIB.S9S_MB_2U(SCH_1):PAGE258_I64@PURE_QUANTA.Q_CAPP(CHIPS)':
 'B': CDS_PINID='B';
NODE_NAME     PC1185 2
 '@S9S_MB_2U_LIB.S9S_MB_2U(SCH_1):PAGE258_I65@PURE_QUANTA.Q_CAPP(CHIPS)':
 'B': CDS_PINID='B';
NODE_NAME     PC1187 2
 '@S9S_MB_2U_LIB.S9S_MB_2U(SCH_1):PAGE258_I69@PURE_QUANTA.Q_CAPP(CHIPS)':
 'B': CDS_PINID='B';
NODE_NAME     PC2170 2
 '@S9S_MB_2U_LIB.S9S_MB_2U(SCH_1):PAGE258_I70@PURE_QUANTA.Q_CAPP(CHIPS)':
 'B': CDS_PINID='B';
NODE_NAME     PC1187_P0_3 2
 '@S9S_MB_2U_LIB.S9S_MB_2U(SCH_1):PAGE258_I73@PURE_QUANTA.Q_CAP(CHIPS)':
 'B': CDS_PINID='B';
NODE_NAME     PC1676 2
 '@S9S_MB_2U_LIB.S9S_MB_2U(SCH_1):PAGE258_I79@PURE_QUANTA.Q_CAP(CHIPS)':
 'B': CDS_PINID='B';
NODE_NAME     PR1707 2
 '@S9S_MB_2U_LIB.S9S_MB_2U(SCH_1):PAGE261_I2@PURE_QUANTA.Q_RES(CHIPS)':
 'B': CDS_PINID='B';
NODE_NAME     PR1708 2
 '@S9S_MB_2U_LIB.S9S_MB_2U(SCH_1):PAGE261_I5@PURE_QUANTA.Q_RES(CHIPS)':
 'B': CDS_PINID='B';
NODE_NAME     PC1346 1
 '@S9S_MB_2U_LIB.S9S_MB_2U(SCH_1):PAGE261_I11@PURE_QUANTA.Q_CAP(CHIPS)':
 'A': CDS_PINID='A';
NODE_NAME     PC188 2
 '@S9S_MB_2U_LIB.S9S_MB_2U(SCH_1):PAGE261_I13@PURE_QUANTA.Q_CAP(CHIPS)':
 'B': CDS_PINID='B';
NODE_NAME     PC2946 2
 '@S9S_MB_2U_LIB.S9S_MB_2U(SCH_1):PAGE261_I16@PURE_QUANTA.Q_CAP(CHIPS)':
 'B': CDS_PINID='B';
NODE_NAME     PC187 2
 '@S9S_MB_2U_LIB.S9S_MB_2U(SCH_1):PAGE261_I24@PURE_QUANTA.Q_CAP(CHIPS)':
 'B': CDS_PINID='B';
NODE_NAME     PC199_P0_1 2
 '@S9S_MB_2U_LIB.S9S_MB_2U(SCH_1):PAGE261_I54@PURE_QUANTA.Q_CAP(CHIPS)':
 'B': CDS_PINID='B';
NODE_NAME     PC204_P0_1 2
 '@S9S_MB_2U_LIB.S9S_MB_2U(SCH_1):PAGE261_I57@PURE_QUANTA.Q_CAP(CHIPS)':
 'B': CDS_PINID='B';
NODE_NAME     PR4226 2
 '@S9S_MB_2U_LIB.S9S_MB_2U(SCH_1):PAGE261_I63@PURE_QUANTA.Q_RES(CHIPS)':
 'B': CDS_PINID='B';
NODE_NAME     PC1579 2
 '@S9S_MB_2U_LIB.S9S_MB_2U(SCH_1):PAGE261_I70@PURE_QUANTA.Q_CAPP(CHIPS)':
 'B': CDS_PINID='B';
NODE_NAME     PC1354 1
 '@S9S_MB_2U_LIB.S9S_MB_2U(SCH_1):PAGE265_I7@PURE_QUANTA.Q_CAP(CHIPS)':
 'A': CDS_PINID='A';
NODE_NAME     PU30_P1_2 2
 '@S9S_MB_2U_LIB.S9S_MB_2U(SCH_1):PAGE271_I7@PURE_QUANTA.ISL99390FRZTR5935(CHIPS)':
 'AGND': CDS_PINID='AGND';
NODE_NAME     PU30_P1_2 5
 '@S9S_MB_2U_LIB.S9S_MB_2U(SCH_1):PAGE271_I7@PURE_QUANTA.ISL99390FRZTR5935(CHIPS)':
 'PGND1': CDS_PINID='PGND1';
NODE_NAME     PU30_P1_2 7_9-20_24
 '@S9S_MB_2U_LIB.S9S_MB_2U(SCH_1):PAGE271_I7@PURE_QUANTA.ISL99390FRZTR5935(CHIPS)':
 'PGND2': CDS_PINID='PGND2';
NODE_NAME     PU30_P1_2 40
 '@S9S_MB_2U_LIB.S9S_MB_2U(SCH_1):PAGE271_I7@PURE_QUANTA.ISL99390FRZTR5935(CHIPS)':
 'PGND3': CDS_PINID='PGND3';
NODE_NAME     PC1339 1
 '@S9S_MB_2U_LIB.S9S_MB_2U(SCH_1):PAGE271_I34@PURE_QUANTA.Q_CAP(CHIPS)':
 'A': CDS_PINID='A';
NODE_NAME     PC557 2
 '@S9S_MB_2U_LIB.S9S_MB_2U(SCH_1):PAGE271_I36@PURE_QUANTA.Q_CAP(CHIPS)':
 'B': CDS_PINID='B';
NODE_NAME     PC561_P1_1 2
 '@S9S_MB_2U_LIB.S9S_MB_2U(SCH_1):PAGE271_I44@PURE_QUANTA.Q_CAP(CHIPS)':
 'B': CDS_PINID='B';
NODE_NAME     PC570_P1_2 2
 '@S9S_MB_2U_LIB.S9S_MB_2U(SCH_1):PAGE271_I53@PURE_QUANTA.Q_CAP(CHIPS)':
 'B': CDS_PINID='B';
NODE_NAME     PC583 2
 '@S9S_MB_2U_LIB.S9S_MB_2U(SCH_1):PAGE271_I64@PURE_QUANTA.Q_CAPP(CHIPS)':
 'B': CDS_PINID='B';
NODE_NAME     PC590 2
 '@S9S_MB_2U_LIB.S9S_MB_2U(SCH_1):PAGE271_I68@PURE_QUANTA.Q_CAPP(CHIPS)':
 'B': CDS_PINID='B';
NODE_NAME     PC571_P1_1 2
 '@S9S_MB_2U_LIB.S9S_MB_2U(SCH_1):PAGE271_I76@PURE_QUANTA.Q_CAP(CHIPS)':
 'B': CDS_PINID='B';
NODE_NAME     PC579 2
 '@S9S_MB_2U_LIB.S9S_MB_2U(SCH_1):PAGE271_I86@PURE_QUANTA.Q_CAPP(CHIPS)':
 'B': CDS_PINID='B';
NODE_NAME     PC585 2
 '@S9S_MB_2U_LIB.S9S_MB_2U(SCH_1):PAGE271_I92@PURE_QUANTA.Q_CAPP(CHIPS)':
 'B': CDS_PINID='B';
NODE_NAME     PC588 2
 '@S9S_MB_2U_LIB.S9S_MB_2U(SCH_1):PAGE271_I94@PURE_QUANTA.Q_CAPP(CHIPS)':
 'B': CDS_PINID='B';
NODE_NAME     PR1305 2
 '@S9S_MB_2U_LIB.S9S_MB_2U(SCH_1):PAGE276_I5@PURE_QUANTA.Q_RES(CHIPS)':
 'B': CDS_PINID='B';
NODE_NAME     PC1192 2
 '@S9S_MB_2U_LIB.S9S_MB_2U(SCH_1):PAGE276_I12@PURE_QUANTA.Q_CAP(CHIPS)':
 'B': CDS_PINID='B';
NODE_NAME     PC1370 1
 '@S9S_MB_2U_LIB.S9S_MB_2U(SCH_1):PAGE276_I13@PURE_QUANTA.Q_CAP(CHIPS)':
 'A': CDS_PINID='A';
NODE_NAME     PC1245_P1_4 2
 '@S9S_MB_2U_LIB.S9S_MB_2U(SCH_1):PAGE276_I20@PURE_QUANTA.Q_CAP(CHIPS)':
 'B': CDS_PINID='B';
NODE_NAME     PC1203_P1_4 2
 '@S9S_MB_2U_LIB.S9S_MB_2U(SCH_1):PAGE276_I47@PURE_QUANTA.Q_CAP(CHIPS)':
 'B': CDS_PINID='B';
NODE_NAME     PC1207_P1_4 2
 '@S9S_MB_2U_LIB.S9S_MB_2U(SCH_1):PAGE276_I48@PURE_QUANTA.Q_CAP(CHIPS)':
 'B': CDS_PINID='B';
NODE_NAME     PC726_P1_3 2
 '@S9S_MB_2U_LIB.S9S_MB_2U(SCH_1):PAGE276_I60@PURE_QUANTA.Q_CAP(CHIPS)':
 'B': CDS_PINID='B';
NODE_NAME     PC1658 2
 '@S9S_MB_2U_LIB.S9S_MB_2U(SCH_1):PAGE276_I62@PURE_QUANTA.Q_CAP(CHIPS)':
 'B': CDS_PINID='B';
NODE_NAME     PC2171 2
 '@S9S_MB_2U_LIB.S9S_MB_2U(SCH_1):PAGE276_I73@PURE_QUANTA.Q_CAPP(CHIPS)':
 'B': CDS_PINID='B';
NODE_NAME     PC1681 2
 '@S9S_MB_2U_LIB.S9S_MB_2U(SCH_1):PAGE276_I75@PURE_QUANTA.Q_CAP(CHIPS)':
 'B': CDS_PINID='B';
NODE_NAME     PC1683 2
 '@S9S_MB_2U_LIB.S9S_MB_2U(SCH_1):PAGE276_I78@PURE_QUANTA.Q_CAP(CHIPS)':
 'B': CDS_PINID='B';
NODE_NAME     PC1210 2
 '@S9S_MB_2U_LIB.S9S_MB_2U(SCH_1):PAGE276_I81@PURE_QUANTA.Q_CAPP(CHIPS)':
 'B': CDS_PINID='B';
NODE_NAME     PR1727 2
 '@S9S_MB_2U_LIB.S9S_MB_2U(SCH_1):PAGE279_I3@PURE_QUANTA.Q_RES(CHIPS)':
 'B': CDS_PINID='B';
NODE_NAME     PC1365 1
 '@S9S_MB_2U_LIB.S9S_MB_2U(SCH_1):PAGE279_I6@PURE_QUANTA.Q_CAP(CHIPS)':
 'A': CDS_PINID='A';
NODE_NAME     PC2949 2
 '@S9S_MB_2U_LIB.S9S_MB_2U(SCH_1):PAGE279_I13@PURE_QUANTA.Q_CAP(CHIPS)':
 'B': CDS_PINID='B';
NODE_NAME     PC1364 1
 '@S9S_MB_2U_LIB.S9S_MB_2U(SCH_1):PAGE279_I20@PURE_QUANTA.Q_CAP(CHIPS)':
 'A': CDS_PINID='A';
NODE_NAME     PC2950 2
 '@S9S_MB_2U_LIB.S9S_MB_2U(SCH_1):PAGE279_I26@PURE_QUANTA.Q_CAP(CHIPS)':
 'B': CDS_PINID='B';
NODE_NAME     PC452_P1_1 2
 '@S9S_MB_2U_LIB.S9S_MB_2U(SCH_1):PAGE279_I55@PURE_QUANTA.Q_CAP(CHIPS)':
 'B': CDS_PINID='B';
NODE_NAME     PC457_P1_1 2
 '@S9S_MB_2U_LIB.S9S_MB_2U(SCH_1):PAGE279_I65@PURE_QUANTA.Q_CAP(CHIPS)':
 'B': CDS_PINID='B';
NODE_NAME     PC1596 2
 '@S9S_MB_2U_LIB.S9S_MB_2U(SCH_1):PAGE279_I71@PURE_QUANTA.Q_CAPP(CHIPS)':
 'B': CDS_PINID='B';
NODE_NAME     PR4249 2
 '@S9S_MB_2U_LIB.S9S_MB_2U(SCH_1):PAGE280_I18@PURE_QUANTA.Q_RES(CHIPS)':
 'B': CDS_PINID='B';
NODE_NAME     PC1930 2
 '@S9S_MB_2U_LIB.S9S_MB_2U(SCH_1):PAGE280_I33@PURE_QUANTA.Q_CAPP(CHIPS)':
 'B': CDS_PINID='B';
NODE_NAME     PR4250 2
 '@S9S_MB_2U_LIB.S9S_MB_2U(SCH_1):PAGE280_I37@PURE_QUANTA.Q_RES(CHIPS)':
 'B': CDS_PINID='B';
NODE_NAME     PR369 2
 '@S9S_MB_2U_LIB.S9S_MB_2U(SCH_1):PAGE264_I7@PURE_QUANTA.Q_RES(CHIPS)':
 'B': CDS_PINID='B';
NODE_NAME     PC624 2
 '@S9S_MB_2U_LIB.S9S_MB_2U(SCH_1):PAGE264_I9@PURE_QUANTA.Q_CAP(CHIPS)':
 'B': CDS_PINID='B';
NODE_NAME     C2443 2
 '@S9S_MB_2U_LIB.S9S_MB_2U(SCH_1):PAGE264_I18@PURE_QUANTA.Q_CAP(CHIPS)':
 'B': CDS_PINID='B';
NODE_NAME     C2444 2
 '@S9S_MB_2U_LIB.S9S_MB_2U(SCH_1):PAGE264_I19@PURE_QUANTA.Q_CAP(CHIPS)':
 'B': CDS_PINID='B';
NODE_NAME     PC631 2
 '@S9S_MB_2U_LIB.S9S_MB_2U(SCH_1):PAGE264_I56@PURE_QUANTA.Q_CAP(CHIPS)':
 'B': CDS_PINID='B';
NODE_NAME     PR4231 2
 '@S9S_MB_2U_LIB.S9S_MB_2U(SCH_1):PAGE264_I69@PURE_QUANTA.Q_RES(CHIPS)':
 'B': CDS_PINID='B';
NODE_NAME     PC630 2
 '@S9S_MB_2U_LIB.S9S_MB_2U(SCH_1):PAGE264_I70@PURE_QUANTA.Q_CAP(CHIPS)':
 'B': CDS_PINID='B';
NODE_NAME     PC1196 2
 '@S9S_MB_2U_LIB.S9S_MB_2U(SCH_1):PAGE264_I71@PURE_QUANTA.Q_CAP(CHIPS)':
 'B': CDS_PINID='B';
NODE_NAME     PC632 2
 '@S9S_MB_2U_LIB.S9S_MB_2U(SCH_1):PAGE264_I73@PURE_QUANTA.Q_CAP(CHIPS)':
 'B': CDS_PINID='B';
NODE_NAME     PR4230 2
 '@S9S_MB_2U_LIB.S9S_MB_2U(SCH_1):PAGE264_I74@PURE_QUANTA.Q_RES(CHIPS)':
 'B': CDS_PINID='B';
NODE_NAME     PR171 2
 '@S9S_MB_2U_LIB.S9S_MB_2U(SCH_1):PAGE252_I8@PURE_QUANTA.Q_RES(CHIPS)':
 'B': CDS_PINID='B';
NODE_NAME     PR527 2
 '@S9S_MB_2U_LIB.S9S_MB_2U(SCH_1):PAGE252_I26@PURE_QUANTA.Q_RES(CHIPS)':
 'B': CDS_PINID='B';
NODE_NAME     PJP1 2
 '@S9S_MB_2U_LIB.S9S_MB_2U(SCH_1):PAGE252_I32@PURE_QUANTA.CONN3_210HP1030BR1(CHIPS)':
 '2': CDS_PINID='\2\';
NODE_NAME     PC329 2
 '@S9S_MB_2U_LIB.S9S_MB_2U(SCH_1):PAGE252_I53@PURE_QUANTA.Q_CAP(CHIPS)':
 'B': CDS_PINID='B';
NODE_NAME     C3269 2
 '@S9S_MB_2U_LIB.S9S_MB_2U(SCH_1):PAGE252_I57@PURE_QUANTA.Q_CAP(CHIPS)':
 'B': CDS_PINID='B';
NODE_NAME     PC336 2
 '@S9S_MB_2U_LIB.S9S_MB_2U(SCH_1):PAGE252_I70@PURE_QUANTA.Q_CAP(CHIPS)':
 'B': CDS_PINID='B';
NODE_NAME     PR400 2
 '@S9S_MB_2U_LIB.S9S_MB_2U(SCH_1):PAGE252_I72@PURE_QUANTA.Q_RES(CHIPS)':
 'B': CDS_PINID='B';
NODE_NAME     PR4218 2
 '@S9S_MB_2U_LIB.S9S_MB_2U(SCH_1):PAGE252_I73@PURE_QUANTA.Q_RES(CHIPS)':
 'B': CDS_PINID='B';
NODE_NAME     C3267 2
 '@S9S_MB_2U_LIB.S9S_MB_2U(SCH_1):PAGE252_I82@PURE_QUANTA.Q_CAP(CHIPS)':
 'B': CDS_PINID='B';
NODE_NAME     C3266 2
 '@S9S_MB_2U_LIB.S9S_MB_2U(SCH_1):PAGE252_I84@PURE_QUANTA.Q_CAP(CHIPS)':
 'B': CDS_PINID='B';
NODE_NAME     PC1173 2
 '@S9S_MB_2U_LIB.S9S_MB_2U(SCH_1):PAGE252_I87@PURE_QUANTA.Q_CAP(CHIPS)':
 'B': CDS_PINID='B';
NODE_NAME     PC334 2
 '@S9S_MB_2U_LIB.S9S_MB_2U(SCH_1):PAGE252_I88@PURE_QUANTA.Q_CAP(CHIPS)':
 'B': CDS_PINID='B';
NODE_NAME     PC337 2
 '@S9S_MB_2U_LIB.S9S_MB_2U(SCH_1):PAGE252_I89@PURE_QUANTA.Q_CAP(CHIPS)':
 'B': CDS_PINID='B';
NODE_NAME     PC100 2
 '@S9S_MB_2U_LIB.S9S_MB_2U(SCH_1):PAGE252_I116@PURE_QUANTA.Q_CAP(CHIPS)':
 'B': CDS_PINID='B';
NODE_NAME     PR451 2
 '@S9S_MB_2U_LIB.S9S_MB_2U(SCH_1):PAGE252_I121@PURE_QUANTA.Q_RES(CHIPS)':
 'B': CDS_PINID='B';
NODE_NAME     C3270 2
 '@S9S_MB_2U_LIB.S9S_MB_2U(SCH_1):PAGE252_I127@PURE_QUANTA.Q_CAP(CHIPS)':
 'B': CDS_PINID='B';
NODE_NAME     C3271 2
 '@S9S_MB_2U_LIB.S9S_MB_2U(SCH_1):PAGE252_I128@PURE_QUANTA.Q_CAP(CHIPS)':
 'B': CDS_PINID='B';
NODE_NAME     PR318 2
 '@S9S_MB_2U_LIB.S9S_MB_2U(SCH_1):PAGE270_I6@PURE_QUANTA.Q_RES(CHIPS)':
 'B': CDS_PINID='B';
NODE_NAME     PR305 2
 '@S9S_MB_2U_LIB.S9S_MB_2U(SCH_1):PAGE270_I27@PURE_QUANTA.Q_RES(CHIPS)':
 'B': CDS_PINID='B';
NODE_NAME     PU29 TH
 '@S9S_MB_2U_LIB.S9S_MB_2U(SCH_1):PAGE270_I33@PURE_QUANTA.RAA229126GNPHA0(CHIPS)':
 'TH_GND': CDS_PINID='TH_GND';
NODE_NAME     PR574 2
 '@S9S_MB_2U_LIB.S9S_MB_2U(SCH_1):PAGE270_I45@PURE_QUANTA.Q_RES(CHIPS)':
 'B': CDS_PINID='B';
NODE_NAME     PC554 2
 '@S9S_MB_2U_LIB.S9S_MB_2U(SCH_1):PAGE270_I72@PURE_QUANTA.Q_CAP(CHIPS)':
 'B': CDS_PINID='B';
NODE_NAME     PR4239 2
 '@S9S_MB_2U_LIB.S9S_MB_2U(SCH_1):PAGE270_I80@PURE_QUANTA.Q_RES(CHIPS)':
 'B': CDS_PINID='B';
NODE_NAME     PC101 2
 '@S9S_MB_2U_LIB.S9S_MB_2U(SCH_1):PAGE270_I92@PURE_QUANTA.Q_CAP(CHIPS)':
 'B': CDS_PINID='B';
NODE_NAME     PR453 2
 '@S9S_MB_2U_LIB.S9S_MB_2U(SCH_1):PAGE270_I94@PURE_QUANTA.Q_RES(CHIPS)':
 'B': CDS_PINID='B';
NODE_NAME     C2448 2
 '@S9S_MB_2U_LIB.S9S_MB_2U(SCH_1):PAGE270_I103@PURE_QUANTA.Q_CAP(CHIPS)':
 'B': CDS_PINID='B';
NODE_NAME     PC553 2
 '@S9S_MB_2U_LIB.S9S_MB_2U(SCH_1):PAGE270_I119@PURE_QUANTA.Q_CAP(CHIPS)':
 'B': CDS_PINID='B';
NODE_NAME     PR4220 2
 '@S9S_MB_2U_LIB.S9S_MB_2U(SCH_1):PAGE260_I19@PURE_QUANTA.Q_RES(CHIPS)':
 'B': CDS_PINID='B';
NODE_NAME     PC214 2
 '@S9S_MB_2U_LIB.S9S_MB_2U(SCH_1):PAGE260_I20@PURE_QUANTA.Q_CAP(CHIPS)':
 'B': CDS_PINID='B';
NODE_NAME     PR123 2
 '@S9S_MB_2U_LIB.S9S_MB_2U(SCH_1):PAGE260_I21@PURE_QUANTA.Q_RES(CHIPS)':
 'B': CDS_PINID='B';
NODE_NAME     C3276 2
 '@S9S_MB_2U_LIB.S9S_MB_2U(SCH_1):PAGE260_I22@PURE_QUANTA.Q_CAP(CHIPS)':
 'B': CDS_PINID='B';
NODE_NAME     PR520 2
 '@S9S_MB_2U_LIB.S9S_MB_2U(SCH_1):PAGE260_I38@PURE_QUANTA.Q_RES(CHIPS)':
 'B': CDS_PINID='B';
NODE_NAME     PR519 2
 '@S9S_MB_2U_LIB.S9S_MB_2U(SCH_1):PAGE260_I42@PURE_QUANTA.Q_RES(CHIPS)':
 'B': CDS_PINID='B';
NODE_NAME     PC222 2
 '@S9S_MB_2U_LIB.S9S_MB_2U(SCH_1):PAGE260_I69@PURE_QUANTA.Q_CAP(CHIPS)':
 'B': CDS_PINID='B';
NODE_NAME     PR435 2
 '@S9S_MB_2U_LIB.S9S_MB_2U(SCH_1):PAGE260_I71@PURE_QUANTA.Q_RES(CHIPS)':
 'B': CDS_PINID='B';
NODE_NAME     PC1271 2
 '@S9S_MB_2U_LIB.S9S_MB_2U(SCH_1):PAGE260_I73@PURE_QUANTA.Q_CAP(CHIPS)':
 'B': CDS_PINID='B';
NODE_NAME     PR4225 2
 '@S9S_MB_2U_LIB.S9S_MB_2U(SCH_1):PAGE260_I76@PURE_QUANTA.Q_RES(CHIPS)':
 'B': CDS_PINID='B';
NODE_NAME     PR4221 2
 '@S9S_MB_2U_LIB.S9S_MB_2U(SCH_1):PAGE260_I87@PURE_QUANTA.Q_RES(CHIPS)':
 'B': CDS_PINID='B';
NODE_NAME     PC1372 2
 '@S9S_MB_2U_LIB.S9S_MB_2U(SCH_1):PAGE260_I95@PURE_QUANTA.Q_CAP(CHIPS)':
 'B': CDS_PINID='B';
NODE_NAME     PC223 2
 '@S9S_MB_2U_LIB.S9S_MB_2U(SCH_1):PAGE260_I98@PURE_QUANTA.Q_CAP(CHIPS)':
 'B': CDS_PINID='B';
NODE_NAME     PC225 2
 '@S9S_MB_2U_LIB.S9S_MB_2U(SCH_1):PAGE260_I99@PURE_QUANTA.Q_CAP(CHIPS)':
 'B': CDS_PINID='B';
NODE_NAME     PR436 2
 '@S9S_MB_2U_LIB.S9S_MB_2U(SCH_1):PAGE260_I106@PURE_QUANTA.Q_RES(CHIPS)':
 'B': CDS_PINID='B';
NODE_NAME     U324 S
 '@S9S_MB_2U_LIB.S9S_MB_2U(SCH_1):PAGE246_I67@PURE_QUANTA.MOSFET_NCH_GDS_ESD_PROTECTED(CHIPS)':
 'S': CDS_PINID='S';
NODE_NAME     R4622 2
 '@S9S_MB_2U_LIB.S9S_MB_2U(SCH_1):PAGE208_I66@PURE_QUANTA.Q_RES(CHIPS)':
 'B': CDS_PINID='B';
NODE_NAME     PR358 1
 '@S9S_MB_2U_LIB.S9S_MB_2U(SCH_1):PAGE264_I95@PURE_QUANTA.Q_RES(CHIPS)':
 'A': CDS_PINID='A';
NODE_NAME     PR259 2
 '@S9S_MB_2U_LIB.S9S_MB_2U(SCH_1):PAGE278_I110@PURE_QUANTA.Q_RES(CHIPS)':
 'B': CDS_PINID='B';
NODE_NAME     PR106 2
 '@S9S_MB_2U_LIB.S9S_MB_2U(SCH_1):PAGE260_I109@PURE_QUANTA.Q_RES(CHIPS)':
 'B': CDS_PINID='B';
NODE_NAME     PR203 1
 '@S9S_MB_2U_LIB.S9S_MB_2U(SCH_1):PAGE282_I95@PURE_QUANTA.Q_RES(CHIPS)':
 'A': CDS_PINID='A';
NODE_NAME     U321 3
 '@S9S_MB_2U_LIB.S9S_MB_2U(SCH_1):PAGE156_I92@PURE_QUANTA.74LVC1G66GV(CHIPS)':
 'GND': CDS_PINID='GND';
NODE_NAME     U320 3
 '@S9S_MB_2U_LIB.S9S_MB_2U(SCH_1):PAGE152_I92@PURE_QUANTA.74LVC1G66GV(CHIPS)':
 'GND': CDS_PINID='GND';
NODE_NAME     C1226 2
 '@S9S_MB_2U_LIB.S9S_MB_2U(SCH_1):PAGE246_I68@PURE_QUANTA.Q_CAP(CHIPS)':
 'B': CDS_PINID='B';
NODE_NAME     Q37 1
 '@S9S_MB_2U_LIB.S9S_MB_2U(SCH_1):PAGE246_I69@PURE_QUANTA.MOSFET_NCH_DUAL(CHIPS)':
 'S1': CDS_PINID='S1';
NODE_NAME     Q15 1
 '@S9S_MB_2U_LIB.S9S_MB_2U(SCH_1):PAGE223_I104@PURE_QUANTA.MOSFET_NCH_DUAL(CHIPS)':
 'S1': CDS_PINID='S1';
NODE_NAME     Q16 1
 '@S9S_MB_2U_LIB.S9S_MB_2U(SCH_1):PAGE223_I106@PURE_QUANTA.MOSFET_NCH_DUAL(CHIPS)':
 'S1': CDS_PINID='S1';
NODE_NAME     Q37 4
 '@S9S_MB_2U_LIB.S9S_MB_2U(SCH_1):PAGE246_I76@PURE_QUANTA.MOSFET_NCH_DUAL(CHIPS)':
 'S2': CDS_PINID='S2';
NODE_NAME     Q15 4
 '@S9S_MB_2U_LIB.S9S_MB_2U(SCH_1):PAGE223_I108@PURE_QUANTA.MOSFET_NCH_DUAL(CHIPS)':
 'S2': CDS_PINID='S2';
NODE_NAME     Q16 4
 '@S9S_MB_2U_LIB.S9S_MB_2U(SCH_1):PAGE223_I109@PURE_QUANTA.MOSFET_NCH_DUAL(CHIPS)':
 'S2': CDS_PINID='S2';
NODE_NAME     Q95 1
 '@S9S_MB_2U_LIB.S9S_MB_2U(SCH_1):PAGE182_I342@PURE_QUANTA.MOSFET_NCH_DUAL(CHIPS)':
 'S1': CDS_PINID='S1';
NODE_NAME     PR1327 2
 '@S9S_MB_2U_LIB.S9S_MB_2U(SCH_1):PAGE248_I6@PURE_QUANTA.Q_RES(CHIPS)':
 'B': CDS_PINID='B';
NODE_NAME     PU73 2
 '@S9S_MB_2U_LIB.S9S_MB_2U(SCH_1):PAGE248_I11@PURE_QUANTA.RS53319LR(CHIPS)':
 'AGND': CDS_PINID='AGND';
NODE_NAME     PU73 11_18
 '@S9S_MB_2U_LIB.S9S_MB_2U(SCH_1):PAGE248_I11@PURE_QUANTA.RS53319LR(CHIPS)':
 'PGND': CDS_PINID='PGND';
NODE_NAME     PC1650 2
 '@S9S_MB_2U_LIB.S9S_MB_2U(SCH_1):PAGE248_I18@PURE_QUANTA.Q_CAP(CHIPS)':
 'B': CDS_PINID='B';
NODE_NAME     PC1217 2
 '@S9S_MB_2U_LIB.S9S_MB_2U(SCH_1):PAGE248_I28@PURE_QUANTA.Q_CAP(CHIPS)':
 'B': CDS_PINID='B';
NODE_NAME     PC1229 2
 '@S9S_MB_2U_LIB.S9S_MB_2U(SCH_1):PAGE248_I47@PURE_QUANTA.Q_CAPP(CHIPS)':
 'B': CDS_PINID='B';
NODE_NAME     PC831 2
 '@S9S_MB_2U_LIB.S9S_MB_2U(SCH_1):PAGE267_I7@PURE_QUANTA.Q_CAP(CHIPS)':
 'B': CDS_PINID='B';
NODE_NAME     PC2001 2
 '@S9S_MB_2U_LIB.S9S_MB_2U(SCH_1):PAGE267_I23@PURE_QUANTA.Q_CAP(CHIPS)':
 'B': CDS_PINID='B';
NODE_NAME     PC1256 2
 '@S9S_MB_2U_LIB.S9S_MB_2U(SCH_1):PAGE267_I43@PURE_QUANTA.Q_CAP(CHIPS)':
 'B': CDS_PINID='B';
NODE_NAME     PC1420 2
 '@S9S_MB_2U_LIB.S9S_MB_2U(SCH_1):PAGE268_I39@PURE_QUANTA.Q_CAP(CHIPS)':
 'B': CDS_PINID='B';
NODE_NAME     PR1339 2
 '@S9S_MB_2U_LIB.S9S_MB_2U(SCH_1):PAGE285_I10@PURE_QUANTA.Q_RES(CHIPS)':
 'B': CDS_PINID='B';
NODE_NAME     PC1261 2
 '@S9S_MB_2U_LIB.S9S_MB_2U(SCH_1):PAGE285_I16@PURE_QUANTA.Q_CAP(CHIPS)':
 'B': CDS_PINID='B';
NODE_NAME     PC1269 2
 '@S9S_MB_2U_LIB.S9S_MB_2U(SCH_1):PAGE285_I41@PURE_QUANTA.Q_CAP(CHIPS)':
 'B': CDS_PINID='B';
NODE_NAME     C2036 2
 '@S9S_MB_2U_LIB.S9S_MB_2U(SCH_1):PAGE197_I393@PURE_QUANTA.Q_CAP(CHIPS)':
 'B': CDS_PINID='B';
NODE_NAME     C2037 2
 '@S9S_MB_2U_LIB.S9S_MB_2U(SCH_1):PAGE197_I394@PURE_QUANTA.Q_CAP(CHIPS)':
 'B': CDS_PINID='B';
NODE_NAME     C2363 2
 '@S9S_MB_2U_LIB.S9S_MB_2U(SCH_1):PAGE240_I15@PURE_QUANTA.Q_CAP(CHIPS)':
 'B': CDS_PINID='B';
NODE_NAME     R4688 1
 '@S9S_MB_2U_LIB.S9S_MB_2U(SCH_1):PAGE240_I18@PURE_QUANTA.Q_RES(CHIPS)':
 'A': CDS_PINID='A';
NODE_NAME     R4687 1
 '@S9S_MB_2U_LIB.S9S_MB_2U(SCH_1):PAGE240_I19@PURE_QUANTA.Q_RES(CHIPS)':
 'A': CDS_PINID='A';
NODE_NAME     U102 1
 '@S9S_MB_2U_LIB.S9S_MB_2U(SCH_1):PAGE240_I29@PURE_QUANTA.INA183A1IDBVR(CHIPS)':
 'GND0': CDS_PINID='GND0';
NODE_NAME     U102 2
 '@S9S_MB_2U_LIB.S9S_MB_2U(SCH_1):PAGE240_I29@PURE_QUANTA.INA183A1IDBVR(CHIPS)':
 'GND1': CDS_PINID='GND1';
NODE_NAME     C2364 2
 '@S9S_MB_2U_LIB.S9S_MB_2U(SCH_1):PAGE240_I33@PURE_QUANTA.Q_CAP(CHIPS)':
 'B': CDS_PINID='B';
NODE_NAME     R2585 2
 '@S9S_MB_2U_LIB.S9S_MB_2U(SCH_1):PAGE303_I7@PURE_QUANTA.Q_RES(CHIPS)':
 'B': CDS_PINID='B';
NODE_NAME     PD15 A
 '@S9S_MB_2U_LIB.S9S_MB_2U(SCH_1):PAGE328_I51@PURE_QUANTA.ZENER_AC(CHIPS)':
 'A': CDS_PINID='A';
NODE_NAME     PD16 A
 '@S9S_MB_2U_LIB.S9S_MB_2U(SCH_1):PAGE328_I53@PURE_QUANTA.ZENER_AC(CHIPS)':
 'A': CDS_PINID='A';
NODE_NAME     PD17 1
 '@S9S_MB_2U_LIB.S9S_MB_2U(SCH_1):PAGE328_I72@PURE_QUANTA.SS15P3SM386A(CHIPS)':
 'ANODE_1': CDS_PINID='ANODE_1';
NODE_NAME     PD17 2
 '@S9S_MB_2U_LIB.S9S_MB_2U(SCH_1):PAGE328_I72@PURE_QUANTA.SS15P3SM386A(CHIPS)':
 'ANODE_2': CDS_PINID='ANODE_2';
NODE_NAME     C2458 2
 '@S9S_MB_2U_LIB.S9S_MB_2U(SCH_1):PAGE327_I8@PURE_QUANTA.Q_CAP(CHIPS)':
 'B': CDS_PINID='B';
NODE_NAME     U345 5
 '@S9S_MB_2U_LIB.S9S_MB_2U(SCH_1):PAGE327_I10@PURE_QUANTA.NCT7718W(CHIPS)':
 'GND': CDS_PINID='GND';
NODE_NAME     PJ42 11
 '@S9S_MB_2U_LIB.S9S_MB_2U(SCH_1):PAGE327_I34@PURE_QUANTA.SCONN21_9193031121LF(CHIPS)':
 '11': CDS_PINID='\11\';
NODE_NAME     PJ42 21
 '@S9S_MB_2U_LIB.S9S_MB_2U(SCH_1):PAGE327_I34@PURE_QUANTA.SCONN21_9193031121LF(CHIPS)':
 '21': CDS_PINID='\21\';
NODE_NAME     PJ42 G1
 '@S9S_MB_2U_LIB.S9S_MB_2U(SCH_1):PAGE327_I34@PURE_QUANTA.SCONN21_9193031121LF(CHIPS)':
 'G1': CDS_PINID='G1';
NODE_NAME     PJ42 G2
 '@S9S_MB_2U_LIB.S9S_MB_2U(SCH_1):PAGE327_I34@PURE_QUANTA.SCONN21_9193031121LF(CHIPS)':
 'G2': CDS_PINID='G2';
NODE_NAME     PC1789 2
 '@S9S_MB_2U_LIB.S9S_MB_2U(SCH_1):PAGE327_I38@PURE_QUANTA.Q_CAP(CHIPS)':
 'B': CDS_PINID='B';
NODE_NAME     R2238 2
 '@S9S_MB_2U_LIB.S9S_MB_2U(SCH_1):PAGE326_I2@PURE_QUANTA.Q_RES(CHIPS)':
 'B': CDS_PINID='B';
NODE_NAME     U205 2
 '@S9S_MB_2U_LIB.S9S_MB_2U(SCH_1):PAGE326_I5@PURE_QUANTA.TPS3700DDCR(CHIPS)':
 'GND': CDS_PINID='GND';
NODE_NAME     R4668 2
 '@S9S_MB_2U_LIB.S9S_MB_2U(SCH_1):PAGE326_I13@PURE_QUANTA.Q_RES(CHIPS)':
 'B': CDS_PINID='B';
NODE_NAME     R2222 2
 '@S9S_MB_2U_LIB.S9S_MB_2U(SCH_1):PAGE326_I17@PURE_QUANTA.Q_RES(CHIPS)':
 'B': CDS_PINID='B';
NODE_NAME     R4670 2
 '@S9S_MB_2U_LIB.S9S_MB_2U(SCH_1):PAGE326_I24@PURE_QUANTA.Q_RES(CHIPS)':
 'B': CDS_PINID='B';
NODE_NAME     U369 2
 '@S9S_MB_2U_LIB.S9S_MB_2U(SCH_1):PAGE326_I30@PURE_QUANTA.TPS3700DDCR(CHIPS)':
 'GND': CDS_PINID='GND';
NODE_NAME     U325 S
 '@S9S_MB_2U_LIB.S9S_MB_2U(SCH_1):PAGE326_I38@PURE_QUANTA.MOSFET_N(CHIPS)':
 'SOURCE': CDS_PINID='SOURCE';
NODE_NAME     R4673 2
 '@S9S_MB_2U_LIB.S9S_MB_2U(SCH_1):PAGE326_I44@PURE_QUANTA.Q_RES(CHIPS)':
 'B': CDS_PINID='B';
NODE_NAME     U329 S
 '@S9S_MB_2U_LIB.S9S_MB_2U(SCH_1):PAGE326_I46@PURE_QUANTA.MOSFET_NCH_GDS_ESD_PROTECTED(CHIPS)':
 'S': CDS_PINID='S';
NODE_NAME     R3268 2
 '@S9S_MB_2U_LIB.S9S_MB_2U(SCH_1):PAGE136_I2@PURE_QUANTA.Q_RES(CHIPS)':
 'B': CDS_PINID='B';
NODE_NAME     R3272 2
 '@S9S_MB_2U_LIB.S9S_MB_2U(SCH_1):PAGE136_I4@PURE_QUANTA.Q_RES(CHIPS)':
 'B': CDS_PINID='B';
NODE_NAME     R3274 2
 '@S9S_MB_2U_LIB.S9S_MB_2U(SCH_1):PAGE136_I6@PURE_QUANTA.Q_RES(CHIPS)':
 'B': CDS_PINID='B';
NODE_NAME     R3278 2
 '@S9S_MB_2U_LIB.S9S_MB_2U(SCH_1):PAGE136_I8@PURE_QUANTA.Q_RES(CHIPS)':
 'B': CDS_PINID='B';
NODE_NAME     R3267 2
 '@S9S_MB_2U_LIB.S9S_MB_2U(SCH_1):PAGE136_I12@PURE_QUANTA.Q_RES(CHIPS)':
 'B': CDS_PINID='B';
NODE_NAME     R3270 2
 '@S9S_MB_2U_LIB.S9S_MB_2U(SCH_1):PAGE136_I14@PURE_QUANTA.Q_RES(CHIPS)':
 'B': CDS_PINID='B';
NODE_NAME     R3273 2
 '@S9S_MB_2U_LIB.S9S_MB_2U(SCH_1):PAGE136_I18@PURE_QUANTA.Q_RES(CHIPS)':
 'B': CDS_PINID='B';
NODE_NAME     R3276 2
 '@S9S_MB_2U_LIB.S9S_MB_2U(SCH_1):PAGE136_I20@PURE_QUANTA.Q_RES(CHIPS)':
 'B': CDS_PINID='B';
NODE_NAME     R3282 2
 '@S9S_MB_2U_LIB.S9S_MB_2U(SCH_1):PAGE136_I27@PURE_QUANTA.Q_RES(CHIPS)':
 'B': CDS_PINID='B';
NODE_NAME     C1863 2
 '@S9S_MB_2U_LIB.S9S_MB_2U(SCH_1):PAGE136_I49@PURE_QUANTA.Q_CAP(CHIPS)':
 'B': CDS_PINID='B';
NODE_NAME     U237 4
 '@S9S_MB_2U_LIB.S9S_MB_2U(SCH_1):PAGE136_I50@PURE_QUANTA.PI3EQX12902AZLEX(CHIPS)':
 'GND1': CDS_PINID='GND1';
NODE_NAME     U237 6
 '@S9S_MB_2U_LIB.S9S_MB_2U(SCH_1):PAGE136_I50@PURE_QUANTA.PI3EQX12902AZLEX(CHIPS)':
 'GND2': CDS_PINID='GND2';
NODE_NAME     U237 7
 '@S9S_MB_2U_LIB.S9S_MB_2U(SCH_1):PAGE136_I50@PURE_QUANTA.PI3EQX12902AZLEX(CHIPS)':
 'GND3': CDS_PINID='GND3';
NODE_NAME     U237 13
 '@S9S_MB_2U_LIB.S9S_MB_2U(SCH_1):PAGE136_I50@PURE_QUANTA.PI3EQX12902AZLEX(CHIPS)':
 'GND4': CDS_PINID='GND4';
NODE_NAME     U237 19
 '@S9S_MB_2U_LIB.S9S_MB_2U(SCH_1):PAGE136_I50@PURE_QUANTA.PI3EQX12902AZLEX(CHIPS)':
 'GND5': CDS_PINID='GND5';
NODE_NAME     U237 22
 '@S9S_MB_2U_LIB.S9S_MB_2U(SCH_1):PAGE136_I50@PURE_QUANTA.PI3EQX12902AZLEX(CHIPS)':
 'GND6': CDS_PINID='GND6';
NODE_NAME     U237 28
 '@S9S_MB_2U_LIB.S9S_MB_2U(SCH_1):PAGE136_I50@PURE_QUANTA.PI3EQX12902AZLEX(CHIPS)':
 'GND7': CDS_PINID='GND7';
NODE_NAME     U237 TH
 '@S9S_MB_2U_LIB.S9S_MB_2U(SCH_1):PAGE136_I50@PURE_QUANTA.PI3EQX12902AZLEX(CHIPS)':
 'GND_TH': CDS_PINID='GND_TH';
NODE_NAME     C1864 2
 '@S9S_MB_2U_LIB.S9S_MB_2U(SCH_1):PAGE136_I51@PURE_QUANTA.Q_CAP(CHIPS)':
 'B': CDS_PINID='B';
NODE_NAME     C1865 2
 '@S9S_MB_2U_LIB.S9S_MB_2U(SCH_1):PAGE136_I52@PURE_QUANTA.Q_CAP(CHIPS)':
 'B': CDS_PINID='B';
NODE_NAME     C1866 2
 '@S9S_MB_2U_LIB.S9S_MB_2U(SCH_1):PAGE136_I53@PURE_QUANTA.Q_CAP(CHIPS)':
 'B': CDS_PINID='B';
NODE_NAME     R3284 2
 '@S9S_MB_2U_LIB.S9S_MB_2U(SCH_1):PAGE136_I56@PURE_QUANTA.Q_RES(CHIPS)':
 'B': CDS_PINID='B';
NODE_NAME     R3285 2
 '@S9S_MB_2U_LIB.S9S_MB_2U(SCH_1):PAGE136_I61@PURE_QUANTA.Q_RES(CHIPS)':
 'B': CDS_PINID='B';
NODE_NAME     R3287 2
 '@S9S_MB_2U_LIB.S9S_MB_2U(SCH_1):PAGE136_I63@PURE_QUANTA.Q_RES(CHIPS)':
 'B': CDS_PINID='B';
NODE_NAME     R3288 2
 '@S9S_MB_2U_LIB.S9S_MB_2U(SCH_1):PAGE136_I66@PURE_QUANTA.Q_RES(CHIPS)':
 'B': CDS_PINID='B';
NODE_NAME     R3291 2
 '@S9S_MB_2U_LIB.S9S_MB_2U(SCH_1):PAGE136_I82@PURE_QUANTA.Q_RES(CHIPS)':
 'B': CDS_PINID='B';
NODE_NAME     R3265 2
 '@S9S_MB_2U_LIB.S9S_MB_2U(SCH_1):PAGE136_I84@PURE_QUANTA.Q_RES(CHIPS)':
 'B': CDS_PINID='B';
NODE_NAME     R4694 2
 '@S9S_MB_2U_LIB.S9S_MB_2U(SCH_1):PAGE159_I10@PURE_QUANTA.Q_RES(CHIPS)':
 'B': CDS_PINID='B';
NODE_NAME     R3362 2
 '@S9S_MB_2U_LIB.S9S_MB_2U(SCH_1):PAGE159_I53@PURE_QUANTA.Q_RES(CHIPS)':
 'B': CDS_PINID='B';
NODE_NAME     R3381 2
 '@S9S_MB_2U_LIB.S9S_MB_2U(SCH_1):PAGE159_I61@PURE_QUANTA.Q_RES(CHIPS)':
 'B': CDS_PINID='B';
NODE_NAME     R4657 2
 '@S9S_MB_2U_LIB.S9S_MB_2U(SCH_1):PAGE159_I65@PURE_QUANTA.Q_RES(CHIPS)':
 'B': CDS_PINID='B';
NODE_NAME     R4650 2
 '@S9S_MB_2U_LIB.S9S_MB_2U(SCH_1):PAGE159_I71@PURE_QUANTA.Q_RES(CHIPS)':
 'B': CDS_PINID='B';
NODE_NAME     R4658 2
 '@S9S_MB_2U_LIB.S9S_MB_2U(SCH_1):PAGE159_I80@PURE_QUANTA.Q_RES(CHIPS)':
 'B': CDS_PINID='B';
NODE_NAME     C2355 2
 '@S9S_MB_2U_LIB.S9S_MB_2U(SCH_1):PAGE159_I96@PURE_QUANTA.Q_CAP(CHIPS)':
 'B': CDS_PINID='B';
NODE_NAME     C2356 2
 '@S9S_MB_2U_LIB.S9S_MB_2U(SCH_1):PAGE159_I98@PURE_QUANTA.Q_CAP(CHIPS)':
 'B': CDS_PINID='B';
NODE_NAME     C2357 2
 '@S9S_MB_2U_LIB.S9S_MB_2U(SCH_1):PAGE159_I99@PURE_QUANTA.Q_CAP(CHIPS)':
 'B': CDS_PINID='B';
NODE_NAME     Q50 1
 '@S9S_MB_2U_LIB.S9S_MB_2U(SCH_1):PAGE314_I43@PURE_QUANTA.MOSFET_NCH_DUAL(CHIPS)':
 'S1': CDS_PINID='S1';
NODE_NAME     U224 3
 '@S9S_MB_2U_LIB.S9S_MB_2U(SCH_1):PAGE151_I7@PURE_QUANTA.74LVC1G126SE7(CHIPS)':
 'GND': CDS_PINID='GND';
NODE_NAME     C1840 2
 '@S9S_MB_2U_LIB.S9S_MB_2U(SCH_1):PAGE151_I8@PURE_QUANTA.Q_CAP(CHIPS)':
 'B': CDS_PINID='B';
NODE_NAME     R3232 2
 '@S9S_MB_2U_LIB.S9S_MB_2U(SCH_1):PAGE151_I13@PURE_QUANTA.Q_RES(CHIPS)':
 'B': CDS_PINID='B';
NODE_NAME     U66 3
 '@S9S_MB_2U_LIB.S9S_MB_2U(SCH_1):PAGE151_I15@PURE_QUANTA.74LVC1G126SE7(CHIPS)':
 'GND': CDS_PINID='GND';
NODE_NAME     R1289 2
 '@S9S_MB_2U_LIB.S9S_MB_2U(SCH_1):PAGE151_I21@PURE_QUANTA.Q_RES(CHIPS)':
 'B': CDS_PINID='B';
NODE_NAME     C639 2
 '@S9S_MB_2U_LIB.S9S_MB_2U(SCH_1):PAGE151_I22@PURE_QUANTA.Q_CAP(CHIPS)':
 'B': CDS_PINID='B';
NODE_NAME     U68 7
 '@S9S_MB_2U_LIB.S9S_MB_2U(SCH_1):PAGE151_I30@PURE_QUANTA.74CBTLV3126PW(CHIPS)':
 'GND': CDS_PINID='GND';
NODE_NAME     C641 2
 '@S9S_MB_2U_LIB.S9S_MB_2U(SCH_1):PAGE151_I32@PURE_QUANTA.Q_CAP(CHIPS)':
 'B': CDS_PINID='B';
NODE_NAME     U67 7
 '@S9S_MB_2U_LIB.S9S_MB_2U(SCH_1):PAGE151_I39@PURE_QUANTA.74CBTLV3126PW(CHIPS)':
 'GND': CDS_PINID='GND';
NODE_NAME     C640 2
 '@S9S_MB_2U_LIB.S9S_MB_2U(SCH_1):PAGE151_I40@PURE_QUANTA.Q_CAP(CHIPS)':
 'B': CDS_PINID='B';
NODE_NAME     R1896 2
 '@S9S_MB_2U_LIB.S9S_MB_2U(SCH_1):PAGE151_I43@PURE_QUANTA.Q_RES(CHIPS)':
 'B': CDS_PINID='B';
NODE_NAME     R1897 2
 '@S9S_MB_2U_LIB.S9S_MB_2U(SCH_1):PAGE151_I50@PURE_QUANTA.Q_RES(CHIPS)':
 'B': CDS_PINID='B';
NODE_NAME     R1898 2
 '@S9S_MB_2U_LIB.S9S_MB_2U(SCH_1):PAGE151_I52@PURE_QUANTA.Q_RES(CHIPS)':
 'B': CDS_PINID='B';
NODE_NAME     R1356 2
 '@S9S_MB_2U_LIB.S9S_MB_2U(SCH_1):PAGE151_I53@PURE_QUANTA.Q_RES(CHIPS)':
 'B': CDS_PINID='B';
NODE_NAME     R1355 2
 '@S9S_MB_2U_LIB.S9S_MB_2U(SCH_1):PAGE151_I54@PURE_QUANTA.Q_RES(CHIPS)':
 'B': CDS_PINID='B';
NODE_NAME     R1354 2
 '@S9S_MB_2U_LIB.S9S_MB_2U(SCH_1):PAGE151_I55@PURE_QUANTA.Q_RES(CHIPS)':
 'B': CDS_PINID='B';
NODE_NAME     R1352 2
 '@S9S_MB_2U_LIB.S9S_MB_2U(SCH_1):PAGE151_I71@PURE_QUANTA.Q_RES(CHIPS)':
 'B': CDS_PINID='B';
NODE_NAME     R1351 2
 '@S9S_MB_2U_LIB.S9S_MB_2U(SCH_1):PAGE151_I72@PURE_QUANTA.Q_RES(CHIPS)':
 'B': CDS_PINID='B';
NODE_NAME     R1350 2
 '@S9S_MB_2U_LIB.S9S_MB_2U(SCH_1):PAGE151_I73@PURE_QUANTA.Q_RES(CHIPS)':
 'B': CDS_PINID='B';
NODE_NAME     R3442 2
 '@S9S_MB_2U_LIB.S9S_MB_2U(SCH_1):PAGE147_I6@PURE_QUANTA.Q_RES(CHIPS)':
 'B': CDS_PINID='B';
NODE_NAME     R3441 2
 '@S9S_MB_2U_LIB.S9S_MB_2U(SCH_1):PAGE147_I7@PURE_QUANTA.Q_RES(CHIPS)':
 'B': CDS_PINID='B';
NODE_NAME     C1209 2
 '@S9S_MB_2U_LIB.S9S_MB_2U(SCH_1):PAGE209_I3@PURE_QUANTA.Q_CAP(CHIPS)':
 'B': CDS_PINID='B';
NODE_NAME     C1211 2
 '@S9S_MB_2U_LIB.S9S_MB_2U(SCH_1):PAGE209_I4@PURE_QUANTA.Q_CAP(CHIPS)':
 'B': CDS_PINID='B';
NODE_NAME     R736 2
 '@S9S_MB_2U_LIB.S9S_MB_2U(SCH_1):PAGE209_I11@PURE_QUANTA.Q_RES(CHIPS)':
 'B': CDS_PINID='B';
NODE_NAME     R1494 2
 '@S9S_MB_2U_LIB.S9S_MB_2U(SCH_1):PAGE209_I21@PURE_QUANTA.Q_RES(CHIPS)':
 'B': CDS_PINID='B';
NODE_NAME     R1312 2
 '@S9S_MB_2U_LIB.S9S_MB_2U(SCH_1):PAGE209_I22@PURE_QUANTA.Q_RES(CHIPS)':
 'B': CDS_PINID='B';
NODE_NAME     R1308 2
 '@S9S_MB_2U_LIB.S9S_MB_2U(SCH_1):PAGE209_I23@PURE_QUANTA.Q_RES(CHIPS)':
 'B': CDS_PINID='B';
NODE_NAME     R1742 2
 '@S9S_MB_2U_LIB.S9S_MB_2U(SCH_1):PAGE209_I24@PURE_QUANTA.Q_RES(CHIPS)':
 'B': CDS_PINID='B';
NODE_NAME     C1797 2
 '@S9S_MB_2U_LIB.S9S_MB_2U(SCH_1):PAGE303_I3@PURE_QUANTA.Q_CAP(CHIPS)':
 'B': CDS_PINID='B';
NODE_NAME     JP4003 3
 '@S9S_MB_2U_LIB.S9S_MB_2U(SCH_1):PAGE303_I12@PURE_QUANTA.CONN3_210HP1030BR1(CHIPS)':
 '3': CDS_PINID='\3\';
NODE_NAME     PR3002 1
 '@S9S_MB_2U_LIB.S9S_MB_2U(SCH_1):PAGE303_I54@PURE_QUANTA.Q_RES(CHIPS)':
 'A': CDS_PINID='A';
NODE_NAME     R4674 2
 '@S9S_MB_2U_LIB.S9S_MB_2U(SCH_1):PAGE209_I46@PURE_QUANTA.Q_RES(CHIPS)':
 'B': CDS_PINID='B';
NODE_NAME     C2359 2
 '@S9S_MB_2U_LIB.S9S_MB_2U(SCH_1):PAGE246_I94@PURE_QUANTA.Q_CAP(CHIPS)':
 'B': CDS_PINID='B';
NODE_NAME     Q236 4
 '@S9S_MB_2U_LIB.S9S_MB_2U(SCH_1):PAGE246_I98@PURE_QUANTA.MOSFET_NCH_DUAL(CHIPS)':
 'S2': CDS_PINID='S2';
NODE_NAME     Q236 1
 '@S9S_MB_2U_LIB.S9S_MB_2U(SCH_1):PAGE246_I99@PURE_QUANTA.MOSFET_NCH_DUAL(CHIPS)':
 'S1': CDS_PINID='S1';
NODE_NAME     U330 1
 '@S9S_MB_2U_LIB.S9S_MB_2U(SCH_1):PAGE246_I105@PURE_QUANTA.APX80929SAG7(CHIPS)':
 'GND': CDS_PINID='GND';
NODE_NAME     C2360 2
 '@S9S_MB_2U_LIB.S9S_MB_2U(SCH_1):PAGE246_I107@PURE_QUANTA.Q_CAP(CHIPS)':
 'B': CDS_PINID='B';
NODE_NAME     R4681 2
 '@S9S_MB_2U_LIB.S9S_MB_2U(SCH_1):PAGE246_I109@PURE_QUANTA.Q_RES(CHIPS)':
 'B': CDS_PINID='B';
NODE_NAME     R4682 2
 '@S9S_MB_2U_LIB.S9S_MB_2U(SCH_1):PAGE246_I112@PURE_QUANTA.Q_RES(CHIPS)':
 'B': CDS_PINID='B';
NODE_NAME     H113 2
 '@S9S_MB_2U_LIB.S9S_MB_2U(SCH_1):PAGE289_I247@PURE_QUANTA.GND_HOLE(CHIPS)':
 'GND2': CDS_PINID='GND2';
NODE_NAME     H113 3
 '@S9S_MB_2U_LIB.S9S_MB_2U(SCH_1):PAGE289_I247@PURE_QUANTA.GND_HOLE(CHIPS)':
 'GND3': CDS_PINID='GND3';
NODE_NAME     H113 4
 '@S9S_MB_2U_LIB.S9S_MB_2U(SCH_1):PAGE289_I247@PURE_QUANTA.GND_HOLE(CHIPS)':
 'GND4': CDS_PINID='GND4';
NODE_NAME     H113 5
 '@S9S_MB_2U_LIB.S9S_MB_2U(SCH_1):PAGE289_I247@PURE_QUANTA.GND_HOLE(CHIPS)':
 'GND5': CDS_PINID='GND5';
NODE_NAME     H113 6
 '@S9S_MB_2U_LIB.S9S_MB_2U(SCH_1):PAGE289_I247@PURE_QUANTA.GND_HOLE(CHIPS)':
 'GND6': CDS_PINID='GND6';
NODE_NAME     H113 7
 '@S9S_MB_2U_LIB.S9S_MB_2U(SCH_1):PAGE289_I247@PURE_QUANTA.GND_HOLE(CHIPS)':
 'GND7': CDS_PINID='GND7';
NODE_NAME     H113 8
 '@S9S_MB_2U_LIB.S9S_MB_2U(SCH_1):PAGE289_I247@PURE_QUANTA.GND_HOLE(CHIPS)':
 'GND8': CDS_PINID='GND8';
NODE_NAME     H113 9
 '@S9S_MB_2U_LIB.S9S_MB_2U(SCH_1):PAGE289_I247@PURE_QUANTA.GND_HOLE(CHIPS)':
 'GND9': CDS_PINID='GND9';
NODE_NAME     H114 2
 '@S9S_MB_2U_LIB.S9S_MB_2U(SCH_1):PAGE289_I248@PURE_QUANTA.GND_HOLE(CHIPS)':
 'GND2': CDS_PINID='GND2';
NODE_NAME     H114 3
 '@S9S_MB_2U_LIB.S9S_MB_2U(SCH_1):PAGE289_I248@PURE_QUANTA.GND_HOLE(CHIPS)':
 'GND3': CDS_PINID='GND3';
NODE_NAME     H114 4
 '@S9S_MB_2U_LIB.S9S_MB_2U(SCH_1):PAGE289_I248@PURE_QUANTA.GND_HOLE(CHIPS)':
 'GND4': CDS_PINID='GND4';
NODE_NAME     H114 5
 '@S9S_MB_2U_LIB.S9S_MB_2U(SCH_1):PAGE289_I248@PURE_QUANTA.GND_HOLE(CHIPS)':
 'GND5': CDS_PINID='GND5';
NODE_NAME     H114 6
 '@S9S_MB_2U_LIB.S9S_MB_2U(SCH_1):PAGE289_I248@PURE_QUANTA.GND_HOLE(CHIPS)':
 'GND6': CDS_PINID='GND6';
NODE_NAME     H114 7
 '@S9S_MB_2U_LIB.S9S_MB_2U(SCH_1):PAGE289_I248@PURE_QUANTA.GND_HOLE(CHIPS)':
 'GND7': CDS_PINID='GND7';
NODE_NAME     H114 8
 '@S9S_MB_2U_LIB.S9S_MB_2U(SCH_1):PAGE289_I248@PURE_QUANTA.GND_HOLE(CHIPS)':
 'GND8': CDS_PINID='GND8';
NODE_NAME     H114 9
 '@S9S_MB_2U_LIB.S9S_MB_2U(SCH_1):PAGE289_I248@PURE_QUANTA.GND_HOLE(CHIPS)':
 'GND9': CDS_PINID='GND9';
NODE_NAME     C1307 2
 '@S9S_MB_2U_LIB.S9S_MB_2U(SCH_1):PAGE268_I4@PURE_QUANTA.Q_CAP(CHIPS)':
 'B': CDS_PINID='B';
NODE_NAME     PC1273 2
 '@S9S_MB_2U_LIB.S9S_MB_2U(SCH_1):PAGE268_I15@PURE_QUANTA.Q_CAP(CHIPS)':
 'B': CDS_PINID='B';
NODE_NAME     PC1274 2
 '@S9S_MB_2U_LIB.S9S_MB_2U(SCH_1):PAGE268_I23@PURE_QUANTA.Q_CAP(CHIPS)':
 'B': CDS_PINID='B';
NODE_NAME     PR50 2
 '@S9S_MB_2U_LIB.S9S_MB_2U(SCH_1):PAGE268_I28@PURE_QUANTA.Q_RES(CHIPS)':
 'B': CDS_PINID='B';
NODE_NAME     PC1279 2
 '@S9S_MB_2U_LIB.S9S_MB_2U(SCH_1):PAGE268_I43@PURE_QUANTA.Q_CAP(CHIPS)':
 'B': CDS_PINID='B';
NODE_NAME     PR2 1
 '@S9S_MB_2U_LIB.S9S_MB_2U(SCH_1):PAGE286_I22@PURE_QUANTA.Q_RES(CHIPS)':
 'A': CDS_PINID='A';
NODE_NAME     PR2 2
 '@S9S_MB_2U_LIB.S9S_MB_2U(SCH_1):PAGE286_I22@PURE_QUANTA.Q_RES(CHIPS)':
 'B': CDS_PINID='B';
NODE_NAME     PC1286 2
 '@S9S_MB_2U_LIB.S9S_MB_2U(SCH_1):PAGE286_I38@PURE_QUANTA.Q_CAP(CHIPS)':
 'B': CDS_PINID='B';
NODE_NAME     PC2361 2
 '@S9S_MB_2U_LIB.S9S_MB_2U(SCH_1):PAGE252_I136@PURE_QUANTA.Q_CAP(CHIPS)':
 'B': CDS_PINID='B';
NODE_NAME     PC2362 2
 '@S9S_MB_2U_LIB.S9S_MB_2U(SCH_1):PAGE260_I110@PURE_QUANTA.Q_CAP(CHIPS)':
 'B': CDS_PINID='B';
NODE_NAME     PC2365 2
 '@S9S_MB_2U_LIB.S9S_MB_2U(SCH_1):PAGE264_I96@PURE_QUANTA.Q_CAP(CHIPS)':
 'B': CDS_PINID='B';
NODE_NAME     PC2366 2
 '@S9S_MB_2U_LIB.S9S_MB_2U(SCH_1):PAGE270_I128@PURE_QUANTA.Q_CAP(CHIPS)':
 'B': CDS_PINID='B';
NODE_NAME     PC2367 2
 '@S9S_MB_2U_LIB.S9S_MB_2U(SCH_1):PAGE278_I111@PURE_QUANTA.Q_CAP(CHIPS)':
 'B': CDS_PINID='B';
NODE_NAME     PC2368 2
 '@S9S_MB_2U_LIB.S9S_MB_2U(SCH_1):PAGE282_I96@PURE_QUANTA.Q_CAP(CHIPS)':
 'B': CDS_PINID='B';
NODE_NAME     R4276 2
 '@S9S_MB_2U_LIB.S9S_MB_2U(SCH_1):PAGE162_I2@PURE_QUANTA.Q_RES(CHIPS)':
 'B': CDS_PINID='B';
NODE_NAME     R4282 2
 '@S9S_MB_2U_LIB.S9S_MB_2U(SCH_1):PAGE162_I6@PURE_QUANTA.Q_RES(CHIPS)':
 'B': CDS_PINID='B';
NODE_NAME     R4636 2
 '@S9S_MB_2U_LIB.S9S_MB_2U(SCH_1):PAGE162_I23@PURE_QUANTA.Q_RES(CHIPS)':
 'B': CDS_PINID='B';
NODE_NAME     C2284 2
 '@S9S_MB_2U_LIB.S9S_MB_2U(SCH_1):PAGE162_I37@PURE_QUANTA.Q_CAP(CHIPS)':
 'B': CDS_PINID='B';
NODE_NAME     R4285 2
 '@S9S_MB_2U_LIB.S9S_MB_2U(SCH_1):PAGE162_I40@PURE_QUANTA.Q_RES(CHIPS)':
 'B': CDS_PINID='B';
NODE_NAME     U309 8
 '@S9S_MB_2U_LIB.S9S_MB_2U(SCH_1):PAGE162_I43@PURE_QUANTA.PI3EQX1002EZREX(CHIPS)':
 'GND_1': CDS_PINID='GND_1';
NODE_NAME     U309 9
 '@S9S_MB_2U_LIB.S9S_MB_2U(SCH_1):PAGE162_I43@PURE_QUANTA.PI3EQX1002EZREX(CHIPS)':
 'GND_2': CDS_PINID='GND_2';
NODE_NAME     U309 10
 '@S9S_MB_2U_LIB.S9S_MB_2U(SCH_1):PAGE162_I43@PURE_QUANTA.PI3EQX1002EZREX(CHIPS)':
 'GND_3': CDS_PINID='GND_3';
NODE_NAME     U309 20
 '@S9S_MB_2U_LIB.S9S_MB_2U(SCH_1):PAGE162_I43@PURE_QUANTA.PI3EQX1002EZREX(CHIPS)':
 'GND_4': CDS_PINID='GND_4';
NODE_NAME     U309 21
 '@S9S_MB_2U_LIB.S9S_MB_2U(SCH_1):PAGE162_I43@PURE_QUANTA.PI3EQX1002EZREX(CHIPS)':
 'GND_5': CDS_PINID='GND_5';
NODE_NAME     U309 22
 '@S9S_MB_2U_LIB.S9S_MB_2U(SCH_1):PAGE162_I43@PURE_QUANTA.PI3EQX1002EZREX(CHIPS)':
 'GND_6': CDS_PINID='GND_6';
NODE_NAME     U309 TH
 '@S9S_MB_2U_LIB.S9S_MB_2U(SCH_1):PAGE162_I43@PURE_QUANTA.PI3EQX1002EZREX(CHIPS)':
 'TH_GND': CDS_PINID='TH_GND';
NODE_NAME     C2285 2
 '@S9S_MB_2U_LIB.S9S_MB_2U(SCH_1):PAGE162_I44@PURE_QUANTA.Q_CAP(CHIPS)':
 'B': CDS_PINID='B';
NODE_NAME     C2286 2
 '@S9S_MB_2U_LIB.S9S_MB_2U(SCH_1):PAGE162_I45@PURE_QUANTA.Q_CAP(CHIPS)':
 'B': CDS_PINID='B';
NODE_NAME     R4288 2
 '@S9S_MB_2U_LIB.S9S_MB_2U(SCH_1):PAGE162_I48@PURE_QUANTA.Q_RES(CHIPS)':
 'B': CDS_PINID='B';
NODE_NAME     C2255 2
 '@S9S_MB_2U_LIB.S9S_MB_2U(SCH_1):PAGE201_I165@PURE_QUANTA.Q_CAP(CHIPS)':
 'B': CDS_PINID='B';
NODE_NAME     C2256 2
 '@S9S_MB_2U_LIB.S9S_MB_2U(SCH_1):PAGE201_I166@PURE_QUANTA.Q_CAP(CHIPS)':
 'B': CDS_PINID='B';
NODE_NAME     H129 1
 '@S9S_MB_2U_LIB.S9S_MB_2U(SCH_1):PAGE289_I249@PURE_QUANTA.HOLE(CHIPS)':
 '1': CDS_PINID='\1\';
NODE_NAME     C2029 2
 '@S9S_MB_2U_LIB.S9S_MB_2U(SCH_1):PAGE155_I210@PURE_QUANTA.Q_CAP(CHIPS)':
 'B': CDS_PINID='B';
NODE_NAME     C2030 2
 '@S9S_MB_2U_LIB.S9S_MB_2U(SCH_1):PAGE155_I211@PURE_QUANTA.Q_CAP(CHIPS)':
 'B': CDS_PINID='B';
NODE_NAME     D143 C
 '@S9S_MB_2U_LIB.S9S_MB_2U(SCH_1):PAGE241_I49@PURE_QUANTA.Q_LED(CHIPS)':
 'C': CDS_PINID='C';
NODE_NAME     D142 C
 '@S9S_MB_2U_LIB.S9S_MB_2U(SCH_1):PAGE241_I58@PURE_QUANTA.Q_LED(CHIPS)':
 'C': CDS_PINID='C';
NODE_NAME     Q150 1
 '@S9S_MB_2U_LIB.S9S_MB_2U(SCH_1):PAGE241_I69@PURE_QUANTA.MOSFET_NCH_DUAL(CHIPS)':
 'S1': CDS_PINID='S1';
NODE_NAME     Q150 4
 '@S9S_MB_2U_LIB.S9S_MB_2U(SCH_1):PAGE241_I72@PURE_QUANTA.MOSFET_NCH_DUAL(CHIPS)':
 'S2': CDS_PINID='S2';
NODE_NAME     Q34 S
 '@S9S_MB_2U_LIB.S9S_MB_2U(SCH_1):PAGE177_I123@PURE_QUANTA.MOSFET_NCH_GDS_ESD_PROTECTED(CHIPS)':
 'S': CDS_PINID='S';
NODE_NAME     Q35 S
 '@S9S_MB_2U_LIB.S9S_MB_2U(SCH_1):PAGE177_I124@PURE_QUANTA.MOSFET_NCH_GDS_ESD_PROTECTED(CHIPS)':
 'S': CDS_PINID='S';
NODE_NAME     R4712 2
 '@S9S_MB_2U_LIB.S9S_MB_2U(SCH_1):PAGE177_I125@PURE_QUANTA.Q_RES(CHIPS)':
 'B': CDS_PINID='B';
NODE_NAME     R4713 2
 '@S9S_MB_2U_LIB.S9S_MB_2U(SCH_1):PAGE177_I127@PURE_QUANTA.Q_RES(CHIPS)':
 'B': CDS_PINID='B';
NODE_NAME     C2370 2
 '@S9S_MB_2U_LIB.S9S_MB_2U(SCH_1):PAGE213_I35@PURE_QUANTA.Q_CAP(CHIPS)':
 'B': CDS_PINID='B';
NODE_NAME     U332 3
 '@S9S_MB_2U_LIB.S9S_MB_2U(SCH_1):PAGE213_I37@PURE_QUANTA.74LVC2G07DW7(CHIPS)':
 '2A': CDS_PINID='\2a\';
NODE_NAME     U332 2
 '@S9S_MB_2U_LIB.S9S_MB_2U(SCH_1):PAGE213_I37@PURE_QUANTA.74LVC2G07DW7(CHIPS)':
 'GND': CDS_PINID='GND';
NODE_NAME     C2369 2
 '@S9S_MB_2U_LIB.S9S_MB_2U(SCH_1):PAGE213_I42@PURE_QUANTA.Q_CAP(CHIPS)':
 'B': CDS_PINID='B';
NODE_NAME     C2372 2
 '@S9S_MB_2U_LIB.S9S_MB_2U(SCH_1):PAGE147_I15@PURE_QUANTA.Q_CAP(CHIPS)':
 'B': CDS_PINID='B';
NODE_NAME     Q151 4
 '@S9S_MB_2U_LIB.S9S_MB_2U(SCH_1):PAGE147_I20@PURE_QUANTA.MOSFET_NCH_DUAL(CHIPS)':
 'S2': CDS_PINID='S2';
NODE_NAME     C2373 2
 '@S9S_MB_2U_LIB.S9S_MB_2U(SCH_1):PAGE147_I22@PURE_QUANTA.Q_CAP(CHIPS)':
 'B': CDS_PINID='B';
NODE_NAME     Q152 4
 '@S9S_MB_2U_LIB.S9S_MB_2U(SCH_1):PAGE147_I26@PURE_QUANTA.MOSFET_NCH_DUAL(CHIPS)':
 'S2': CDS_PINID='S2';
NODE_NAME     Q151 1
 '@S9S_MB_2U_LIB.S9S_MB_2U(SCH_1):PAGE147_I31@PURE_QUANTA.MOSFET_NCH_DUAL(CHIPS)':
 'S1': CDS_PINID='S1';
NODE_NAME     R4724 2
 '@S9S_MB_2U_LIB.S9S_MB_2U(SCH_1):PAGE147_I34@PURE_QUANTA.Q_RES(CHIPS)':
 'B': CDS_PINID='B';
NODE_NAME     Q152 1
 '@S9S_MB_2U_LIB.S9S_MB_2U(SCH_1):PAGE147_I38@PURE_QUANTA.MOSFET_NCH_DUAL(CHIPS)':
 'S1': CDS_PINID='S1';
NODE_NAME     R4731 2
 '@S9S_MB_2U_LIB.S9S_MB_2U(SCH_1):PAGE147_I42@PURE_QUANTA.Q_RES(CHIPS)':
 'B': CDS_PINID='B';
NODE_NAME     C2374 2
 '@S9S_MB_2U_LIB.S9S_MB_2U(SCH_1):PAGE147_I47@PURE_QUANTA.Q_CAP(CHIPS)':
 'B': CDS_PINID='B';
NODE_NAME     Q153 4
 '@S9S_MB_2U_LIB.S9S_MB_2U(SCH_1):PAGE147_I51@PURE_QUANTA.MOSFET_NCH_DUAL(CHIPS)':
 'S2': CDS_PINID='S2';
NODE_NAME     Q153 1
 '@S9S_MB_2U_LIB.S9S_MB_2U(SCH_1):PAGE147_I55@PURE_QUANTA.MOSFET_NCH_DUAL(CHIPS)':
 'S1': CDS_PINID='S1';
NODE_NAME     R4738 2
 '@S9S_MB_2U_LIB.S9S_MB_2U(SCH_1):PAGE147_I60@PURE_QUANTA.Q_RES(CHIPS)':
 'B': CDS_PINID='B';
NODE_NAME     C2376 2
 '@S9S_MB_2U_LIB.S9S_MB_2U(SCH_1):PAGE154_I241@PURE_QUANTA.Q_CAP(CHIPS)':
 'B': CDS_PINID='B';
NODE_NAME     U334 3
 '@S9S_MB_2U_LIB.S9S_MB_2U(SCH_1):PAGE154_I243@PURE_QUANTA.74LVC1G08W57(CHIPS)':
 'GND': CDS_PINID='GND';
NODE_NAME     PC2142 2
 '@S9S_MB_2U_LIB.S9S_MB_2U(SCH_1):PAGE131_I113@PURE_QUANTA.Q_CAP(CHIPS)':
 'B': CDS_PINID='B';
NODE_NAME     U335 3
 '@S9S_MB_2U_LIB.S9S_MB_2U(SCH_1):PAGE132_I108@PURE_QUANTA.74LVC1G08W57(CHIPS)':
 'GND': CDS_PINID='GND';
NODE_NAME     C2377 2
 '@S9S_MB_2U_LIB.S9S_MB_2U(SCH_1):PAGE132_I110@PURE_QUANTA.Q_CAP(CHIPS)':
 'B': CDS_PINID='B';
NODE_NAME     C2378 2
 '@S9S_MB_2U_LIB.S9S_MB_2U(SCH_1):PAGE297_I327@PURE_QUANTA.Q_CAP(CHIPS)':
 'B': CDS_PINID='B';
NODE_NAME     U336 1
 '@S9S_MB_2U_LIB.S9S_MB_2U(SCH_1):PAGE297_I329@PURE_QUANTA.APX80929SAG7(CHIPS)':
 'GND': CDS_PINID='GND';
NODE_NAME     C2379 2
 '@S9S_MB_2U_LIB.S9S_MB_2U(SCH_1):PAGE329_I1@PURE_QUANTA.Q_CAP(CHIPS)':
 'B': CDS_PINID='B';
NODE_NAME     R4775 2
 '@S9S_MB_2U_LIB.S9S_MB_2U(SCH_1):PAGE329_I2@PURE_QUANTA.Q_RES(CHIPS)':
 'B': CDS_PINID='B';
NODE_NAME     U337 2
 '@S9S_MB_2U_LIB.S9S_MB_2U(SCH_1):PAGE329_I3@PURE_QUANTA.LM4040AIM3X25NOPB(CHIPS)':
 '2-': CDS_PINID='\2-\';
NODE_NAME     C2383 2
 '@S9S_MB_2U_LIB.S9S_MB_2U(SCH_1):PAGE329_I11@PURE_QUANTA.Q_CAP(CHIPS)':
 'B': CDS_PINID='B';
NODE_NAME     U339 2
 '@S9S_MB_2U_LIB.S9S_MB_2U(SCH_1):PAGE329_I12@PURE_QUANTA.AP331AWG7(CHIPS)':
 'GND': CDS_PINID='GND';
NODE_NAME     C2381 2
 '@S9S_MB_2U_LIB.S9S_MB_2U(SCH_1):PAGE329_I14@PURE_QUANTA.Q_CAP(CHIPS)':
 'B': CDS_PINID='B';
NODE_NAME     U340 2
 '@S9S_MB_2U_LIB.S9S_MB_2U(SCH_1):PAGE329_I23@PURE_QUANTA.AP331AWG7(CHIPS)':
 'GND': CDS_PINID='GND';
NODE_NAME     C2384 2
 '@S9S_MB_2U_LIB.S9S_MB_2U(SCH_1):PAGE329_I29@PURE_QUANTA.Q_CAP(CHIPS)':
 'B': CDS_PINID='B';
NODE_NAME     C2382 2
 '@S9S_MB_2U_LIB.S9S_MB_2U(SCH_1):PAGE329_I33@PURE_QUANTA.Q_CAP(CHIPS)':
 'B': CDS_PINID='B';
NODE_NAME     C2380 2
 '@S9S_MB_2U_LIB.S9S_MB_2U(SCH_1):PAGE329_I35@PURE_QUANTA.Q_CAP(CHIPS)':
 'B': CDS_PINID='B';
NODE_NAME     R4777 2
 '@S9S_MB_2U_LIB.S9S_MB_2U(SCH_1):PAGE329_I39@PURE_QUANTA.Q_RES(CHIPS)':
 'B': CDS_PINID='B';
NODE_NAME     U338 2
 '@S9S_MB_2U_LIB.S9S_MB_2U(SCH_1):PAGE329_I43@PURE_QUANTA.LM4040AIM3X25NOPB(CHIPS)':
 '2-': CDS_PINID='\2-\';
NODE_NAME     U342 2
 '@S9S_MB_2U_LIB.S9S_MB_2U(SCH_1):PAGE329_I45@PURE_QUANTA.AP331AWG7(CHIPS)':
 'GND': CDS_PINID='GND';
NODE_NAME     C2387 2
 '@S9S_MB_2U_LIB.S9S_MB_2U(SCH_1):PAGE329_I51@PURE_QUANTA.Q_CAP(CHIPS)':
 'B': CDS_PINID='B';
NODE_NAME     C2386 2
 '@S9S_MB_2U_LIB.S9S_MB_2U(SCH_1):PAGE329_I55@PURE_QUANTA.Q_CAP(CHIPS)':
 'B': CDS_PINID='B';
NODE_NAME     C2385 2
 '@S9S_MB_2U_LIB.S9S_MB_2U(SCH_1):PAGE329_I57@PURE_QUANTA.Q_CAP(CHIPS)':
 'B': CDS_PINID='B';
NODE_NAME     U341 2
 '@S9S_MB_2U_LIB.S9S_MB_2U(SCH_1):PAGE329_I63@PURE_QUANTA.LM4040AIM3X25NOPB(CHIPS)':
 '2-': CDS_PINID='\2-\';
NODE_NAME     R4791 2
 '@S9S_MB_2U_LIB.S9S_MB_2U(SCH_1):PAGE329_I68@PURE_QUANTA.Q_RES(CHIPS)':
 'B': CDS_PINID='B';
NODE_NAME     U343 2
 '@S9S_MB_2U_LIB.S9S_MB_2U(SCH_1):PAGE326_I56@PURE_QUANTA.LM4040AIM3X25NOPB(CHIPS)':
 '2-': CDS_PINID='\2-\';
NODE_NAME     C2388 2
 '@S9S_MB_2U_LIB.S9S_MB_2U(SCH_1):PAGE326_I64@PURE_QUANTA.Q_CAP(CHIPS)':
 'B': CDS_PINID='B';
NODE_NAME     U344 2
 '@S9S_MB_2U_LIB.S9S_MB_2U(SCH_1):PAGE326_I66@PURE_QUANTA.AP331AWG7(CHIPS)':
 'GND': CDS_PINID='GND';
NODE_NAME     C2390 2
 '@S9S_MB_2U_LIB.S9S_MB_2U(SCH_1):PAGE326_I71@PURE_QUANTA.Q_CAP(CHIPS)':
 'B': CDS_PINID='B';
NODE_NAME     C2389 2
 '@S9S_MB_2U_LIB.S9S_MB_2U(SCH_1):PAGE326_I76@PURE_QUANTA.Q_CAP(CHIPS)':
 'B': CDS_PINID='B';
NODE_NAME     R4796 2
 '@S9S_MB_2U_LIB.S9S_MB_2U(SCH_1):PAGE326_I77@PURE_QUANTA.Q_RES(CHIPS)':
 'B': CDS_PINID='B';
NODE_NAME     Q154 4
 '@S9S_MB_2U_LIB.S9S_MB_2U(SCH_1):PAGE147_I62@PURE_QUANTA.MOSFET_NCH_DUAL(CHIPS)':
 'S2': CDS_PINID='S2';
NODE_NAME     C2391 2
 '@S9S_MB_2U_LIB.S9S_MB_2U(SCH_1):PAGE147_I66@PURE_QUANTA.Q_CAP(CHIPS)':
 'B': CDS_PINID='B';
NODE_NAME     Q154 1
 '@S9S_MB_2U_LIB.S9S_MB_2U(SCH_1):PAGE147_I71@PURE_QUANTA.MOSFET_NCH_DUAL(CHIPS)':
 'S1': CDS_PINID='S1';
NODE_NAME     R4799 2
 '@S9S_MB_2U_LIB.S9S_MB_2U(SCH_1):PAGE147_I76@PURE_QUANTA.Q_RES(CHIPS)':
 'B': CDS_PINID='B';
NODE_NAME     C1562 2
 '@S9S_MB_2U_LIB.S9S_MB_2U(SCH_1):PAGE326_I89@PURE_QUANTA.Q_CAP(CHIPS)':
 'B': CDS_PINID='B';
NODE_NAME     C1561 2
 '@S9S_MB_2U_LIB.S9S_MB_2U(SCH_1):PAGE326_I90@PURE_QUANTA.Q_CAP(CHIPS)':
 'B': CDS_PINID='B';
NODE_NAME     C4562 2
 '@S9S_MB_2U_LIB.S9S_MB_2U(SCH_1):PAGE326_I91@PURE_QUANTA.Q_CAP(CHIPS)':
 'B': CDS_PINID='B';
NODE_NAME     C2393 2
 '@S9S_MB_2U_LIB.S9S_MB_2U(SCH_1):PAGE326_I92@PURE_QUANTA.Q_CAP(CHIPS)':
 'B': CDS_PINID='B';
NODE_NAME     C2394 2
 '@S9S_MB_2U_LIB.S9S_MB_2U(SCH_1):PAGE326_I93@PURE_QUANTA.Q_CAP(CHIPS)':
 'B': CDS_PINID='B';
NODE_NAME     C2392 2
 '@S9S_MB_2U_LIB.S9S_MB_2U(SCH_1):PAGE326_I95@PURE_QUANTA.Q_CAP(CHIPS)':
 'B': CDS_PINID='B';
NODE_NAME     R2227 2
 '@S9S_MB_2U_LIB.S9S_MB_2U(SCH_1):PAGE326_I101@PURE_QUANTA.Q_RES(CHIPS)':
 'B': CDS_PINID='B';
NODE_NAME     U206 2
 '@S9S_MB_2U_LIB.S9S_MB_2U(SCH_1):PAGE326_I102@PURE_QUANTA.LT6700CS61TRPBF(CHIPS)':
 'GND': CDS_PINID='GND';
NODE_NAME     JP10 3
 '@S9S_MB_2U_LIB.S9S_MB_2U(SCH_1):PAGE327_I51@PURE_QUANTA.CONN3_210HP1030BR1(CHIPS)':
 '3': CDS_PINID='\3\';
NODE_NAME     Q123 1
 '@S9S_MB_2U_LIB.S9S_MB_2U(SCH_1):PAGE153_I9@PURE_QUANTA.MOSFET_NCH_DUAL(CHIPS)':
 'S1': CDS_PINID='S1';
NODE_NAME     Q124 1
 '@S9S_MB_2U_LIB.S9S_MB_2U(SCH_1):PAGE153_I21@PURE_QUANTA.MOSFET_NCH_DUAL(CHIPS)':
 'S1': CDS_PINID='S1';
NODE_NAME     C592 2
 '@S9S_MB_2U_LIB.S9S_MB_2U(SCH_1):PAGE153_I30@PURE_QUANTA.Q_CAP(CHIPS)':
 'B': CDS_PINID='B';
NODE_NAME     PR3788 2
 '@S9S_MB_2U_LIB.S9S_MB_2U(SCH_1):PAGE153_I33@PURE_QUANTA.Q_RES(CHIPS)':
 'B': CDS_PINID='B';
NODE_NAME     Q124 4
 '@S9S_MB_2U_LIB.S9S_MB_2U(SCH_1):PAGE153_I36@PURE_QUANTA.MOSFET_NCH_DUAL(CHIPS)':
 'S2': CDS_PINID='S2';
NODE_NAME     PC2079 2
 '@S9S_MB_2U_LIB.S9S_MB_2U(SCH_1):PAGE153_I44@PURE_QUANTA.Q_CAP(CHIPS)':
 'B': CDS_PINID='B';
NODE_NAME     PU203 A7
 '@S9S_MB_2U_LIB.S9S_MB_2U(SCH_1):PAGE153_I51@PURE_QUANTA.MAX15090BEWIT(CHIPS)':
 'CDLY': CDS_PINID='CDLY';
NODE_NAME     PU203 B7
 '@S9S_MB_2U_LIB.S9S_MB_2U(SCH_1):PAGE153_I51@PURE_QUANTA.MAX15090BEWIT(CHIPS)':
 'EN#': CDS_PINID='\en#\';
NODE_NAME     PU203 B2
 '@S9S_MB_2U_LIB.S9S_MB_2U(SCH_1):PAGE153_I51@PURE_QUANTA.MAX15090BEWIT(CHIPS)':
 'GND_B2': CDS_PINID='GND_B2';
NODE_NAME     PU203 C1
 '@S9S_MB_2U_LIB.S9S_MB_2U(SCH_1):PAGE153_I51@PURE_QUANTA.MAX15090BEWIT(CHIPS)':
 'GND_C1': CDS_PINID='GND_C1';
NODE_NAME     PU203 C2
 '@S9S_MB_2U_LIB.S9S_MB_2U(SCH_1):PAGE153_I51@PURE_QUANTA.MAX15090BEWIT(CHIPS)':
 'GND_C2': CDS_PINID='GND_C2';
NODE_NAME     PR3780 2
 '@S9S_MB_2U_LIB.S9S_MB_2U(SCH_1):PAGE153_I60@PURE_QUANTA.Q_RES(CHIPS)':
 'B': CDS_PINID='B';
NODE_NAME     PU202 A7
 '@S9S_MB_2U_LIB.S9S_MB_2U(SCH_1):PAGE153_I61@PURE_QUANTA.MAX15090BEWIT(CHIPS)':
 'CDLY': CDS_PINID='CDLY';
NODE_NAME     PU202 B7
 '@S9S_MB_2U_LIB.S9S_MB_2U(SCH_1):PAGE153_I61@PURE_QUANTA.MAX15090BEWIT(CHIPS)':
 'EN#': CDS_PINID='\en#\';
NODE_NAME     PU202 B2
 '@S9S_MB_2U_LIB.S9S_MB_2U(SCH_1):PAGE153_I61@PURE_QUANTA.MAX15090BEWIT(CHIPS)':
 'GND_B2': CDS_PINID='GND_B2';
NODE_NAME     PU202 C1
 '@S9S_MB_2U_LIB.S9S_MB_2U(SCH_1):PAGE153_I61@PURE_QUANTA.MAX15090BEWIT(CHIPS)':
 'GND_C1': CDS_PINID='GND_C1';
NODE_NAME     PU202 C2
 '@S9S_MB_2U_LIB.S9S_MB_2U(SCH_1):PAGE153_I61@PURE_QUANTA.MAX15090BEWIT(CHIPS)':
 'GND_C2': CDS_PINID='GND_C2';
NODE_NAME     PC5328 2
 '@S9S_MB_2U_LIB.S9S_MB_2U(SCH_1):PAGE153_I66@PURE_QUANTA.Q_CAP(CHIPS)':
 'B': CDS_PINID='B';
NODE_NAME     PC4056 2
 '@S9S_MB_2U_LIB.S9S_MB_2U(SCH_1):PAGE153_I83@PURE_QUANTA.Q_CAP(CHIPS)':
 'B': CDS_PINID='B';
NODE_NAME     PD102 A
 '@S9S_MB_2U_LIB.S9S_MB_2U(SCH_1):PAGE153_I86@PURE_QUANTA.SCHOTTKY_AC(CHIPS)':
 'A': CDS_PINID='A';
NODE_NAME     PC2080 2
 '@S9S_MB_2U_LIB.S9S_MB_2U(SCH_1):PAGE153_I94@PURE_QUANTA.Q_CAP(CHIPS)':
 'B': CDS_PINID='B';
NODE_NAME     PC2091 2
 '@S9S_MB_2U_LIB.S9S_MB_2U(SCH_1):PAGE153_I111@PURE_QUANTA.Q_CAP(CHIPS)':
 'B': CDS_PINID='B';
NODE_NAME     PC2081 2
 '@S9S_MB_2U_LIB.S9S_MB_2U(SCH_1):PAGE153_I113@PURE_QUANTA.Q_CAP(CHIPS)':
 'B': CDS_PINID='B';
NODE_NAME     PC2153 2
 '@S9S_MB_2U_LIB.S9S_MB_2U(SCH_1):PAGE236_I60@PURE_QUANTA.Q_CAP(CHIPS)':
 'B': CDS_PINID='B';
NODE_NAME     PR3835 2
 '@S9S_MB_2U_LIB.S9S_MB_2U(SCH_1):PAGE236_I62@PURE_QUANTA.Q_RES(CHIPS)':
 'B': CDS_PINID='B';
NODE_NAME     PC2155 2
 '@S9S_MB_2U_LIB.S9S_MB_2U(SCH_1):PAGE236_I63@PURE_QUANTA.Q_CAP(CHIPS)':
 'B': CDS_PINID='B';
NODE_NAME     PC2154 2
 '@S9S_MB_2U_LIB.S9S_MB_2U(SCH_1):PAGE236_I68@PURE_QUANTA.Q_CAP(CHIPS)':
 'B': CDS_PINID='B';
NODE_NAME     PU204 3
 '@S9S_MB_2U_LIB.S9S_MB_2U(SCH_1):PAGE236_I70@PURE_QUANTA.RS31312R(CHIPS)':
 'ENTM': CDS_PINID='ENTM';
NODE_NAME     PU204 7
 '@S9S_MB_2U_LIB.S9S_MB_2U(SCH_1):PAGE236_I70@PURE_QUANTA.RS31312R(CHIPS)':
 'GND': CDS_PINID='GND';
NODE_NAME     PU204 2
 '@S9S_MB_2U_LIB.S9S_MB_2U(SCH_1):PAGE236_I70@PURE_QUANTA.RS31312R(CHIPS)':
 'LOADEN': CDS_PINID='LOADEN';
NODE_NAME     PR3837 2
 '@S9S_MB_2U_LIB.S9S_MB_2U(SCH_1):PAGE236_I72@PURE_QUANTA.Q_RES(CHIPS)':
 'B': CDS_PINID='B';
NODE_NAME     PC2156 2
 '@S9S_MB_2U_LIB.S9S_MB_2U(SCH_1):PAGE236_I74@PURE_QUANTA.Q_CAP(CHIPS)':
 'B': CDS_PINID='B';
NODE_NAME     PR3842 2
 '@S9S_MB_2U_LIB.S9S_MB_2U(SCH_1):PAGE236_I83@PURE_QUANTA.Q_RES(CHIPS)':
 'B': CDS_PINID='B';
NODE_NAME     PC2158 2
 '@S9S_MB_2U_LIB.S9S_MB_2U(SCH_1):PAGE236_I88@PURE_QUANTA.Q_CAP(CHIPS)':
 'B': CDS_PINID='B';
NODE_NAME     PC2160 2
 '@S9S_MB_2U_LIB.S9S_MB_2U(SCH_1):PAGE236_I91@PURE_QUANTA.Q_CAP(CHIPS)':
 'B': CDS_PINID='B';
NODE_NAME     Q118 1
 '@S9S_MB_2U_LIB.S9S_MB_2U(SCH_1):PAGE131_I7@PURE_QUANTA.MOSFET_NCH_DUAL(CHIPS)':
 'S1': CDS_PINID='S1';
NODE_NAME     C1810 2
 '@S9S_MB_2U_LIB.S9S_MB_2U(SCH_1):PAGE131_I21@PURE_QUANTA.Q_CAP(CHIPS)':
 'B': CDS_PINID='B';
NODE_NAME     PR3828 2
 '@S9S_MB_2U_LIB.S9S_MB_2U(SCH_1):PAGE131_I29@PURE_QUANTA.Q_RES(CHIPS)':
 'B': CDS_PINID='B';
NODE_NAME     R4066 2
 '@S9S_MB_2U_LIB.S9S_MB_2U(SCH_1):PAGE131_I37@PURE_QUANTA.Q_RES(CHIPS)':
 'B': CDS_PINID='B';
NODE_NAME     PD107 A
 '@S9S_MB_2U_LIB.S9S_MB_2U(SCH_1):PAGE131_I44@PURE_QUANTA.DIODE_TVS(CHIPS)':
 'A': CDS_PINID='A';
NODE_NAME     PC2139 2
 '@S9S_MB_2U_LIB.S9S_MB_2U(SCH_1):PAGE131_I46@PURE_QUANTA.Q_CAP(CHIPS)':
 'B': CDS_PINID='B';
NODE_NAME     PC2098 2
 '@S9S_MB_2U_LIB.S9S_MB_2U(SCH_1):PAGE131_I61@PURE_QUANTA.Q_CAP(CHIPS)':
 'B': CDS_PINID='B';
NODE_NAME     PC2146 1
 '@S9S_MB_2U_LIB.S9S_MB_2U(SCH_1):PAGE131_I62@PURE_QUANTA.Q_CAP(CHIPS)':
 'A': CDS_PINID='A';
NODE_NAME     PR3823 2
 '@S9S_MB_2U_LIB.S9S_MB_2U(SCH_1):PAGE131_I72@PURE_QUANTA.Q_RES(CHIPS)':
 'B': CDS_PINID='B';
NODE_NAME     PC2150 2
 '@S9S_MB_2U_LIB.S9S_MB_2U(SCH_1):PAGE131_I76@PURE_QUANTA.Q_CAP(CHIPS)':
 'B': CDS_PINID='B';
NODE_NAME     PC190 2
 '@S9S_MB_2U_LIB.S9S_MB_2U(SCH_1):PAGE131_I91@PURE_QUANTA.Q_CAP(CHIPS)':
 'B': CDS_PINID='B';
NODE_NAME     PR3824 2
 '@S9S_MB_2U_LIB.S9S_MB_2U(SCH_1):PAGE131_I95@PURE_QUANTA.Q_RES(CHIPS)':
 'B': CDS_PINID='B';
NODE_NAME     PC2152 2
 '@S9S_MB_2U_LIB.S9S_MB_2U(SCH_1):PAGE131_I98@PURE_QUANTA.Q_CAP(CHIPS)':
 'B': CDS_PINID='B';
NODE_NAME     PR3847 2
 '@S9S_MB_2U_LIB.S9S_MB_2U(SCH_1):PAGE237_I61@PURE_QUANTA.Q_RES(CHIPS)':
 'B': CDS_PINID='B';
NODE_NAME     PC2164 2
 '@S9S_MB_2U_LIB.S9S_MB_2U(SCH_1):PAGE237_I62@PURE_QUANTA.Q_CAP(CHIPS)':
 'B': CDS_PINID='B';
NODE_NAME     PC2166 2
 '@S9S_MB_2U_LIB.S9S_MB_2U(SCH_1):PAGE237_I65@PURE_QUANTA.Q_CAP(CHIPS)':
 'B': CDS_PINID='B';
NODE_NAME     PC2165 2
 '@S9S_MB_2U_LIB.S9S_MB_2U(SCH_1):PAGE237_I68@PURE_QUANTA.Q_CAP(CHIPS)':
 'B': CDS_PINID='B';
NODE_NAME     PU206 3
 '@S9S_MB_2U_LIB.S9S_MB_2U(SCH_1):PAGE237_I70@PURE_QUANTA.RS31312R(CHIPS)':
 'ENTM': CDS_PINID='ENTM';
NODE_NAME     PU206 7
 '@S9S_MB_2U_LIB.S9S_MB_2U(SCH_1):PAGE237_I70@PURE_QUANTA.RS31312R(CHIPS)':
 'GND': CDS_PINID='GND';
NODE_NAME     PU206 2
 '@S9S_MB_2U_LIB.S9S_MB_2U(SCH_1):PAGE237_I70@PURE_QUANTA.RS31312R(CHIPS)':
 'LOADEN': CDS_PINID='LOADEN';
NODE_NAME     PR3849 2
 '@S9S_MB_2U_LIB.S9S_MB_2U(SCH_1):PAGE237_I72@PURE_QUANTA.Q_RES(CHIPS)':
 'B': CDS_PINID='B';
NODE_NAME     PC2167 2
 '@S9S_MB_2U_LIB.S9S_MB_2U(SCH_1):PAGE237_I73@PURE_QUANTA.Q_CAP(CHIPS)':
 'B': CDS_PINID='B';
NODE_NAME     PR3854 2
 '@S9S_MB_2U_LIB.S9S_MB_2U(SCH_1):PAGE237_I83@PURE_QUANTA.Q_RES(CHIPS)':
 'B': CDS_PINID='B';
NODE_NAME     PC2174 2
 '@S9S_MB_2U_LIB.S9S_MB_2U(SCH_1):PAGE237_I91@PURE_QUANTA.Q_CAP(CHIPS)':
 'B': CDS_PINID='B';
NODE_NAME     PC1320 2
 '@S9S_MB_2U_LIB.S9S_MB_2U(SCH_1):PAGE237_I95@PURE_QUANTA.Q_CAP(CHIPS)':
 'B': CDS_PINID='B';
NODE_NAME     PR3949 2
 '@S9S_MB_2U_LIB.S9S_MB_2U(SCH_1):PAGE323_I53@PURE_QUANTA.Q_RES(CHIPS)':
 'B': CDS_PINID='B';
NODE_NAME     PR3954 2
 '@S9S_MB_2U_LIB.S9S_MB_2U(SCH_1):PAGE323_I58@PURE_QUANTA.Q_RES(CHIPS)':
 'B': CDS_PINID='B';
NODE_NAME     PC2205 2
 '@S9S_MB_2U_LIB.S9S_MB_2U(SCH_1):PAGE323_I69@PURE_QUANTA.Q_CAP(CHIPS)':
 'B': CDS_PINID='B';
NODE_NAME     PC2206 2
 '@S9S_MB_2U_LIB.S9S_MB_2U(SCH_1):PAGE323_I73@PURE_QUANTA.Q_CAP(CHIPS)':
 'B': CDS_PINID='B';
NODE_NAME     Q126 1
 '@S9S_MB_2U_LIB.S9S_MB_2U(SCH_1):PAGE324_I3@PURE_QUANTA.MOSFET_NCH_DUAL(CHIPS)':
 'S1': CDS_PINID='S1';
NODE_NAME     Q127 1
 '@S9S_MB_2U_LIB.S9S_MB_2U(SCH_1):PAGE324_I10@PURE_QUANTA.MOSFET_NCH_DUAL(CHIPS)':
 'S1': CDS_PINID='S1';
NODE_NAME     Q127 4
 '@S9S_MB_2U_LIB.S9S_MB_2U(SCH_1):PAGE324_I24@PURE_QUANTA.MOSFET_NCH_DUAL(CHIPS)':
 'S2': CDS_PINID='S2';
NODE_NAME     PU295 A7
 '@S9S_MB_2U_LIB.S9S_MB_2U(SCH_1):PAGE324_I35@PURE_QUANTA.MAX15090BEWIT(CHIPS)':
 'CDLY': CDS_PINID='CDLY';
NODE_NAME     PU295 B7
 '@S9S_MB_2U_LIB.S9S_MB_2U(SCH_1):PAGE324_I35@PURE_QUANTA.MAX15090BEWIT(CHIPS)':
 'EN#': CDS_PINID='\en#\';
NODE_NAME     PU295 B2
 '@S9S_MB_2U_LIB.S9S_MB_2U(SCH_1):PAGE324_I35@PURE_QUANTA.MAX15090BEWIT(CHIPS)':
 'GND_B2': CDS_PINID='GND_B2';
NODE_NAME     PU295 C1
 '@S9S_MB_2U_LIB.S9S_MB_2U(SCH_1):PAGE324_I35@PURE_QUANTA.MAX15090BEWIT(CHIPS)':
 'GND_C1': CDS_PINID='GND_C1';
NODE_NAME     PU295 C2
 '@S9S_MB_2U_LIB.S9S_MB_2U(SCH_1):PAGE324_I35@PURE_QUANTA.MAX15090BEWIT(CHIPS)':
 'GND_C2': CDS_PINID='GND_C2';
NODE_NAME     PC2212 1
 '@S9S_MB_2U_LIB.S9S_MB_2U(SCH_1):PAGE324_I38@PURE_QUANTA.Q_CAP(CHIPS)':
 'A': CDS_PINID='A';
NODE_NAME     PC2218 2
 '@S9S_MB_2U_LIB.S9S_MB_2U(SCH_1):PAGE324_I52@PURE_QUANTA.Q_CAP(CHIPS)':
 'B': CDS_PINID='B';
NODE_NAME     PC2220 2
 '@S9S_MB_2U_LIB.S9S_MB_2U(SCH_1):PAGE324_I53@PURE_QUANTA.Q_CAP(CHIPS)':
 'B': CDS_PINID='B';
NODE_NAME     PC2211 1
 '@S9S_MB_2U_LIB.S9S_MB_2U(SCH_1):PAGE324_I57@PURE_QUANTA.Q_CAP(CHIPS)':
 'A': CDS_PINID='A';
NODE_NAME     PR3968 2
 '@S9S_MB_2U_LIB.S9S_MB_2U(SCH_1):PAGE324_I59@PURE_QUANTA.Q_RES(CHIPS)':
 'B': CDS_PINID='B';
NODE_NAME     PR3970 2
 '@S9S_MB_2U_LIB.S9S_MB_2U(SCH_1):PAGE324_I64@PURE_QUANTA.Q_RES(CHIPS)':
 'B': CDS_PINID='B';
NODE_NAME     PC2280 2
 '@S9S_MB_2U_LIB.S9S_MB_2U(SCH_1):PAGE324_I79@PURE_QUANTA.Q_CAP(CHIPS)':
 'B': CDS_PINID='B';
NODE_NAME     PD114 A
 '@S9S_MB_2U_LIB.S9S_MB_2U(SCH_1):PAGE324_I84@PURE_QUANTA.DIODE_TVS(CHIPS)':
 'A': CDS_PINID='A';
NODE_NAME     C2541 2
 '@S9S_MB_2U_LIB.S9S_MB_2U(SCH_1):PAGE245_I73@PURE_QUANTA.Q_CAP(CHIPS)':
 'B': CDS_PINID='B';
NODE_NAME     R3118 2
 '@S9S_MB_2U_LIB.S9S_MB_2U(SCH_1):PAGE245_I76@PURE_QUANTA.Q_RES(CHIPS)':
 'B': CDS_PINID='B';
NODE_NAME     PR832 2
 '@S9S_MB_2U_LIB.S9S_MB_2U(SCH_1):PAGE245_I84@PURE_QUANTA.Q_RES(CHIPS)':
 'B': CDS_PINID='B';
NODE_NAME     PC581 2
 '@S9S_MB_2U_LIB.S9S_MB_2U(SCH_1):PAGE245_I86@PURE_QUANTA.Q_CAP(CHIPS)':
 'B': CDS_PINID='B';
NODE_NAME     PR833 2
 '@S9S_MB_2U_LIB.S9S_MB_2U(SCH_1):PAGE245_I89@PURE_QUANTA.Q_RES(CHIPS)':
 'B': CDS_PINID='B';
NODE_NAME     PR834 2
 '@S9S_MB_2U_LIB.S9S_MB_2U(SCH_1):PAGE245_I91@PURE_QUANTA.Q_RES(CHIPS)':
 'B': CDS_PINID='B';
NODE_NAME     PC591 2
 '@S9S_MB_2U_LIB.S9S_MB_2U(SCH_1):PAGE245_I93@PURE_QUANTA.Q_CAP(CHIPS)':
 'B': CDS_PINID='B';
NODE_NAME     PU9 32
 '@S9S_MB_2U_LIB.S9S_MB_2U(SCH_1):PAGE245_I95@PURE_QUANTA.IR3889MTRPBF(CHIPS)':
 'AGND': CDS_PINID='AGND';
NODE_NAME     PU9 7_10-19
 '@S9S_MB_2U_LIB.S9S_MB_2U(SCH_1):PAGE245_I95@PURE_QUANTA.IR3889MTRPBF(CHIPS)':
 'PGND': CDS_PINID='PGND';
NODE_NAME     PU9 31
 '@S9S_MB_2U_LIB.S9S_MB_2U(SCH_1):PAGE245_I95@PURE_QUANTA.IR3889MTRPBF(CHIPS)':
 'VSENM': CDS_PINID='VSENM';
NODE_NAME     PC1649 2
 '@S9S_MB_2U_LIB.S9S_MB_2U(SCH_1):PAGE245_I97@PURE_QUANTA.Q_CAP(CHIPS)':
 'B': CDS_PINID='B';
NODE_NAME     PC2260 2
 '@S9S_MB_2U_LIB.S9S_MB_2U(SCH_1):PAGE245_I100@PURE_QUANTA.Q_CAP(CHIPS)':
 'B': CDS_PINID='B';
NODE_NAME     PC2261 2
 '@S9S_MB_2U_LIB.S9S_MB_2U(SCH_1):PAGE245_I101@PURE_QUANTA.Q_CAP(CHIPS)':
 'B': CDS_PINID='B';
NODE_NAME     PC3 2
 '@S9S_MB_2U_LIB.S9S_MB_2U(SCH_1):PAGE245_I103@PURE_QUANTA.Q_CAPP(CHIPS)':
 'B': CDS_PINID='B';
NODE_NAME     PC566 2
 '@S9S_MB_2U_LIB.S9S_MB_2U(SCH_1):PAGE245_I104@PURE_QUANTA.Q_CAPP(CHIPS)':
 'B': CDS_PINID='B';
NODE_NAME     PC2262 2
 '@S9S_MB_2U_LIB.S9S_MB_2U(SCH_1):PAGE245_I105@PURE_QUANTA.Q_CAP(CHIPS)':
 'B': CDS_PINID='B';
NODE_NAME     PC567 2
 '@S9S_MB_2U_LIB.S9S_MB_2U(SCH_1):PAGE245_I106@PURE_QUANTA.Q_CAP(CHIPS)':
 'B': CDS_PINID='B';
NODE_NAME     PC2263 2
 '@S9S_MB_2U_LIB.S9S_MB_2U(SCH_1):PAGE245_I107@PURE_QUANTA.Q_CAP(CHIPS)':
 'B': CDS_PINID='B';
NODE_NAME     PC2342 2
 '@S9S_MB_2U_LIB.S9S_MB_2U(SCH_1):PAGE245_I108@PURE_QUANTA.Q_CAP(CHIPS)':
 'B': CDS_PINID='B';
NODE_NAME     PC570 2
 '@S9S_MB_2U_LIB.S9S_MB_2U(SCH_1):PAGE245_I109@PURE_QUANTA.Q_CAP(CHIPS)':
 'B': CDS_PINID='B';
NODE_NAME     PC571 2
 '@S9S_MB_2U_LIB.S9S_MB_2U(SCH_1):PAGE245_I110@PURE_QUANTA.Q_CAP(CHIPS)':
 'B': CDS_PINID='B';
NODE_NAME     PC2343 2
 '@S9S_MB_2U_LIB.S9S_MB_2U(SCH_1):PAGE245_I111@PURE_QUANTA.Q_CAP(CHIPS)':
 'B': CDS_PINID='B';
NODE_NAME     PC2344 2
 '@S9S_MB_2U_LIB.S9S_MB_2U(SCH_1):PAGE245_I112@PURE_QUANTA.Q_CAP(CHIPS)':
 'B': CDS_PINID='B';
NODE_NAME     PC576 2
 '@S9S_MB_2U_LIB.S9S_MB_2U(SCH_1):PAGE245_I113@PURE_QUANTA.Q_CAP(CHIPS)':
 'B': CDS_PINID='B';
NODE_NAME     PC71 2
 '@S9S_MB_2U_LIB.S9S_MB_2U(SCH_1):PAGE245_I114@PURE_QUANTA.Q_CAP(CHIPS)':
 'B': CDS_PINID='B';
NODE_NAME     PC577 2
 '@S9S_MB_2U_LIB.S9S_MB_2U(SCH_1):PAGE245_I115@PURE_QUANTA.Q_CAP(CHIPS)':
 'B': CDS_PINID='B';
NODE_NAME     PC8 2
 '@S9S_MB_2U_LIB.S9S_MB_2U(SCH_1):PAGE245_I118@PURE_QUANTA.Q_CAP(CHIPS)':
 'B': CDS_PINID='B';
NODE_NAME     PR830 2
 '@S9S_MB_2U_LIB.S9S_MB_2U(SCH_1):PAGE245_I125@PURE_QUANTA.Q_RES(CHIPS)':
 'B': CDS_PINID='B';
NODE_NAME     PC1866 2
 '@S9S_MB_2U_LIB.S9S_MB_2U(SCH_1):PAGE245_I131@PURE_QUANTA.Q_CAPP(CHIPS)':
 'B': CDS_PINID='B';
NODE_NAME     PC1867 2
 '@S9S_MB_2U_LIB.S9S_MB_2U(SCH_1):PAGE245_I132@PURE_QUANTA.Q_CAPP(CHIPS)':
 'B': CDS_PINID='B';
NODE_NAME     PC1868 2
 '@S9S_MB_2U_LIB.S9S_MB_2U(SCH_1):PAGE245_I133@PURE_QUANTA.Q_CAP(CHIPS)':
 'B': CDS_PINID='B';
NODE_NAME     PC1599 2
 '@S9S_MB_2U_LIB.S9S_MB_2U(SCH_1):PAGE245_I134@PURE_QUANTA.Q_CAP(CHIPS)':
 'B': CDS_PINID='B';
NODE_NAME     PC1600 2
 '@S9S_MB_2U_LIB.S9S_MB_2U(SCH_1):PAGE245_I136@PURE_QUANTA.Q_CAP(CHIPS)':
 'B': CDS_PINID='B';
NODE_NAME     PC1869 2
 '@S9S_MB_2U_LIB.S9S_MB_2U(SCH_1):PAGE245_I137@PURE_QUANTA.Q_CAP(CHIPS)':
 'B': CDS_PINID='B';
NODE_NAME     Q39 S
 '@S9S_MB_2U_LIB.S9S_MB_2U(SCH_1):PAGE229_I9@PURE_QUANTA.MOSFET_NCH_GDS_ESD_PROTECTED(CHIPS)':
 'S': CDS_PINID='S';
NODE_NAME     Q125 4
 '@S9S_MB_2U_LIB.S9S_MB_2U(SCH_1):PAGE229_I26@PURE_QUANTA.MOSFET_NCH_DUAL(CHIPS)':
 'S2': CDS_PINID='S2';
NODE_NAME     PC2241 2
 '@S9S_MB_2U_LIB.S9S_MB_2U(SCH_1):PAGE229_I57@PURE_QUANTA.Q_CAP(CHIPS)':
 'B': CDS_PINID='B';
NODE_NAME     PR4002 2
 '@S9S_MB_2U_LIB.S9S_MB_2U(SCH_1):PAGE229_I61@PURE_QUANTA.Q_RES(CHIPS)':
 'B': CDS_PINID='B';
NODE_NAME     PU300 A7
 '@S9S_MB_2U_LIB.S9S_MB_2U(SCH_1):PAGE229_I69@PURE_QUANTA.MAX15090BEWIT(CHIPS)':
 'CDLY': CDS_PINID='CDLY';
NODE_NAME     PU300 B7
 '@S9S_MB_2U_LIB.S9S_MB_2U(SCH_1):PAGE229_I69@PURE_QUANTA.MAX15090BEWIT(CHIPS)':
 'EN#': CDS_PINID='\en#\';
NODE_NAME     PU300 B2
 '@S9S_MB_2U_LIB.S9S_MB_2U(SCH_1):PAGE229_I69@PURE_QUANTA.MAX15090BEWIT(CHIPS)':
 'GND_B2': CDS_PINID='GND_B2';
NODE_NAME     PU300 C1
 '@S9S_MB_2U_LIB.S9S_MB_2U(SCH_1):PAGE229_I69@PURE_QUANTA.MAX15090BEWIT(CHIPS)':
 'GND_C1': CDS_PINID='GND_C1';
NODE_NAME     PU300 C2
 '@S9S_MB_2U_LIB.S9S_MB_2U(SCH_1):PAGE229_I69@PURE_QUANTA.MAX15090BEWIT(CHIPS)':
 'GND_C2': CDS_PINID='GND_C2';
NODE_NAME     PC2237 2
 '@S9S_MB_2U_LIB.S9S_MB_2U(SCH_1):PAGE229_I75@PURE_QUANTA.Q_CAP(CHIPS)':
 'B': CDS_PINID='B';
NODE_NAME     PD116 A
 '@S9S_MB_2U_LIB.S9S_MB_2U(SCH_1):PAGE229_I82@PURE_QUANTA.SCHOTTKY_AC(CHIPS)':
 'A': CDS_PINID='A';
NODE_NAME     PC2240 2
 '@S9S_MB_2U_LIB.S9S_MB_2U(SCH_1):PAGE229_I84@PURE_QUANTA.Q_CAP(CHIPS)':
 'B': CDS_PINID='B';
NODE_NAME     PC2242 2
 '@S9S_MB_2U_LIB.S9S_MB_2U(SCH_1):PAGE229_I88@PURE_QUANTA.Q_CAP(CHIPS)':
 'B': CDS_PINID='B';
NODE_NAME     PU299 3
 '@S9S_MB_2U_LIB.S9S_MB_2U(SCH_1):PAGE229_I90@PURE_QUANTA.RS31312R(CHIPS)':
 'ENTM': CDS_PINID='ENTM';
NODE_NAME     PU299 7
 '@S9S_MB_2U_LIB.S9S_MB_2U(SCH_1):PAGE229_I90@PURE_QUANTA.RS31312R(CHIPS)':
 'GND': CDS_PINID='GND';
NODE_NAME     PU299 2
 '@S9S_MB_2U_LIB.S9S_MB_2U(SCH_1):PAGE229_I90@PURE_QUANTA.RS31312R(CHIPS)':
 'LOADEN': CDS_PINID='LOADEN';
NODE_NAME     PC1648 2
 '@S9S_MB_2U_LIB.S9S_MB_2U(SCH_1):PAGE244_I2@PURE_QUANTA.Q_CAP(CHIPS)':
 'B': CDS_PINID='B';
NODE_NAME     PC1849 2
 '@S9S_MB_2U_LIB.S9S_MB_2U(SCH_1):PAGE244_I7@PURE_QUANTA.Q_CAP(CHIPS)':
 'B': CDS_PINID='B';
NODE_NAME     PC1848 2
 '@S9S_MB_2U_LIB.S9S_MB_2U(SCH_1):PAGE244_I8@PURE_QUANTA.Q_CAP(CHIPS)':
 'B': CDS_PINID='B';
NODE_NAME     PC1850 2
 '@S9S_MB_2U_LIB.S9S_MB_2U(SCH_1):PAGE244_I11@PURE_QUANTA.Q_CAP(CHIPS)':
 'B': CDS_PINID='B';
NODE_NAME     PC1846 2
 '@S9S_MB_2U_LIB.S9S_MB_2U(SCH_1):PAGE244_I14@PURE_QUANTA.Q_CAP(CHIPS)':
 'B': CDS_PINID='B';
NODE_NAME     PU181 2
 '@S9S_MB_2U_LIB.S9S_MB_2U(SCH_1):PAGE244_I20@PURE_QUANTA.RS53318LR(CHIPS)':
 'AGND': CDS_PINID='AGND';
NODE_NAME     PU181 11_18
 '@S9S_MB_2U_LIB.S9S_MB_2U(SCH_1):PAGE244_I20@PURE_QUANTA.RS53318LR(CHIPS)':
 'PGND': CDS_PINID='PGND';
NODE_NAME     PU181 6
 '@S9S_MB_2U_LIB.S9S_MB_2U(SCH_1):PAGE244_I20@PURE_QUANTA.RS53318LR(CHIPS)':
 'RTN': CDS_PINID='RTN';
NODE_NAME     PC1853 2
 '@S9S_MB_2U_LIB.S9S_MB_2U(SCH_1):PAGE244_I21@PURE_QUANTA.Q_CAP(CHIPS)':
 'B': CDS_PINID='B';
NODE_NAME     PC1845 2
 '@S9S_MB_2U_LIB.S9S_MB_2U(SCH_1):PAGE244_I32@PURE_QUANTA.Q_CAPP(CHIPS)':
 'B': CDS_PINID='B';
NODE_NAME     PC1855 2
 '@S9S_MB_2U_LIB.S9S_MB_2U(SCH_1):PAGE244_I33@PURE_QUANTA.Q_CAP(CHIPS)':
 'B': CDS_PINID='B';
NODE_NAME     PC1852 2
 '@S9S_MB_2U_LIB.S9S_MB_2U(SCH_1):PAGE244_I36@PURE_QUANTA.Q_CAP(CHIPS)':
 'B': CDS_PINID='B';
NODE_NAME     PR1850 1
 '@S9S_MB_2U_LIB.S9S_MB_2U(SCH_1):PAGE249_I11@PURE_QUANTA.Q_RES(CHIPS)':
 'A': CDS_PINID='A';
NODE_NAME     PC1232 2
 '@S9S_MB_2U_LIB.S9S_MB_2U(SCH_1):PAGE249_I19@PURE_QUANTA.Q_CAP(CHIPS)':
 'B': CDS_PINID='B';
NODE_NAME     PC1233 2
 '@S9S_MB_2U_LIB.S9S_MB_2U(SCH_1):PAGE249_I20@PURE_QUANTA.Q_CAP(CHIPS)':
 'B': CDS_PINID='B';
NODE_NAME     PC1241 2
 '@S9S_MB_2U_LIB.S9S_MB_2U(SCH_1):PAGE249_I41@PURE_QUANTA.Q_CAP(CHIPS)':
 'B': CDS_PINID='B';
NODE_NAME     PR1653 2
 '@S9S_MB_2U_LIB.S9S_MB_2U(SCH_1):PAGE249_I42@PURE_QUANTA.Q_RES(CHIPS)':
 'B': CDS_PINID='B';
NODE_NAME     PC1247 2
 '@S9S_MB_2U_LIB.S9S_MB_2U(SCH_1):PAGE267_I10@PURE_QUANTA.Q_CAP(CHIPS)':
 'B': CDS_PINID='B';
NODE_NAME     R2332 2
 '@S9S_MB_2U_LIB.S9S_MB_2U(SCH_1):PAGE267_I14@PURE_QUANTA.Q_RES(CHIPS)':
 'B': CDS_PINID='B';
NODE_NAME     PU79 2
 '@S9S_MB_2U_LIB.S9S_MB_2U(SCH_1):PAGE267_I19@PURE_QUANTA.RS53318LR(CHIPS)':
 'AGND': CDS_PINID='AGND';
NODE_NAME     PU79 11_18
 '@S9S_MB_2U_LIB.S9S_MB_2U(SCH_1):PAGE267_I19@PURE_QUANTA.RS53318LR(CHIPS)':
 'PGND': CDS_PINID='PGND';
NODE_NAME     PC1257 2
 '@S9S_MB_2U_LIB.S9S_MB_2U(SCH_1):PAGE267_I44@PURE_QUANTA.Q_CAP(CHIPS)':
 'B': CDS_PINID='B';
NODE_NAME     PC113 2
 '@S9S_MB_2U_LIB.S9S_MB_2U(SCH_1):PAGE248_I2@PURE_QUANTA.Q_CAP(CHIPS)':
 'B': CDS_PINID='B';
NODE_NAME     PR338 2
 '@S9S_MB_2U_LIB.S9S_MB_2U(SCH_1):PAGE248_I10@PURE_QUANTA.Q_RES(CHIPS)':
 'B': CDS_PINID='B';
NODE_NAME     PC2000 2
 '@S9S_MB_2U_LIB.S9S_MB_2U(SCH_1):PAGE248_I14@PURE_QUANTA.Q_CAP(CHIPS)':
 'B': CDS_PINID='B';
NODE_NAME     PC1216 2
 '@S9S_MB_2U_LIB.S9S_MB_2U(SCH_1):PAGE248_I25@PURE_QUANTA.Q_CAP(CHIPS)':
 'B': CDS_PINID='B';
NODE_NAME     PC1224 2
 '@S9S_MB_2U_LIB.S9S_MB_2U(SCH_1):PAGE248_I38@PURE_QUANTA.Q_CAP(CHIPS)':
 'B': CDS_PINID='B';
NODE_NAME     PC117 2
 '@S9S_MB_2U_LIB.S9S_MB_2U(SCH_1):PAGE248_I40@PURE_QUANTA.Q_CAPP(CHIPS)':
 'B': CDS_PINID='B';
NODE_NAME     PC1230 2
 '@S9S_MB_2U_LIB.S9S_MB_2U(SCH_1):PAGE248_I48@PURE_QUANTA.Q_CAPP(CHIPS)':
 'B': CDS_PINID='B';
NODE_NAME     PC2221 2
 '@S9S_MB_2U_LIB.S9S_MB_2U(SCH_1):PAGE268_I7@PURE_QUANTA.Q_CAP(CHIPS)':
 'B': CDS_PINID='B';
NODE_NAME     PR1301 2
 '@S9S_MB_2U_LIB.S9S_MB_2U(SCH_1):PAGE268_I9@PURE_QUANTA.Q_RES(CHIPS)':
 'B': CDS_PINID='B';
NODE_NAME     PC1272 2
 '@S9S_MB_2U_LIB.S9S_MB_2U(SCH_1):PAGE268_I13@PURE_QUANTA.Q_CAP(CHIPS)':
 'B': CDS_PINID='B';
NODE_NAME     PR1303 2
 '@S9S_MB_2U_LIB.S9S_MB_2U(SCH_1):PAGE268_I21@PURE_QUANTA.Q_RES(CHIPS)':
 'B': CDS_PINID='B';
NODE_NAME     PU81 7
 '@S9S_MB_2U_LIB.S9S_MB_2U(SCH_1):PAGE268_I22@PURE_QUANTA.RS53317LR(CHIPS)':
 'AGND': CDS_PINID='AGND';
NODE_NAME     PU81 1
 '@S9S_MB_2U_LIB.S9S_MB_2U(SCH_1):PAGE268_I22@PURE_QUANTA.RS53317LR(CHIPS)':
 'PGND1': CDS_PINID='PGND1';
NODE_NAME     PU81 14
 '@S9S_MB_2U_LIB.S9S_MB_2U(SCH_1):PAGE268_I22@PURE_QUANTA.RS53317LR(CHIPS)':
 'PGND2': CDS_PINID='PGND2';
NODE_NAME     PC1276 2
 '@S9S_MB_2U_LIB.S9S_MB_2U(SCH_1):PAGE268_I37@PURE_QUANTA.Q_CAP(CHIPS)':
 'B': CDS_PINID='B';
NODE_NAME     PC1277 2
 '@S9S_MB_2U_LIB.S9S_MB_2U(SCH_1):PAGE268_I38@PURE_QUANTA.Q_CAP(CHIPS)':
 'B': CDS_PINID='B';
NODE_NAME     PC1206 2
 '@S9S_MB_2U_LIB.S9S_MB_2U(SCH_1):PAGE268_I47@PURE_QUANTA.Q_CAP(CHIPS)':
 'B': CDS_PINID='B';
NODE_NAME     PC644 2
 '@S9S_MB_2U_LIB.S9S_MB_2U(SCH_1):PAGE285_I1@PURE_QUANTA.Q_CAP(CHIPS)':
 'B': CDS_PINID='B';
NODE_NAME     PC1259 2
 '@S9S_MB_2U_LIB.S9S_MB_2U(SCH_1):PAGE285_I8@PURE_QUANTA.Q_CAP(CHIPS)':
 'B': CDS_PINID='B';
NODE_NAME     PC2002 2
 '@S9S_MB_2U_LIB.S9S_MB_2U(SCH_1):PAGE285_I23@PURE_QUANTA.Q_CAP(CHIPS)':
 'B': CDS_PINID='B';
NODE_NAME     PC1267 2
 '@S9S_MB_2U_LIB.S9S_MB_2U(SCH_1):PAGE285_I39@PURE_QUANTA.Q_CAP(CHIPS)':
 'B': CDS_PINID='B';
NODE_NAME     PC1268 2
 '@S9S_MB_2U_LIB.S9S_MB_2U(SCH_1):PAGE285_I40@PURE_QUANTA.Q_CAP(CHIPS)':
 'B': CDS_PINID='B';
NODE_NAME     PC1270 2
 '@S9S_MB_2U_LIB.S9S_MB_2U(SCH_1):PAGE285_I47@PURE_QUANTA.Q_CAP(CHIPS)':
 'B': CDS_PINID='B';
NODE_NAME     PC1771 2
 '@S9S_MB_2U_LIB.S9S_MB_2U(SCH_1):PAGE285_I49@PURE_QUANTA.Q_CAPP(CHIPS)':
 'B': CDS_PINID='B';
NODE_NAME     R2385 2
 '@S9S_MB_2U_LIB.S9S_MB_2U(SCH_1):PAGE286_I7@PURE_QUANTA.Q_RES(CHIPS)':
 'B': CDS_PINID='B';
NODE_NAME     PC2222 2
 '@S9S_MB_2U_LIB.S9S_MB_2U(SCH_1):PAGE286_I10@PURE_QUANTA.Q_CAP(CHIPS)':
 'B': CDS_PINID='B';
NODE_NAME     PR2220 2
 '@S9S_MB_2U_LIB.S9S_MB_2U(SCH_1):PAGE286_I12@PURE_QUANTA.Q_RES(CHIPS)':
 'B': CDS_PINID='B';
NODE_NAME     PC1281 2
 '@S9S_MB_2U_LIB.S9S_MB_2U(SCH_1):PAGE286_I14@PURE_QUANTA.Q_CAP(CHIPS)':
 'B': CDS_PINID='B';
NODE_NAME     PR2222 2
 '@S9S_MB_2U_LIB.S9S_MB_2U(SCH_1):PAGE286_I19@PURE_QUANTA.Q_RES(CHIPS)':
 'B': CDS_PINID='B';
NODE_NAME     PC1284 2
 '@S9S_MB_2U_LIB.S9S_MB_2U(SCH_1):PAGE286_I28@PURE_QUANTA.Q_CAP(CHIPS)':
 'B': CDS_PINID='B';
NODE_NAME     C1297 2
 '@S9S_MB_2U_LIB.S9S_MB_2U(SCH_1):PAGE286_I37@PURE_QUANTA.Q_CAP(CHIPS)':
 'B': CDS_PINID='B';
NODE_NAME     PC2277 2
 '@S9S_MB_2U_LIB.S9S_MB_2U(SCH_1):PAGE286_I40@PURE_QUANTA.Q_CAP(CHIPS)':
 'B': CDS_PINID='B';
NODE_NAME     PC1207 2
 '@S9S_MB_2U_LIB.S9S_MB_2U(SCH_1):PAGE286_I45@PURE_QUANTA.Q_CAP(CHIPS)':
 'B': CDS_PINID='B';
NODE_NAME     R1692 2
 '@S9S_MB_2U_LIB.S9S_MB_2U(SCH_1):PAGE232_I3@PURE_QUANTA.Q_RES(CHIPS)':
 'B': CDS_PINID='B';
NODE_NAME     C1318 2
 '@S9S_MB_2U_LIB.S9S_MB_2U(SCH_1):PAGE232_I7@PURE_QUANTA.Q_CAP(CHIPS)':
 'B': CDS_PINID='B';
NODE_NAME     C1317 2
 '@S9S_MB_2U_LIB.S9S_MB_2U(SCH_1):PAGE232_I9@PURE_QUANTA.Q_CAP(CHIPS)':
 'B': CDS_PINID='B';
NODE_NAME     U95 3
 '@S9S_MB_2U_LIB.S9S_MB_2U(SCH_1):PAGE232_I11@PURE_QUANTA.74LVC1G07SE7(CHIPS)':
 'GND': CDS_PINID='GND';
NODE_NAME     Q52 S
 '@S9S_MB_2U_LIB.S9S_MB_2U(SCH_1):PAGE232_I14@PURE_QUANTA.MOSFET_NCH_GDS_ESD_PROTECTED(CHIPS)':
 'S': CDS_PINID='S';
NODE_NAME     R1689 2
 '@S9S_MB_2U_LIB.S9S_MB_2U(SCH_1):PAGE232_I16@PURE_QUANTA.Q_RES(CHIPS)':
 'B': CDS_PINID='B';
NODE_NAME     C1315 2
 '@S9S_MB_2U_LIB.S9S_MB_2U(SCH_1):PAGE232_I24@PURE_QUANTA.Q_CAP(CHIPS)':
 'B': CDS_PINID='B';
NODE_NAME     U117 2
 '@S9S_MB_2U_LIB.S9S_MB_2U(SCH_1):PAGE232_I26@PURE_QUANTA.TPS3895ADRYR(CHIPS)':
 'GND': CDS_PINID='GND';
NODE_NAME     U94 2
 '@S9S_MB_2U_LIB.S9S_MB_2U(SCH_1):PAGE232_I27@PURE_QUANTA.ADM1086AKSZREEL7(CHIPS)':
 'GND': CDS_PINID='GND';
NODE_NAME     R4808 2
 '@S9S_MB_2U_LIB.S9S_MB_2U(SCH_1):PAGE232_I31@PURE_QUANTA.Q_RES(CHIPS)':
 'B': CDS_PINID='B';
NODE_NAME     Q53 S
 '@S9S_MB_2U_LIB.S9S_MB_2U(SCH_1):PAGE232_I39@PURE_QUANTA.MOSFET_NCH_GDS_ESD_PROTECTED(CHIPS)':
 'S': CDS_PINID='S';
NODE_NAME     R678 2
 '@S9S_MB_2U_LIB.S9S_MB_2U(SCH_1):PAGE217_I13@PURE_QUANTA.Q_RES(CHIPS)':
 'B': CDS_PINID='B';
NODE_NAME     U15 8
 '@S9S_MB_2U_LIB.S9S_MB_2U(SCH_1):PAGE217_I19@PURE_QUANTA.QS3VH257QG8(CHIPS)':
 'GND': CDS_PINID='GND';
NODE_NAME     C538 2
 '@S9S_MB_2U_LIB.S9S_MB_2U(SCH_1):PAGE217_I24@PURE_QUANTA.Q_CAP(CHIPS)':
 'B': CDS_PINID='B';
NODE_NAME     R318 2
 '@S9S_MB_2U_LIB.S9S_MB_2U(SCH_1):PAGE217_I42@PURE_QUANTA.Q_RES(CHIPS)':
 'B': CDS_PINID='B';
NODE_NAME     R4592 2
 '@S9S_MB_2U_LIB.S9S_MB_2U(SCH_1):PAGE184_I4@PURE_QUANTA.Q_RES(CHIPS)':
 'B': CDS_PINID='B';
NODE_NAME     R2235 2
 '@S9S_MB_2U_LIB.S9S_MB_2U(SCH_1):PAGE184_I9@PURE_QUANTA.Q_RES(CHIPS)':
 'B': CDS_PINID='B';
NODE_NAME     R2977 2
 '@S9S_MB_2U_LIB.S9S_MB_2U(SCH_1):PAGE184_I11@PURE_QUANTA.Q_RES(CHIPS)':
 'B': CDS_PINID='B';
NODE_NAME     R4598 2
 '@S9S_MB_2U_LIB.S9S_MB_2U(SCH_1):PAGE184_I16@PURE_QUANTA.Q_RES(CHIPS)':
 'B': CDS_PINID='B';
NODE_NAME     R2980 2
 '@S9S_MB_2U_LIB.S9S_MB_2U(SCH_1):PAGE184_I26@PURE_QUANTA.Q_RES(CHIPS)':
 'B': CDS_PINID='B';
NODE_NAME     R2241 2
 '@S9S_MB_2U_LIB.S9S_MB_2U(SCH_1):PAGE184_I28@PURE_QUANTA.Q_RES(CHIPS)':
 'B': CDS_PINID='B';
NODE_NAME     R4596 2
 '@S9S_MB_2U_LIB.S9S_MB_2U(SCH_1):PAGE184_I61@PURE_QUANTA.Q_RES(CHIPS)':
 'B': CDS_PINID='B';
NODE_NAME     Q139 1
 '@S9S_MB_2U_LIB.S9S_MB_2U(SCH_1):PAGE121_I21@PURE_QUANTA.BC847BPN(CHIPS)':
 'E1': CDS_PINID='E1';
NODE_NAME     Q138 1
 '@S9S_MB_2U_LIB.S9S_MB_2U(SCH_1):PAGE121_I31@PURE_QUANTA.BC847BPN(CHIPS)':
 'E1': CDS_PINID='E1';
NODE_NAME     Q142 1
 '@S9S_MB_2U_LIB.S9S_MB_2U(SCH_1):PAGE122_I17@PURE_QUANTA.BC847BPN(CHIPS)':
 'E1': CDS_PINID='E1';
NODE_NAME     Q143 1
 '@S9S_MB_2U_LIB.S9S_MB_2U(SCH_1):PAGE122_I22@PURE_QUANTA.BC847BPN(CHIPS)':
 'E1': CDS_PINID='E1';
NODE_NAME     Q140 1
 '@S9S_MB_2U_LIB.S9S_MB_2U(SCH_1):PAGE123_I16@PURE_QUANTA.BC847BPN(CHIPS)':
 'E1': CDS_PINID='E1';
NODE_NAME     Q141 1
 '@S9S_MB_2U_LIB.S9S_MB_2U(SCH_1):PAGE123_I18@PURE_QUANTA.BC847BPN(CHIPS)':
 'E1': CDS_PINID='E1';
NODE_NAME     R4769 2
 '@S9S_MB_2U_LIB.S9S_MB_2U(SCH_1):PAGE233_I3@PURE_QUANTA.Q_RES(CHIPS)':
 'B': CDS_PINID='B';
NODE_NAME     J45 B3
 '@S9S_MB_2U_LIB.S9S_MB_2U(SCH_1):PAGE233_I12@PURE_QUANTA.CONN60_101062636003K02LF(CHIPS)':
 'B3': CDS_PINID='B3';
NODE_NAME     J45 P1_1
 '@S9S_MB_2U_LIB.S9S_MB_2U(SCH_1):PAGE233_I12@PURE_QUANTA.CONN60_101062636003K02LF(CHIPS)':
 'P1_1': CDS_PINID='P1_1';
NODE_NAME     J45 P1_2
 '@S9S_MB_2U_LIB.S9S_MB_2U(SCH_1):PAGE233_I12@PURE_QUANTA.CONN60_101062636003K02LF(CHIPS)':
 'P1_2': CDS_PINID='P1_2';
NODE_NAME     J45 P1_3
 '@S9S_MB_2U_LIB.S9S_MB_2U(SCH_1):PAGE233_I12@PURE_QUANTA.CONN60_101062636003K02LF(CHIPS)':
 'P1_3': CDS_PINID='P1_3';
NODE_NAME     J45 P1_4
 '@S9S_MB_2U_LIB.S9S_MB_2U(SCH_1):PAGE233_I12@PURE_QUANTA.CONN60_101062636003K02LF(CHIPS)':
 'P1_4': CDS_PINID='P1_4';
NODE_NAME     J45 P1_5
 '@S9S_MB_2U_LIB.S9S_MB_2U(SCH_1):PAGE233_I12@PURE_QUANTA.CONN60_101062636003K02LF(CHIPS)':
 'P1_5': CDS_PINID='P1_5';
NODE_NAME     J45 P1_6
 '@S9S_MB_2U_LIB.S9S_MB_2U(SCH_1):PAGE233_I12@PURE_QUANTA.CONN60_101062636003K02LF(CHIPS)':
 'P1_6': CDS_PINID='P1_6';
NODE_NAME     J45 P1_7
 '@S9S_MB_2U_LIB.S9S_MB_2U(SCH_1):PAGE233_I12@PURE_QUANTA.CONN60_101062636003K02LF(CHIPS)':
 'P1_7': CDS_PINID='P1_7';
NODE_NAME     J45 P1_8
 '@S9S_MB_2U_LIB.S9S_MB_2U(SCH_1):PAGE233_I12@PURE_QUANTA.CONN60_101062636003K02LF(CHIPS)':
 'P1_8': CDS_PINID='P1_8';
NODE_NAME     J45 P2_1
 '@S9S_MB_2U_LIB.S9S_MB_2U(SCH_1):PAGE233_I12@PURE_QUANTA.CONN60_101062636003K02LF(CHIPS)':
 'P2_1': CDS_PINID='P2_1';
NODE_NAME     J45 P2_2
 '@S9S_MB_2U_LIB.S9S_MB_2U(SCH_1):PAGE233_I12@PURE_QUANTA.CONN60_101062636003K02LF(CHIPS)':
 'P2_2': CDS_PINID='P2_2';
NODE_NAME     J45 P2_3
 '@S9S_MB_2U_LIB.S9S_MB_2U(SCH_1):PAGE233_I12@PURE_QUANTA.CONN60_101062636003K02LF(CHIPS)':
 'P2_3': CDS_PINID='P2_3';
NODE_NAME     J45 P2_4
 '@S9S_MB_2U_LIB.S9S_MB_2U(SCH_1):PAGE233_I12@PURE_QUANTA.CONN60_101062636003K02LF(CHIPS)':
 'P2_4': CDS_PINID='P2_4';
NODE_NAME     J45 P2_5
 '@S9S_MB_2U_LIB.S9S_MB_2U(SCH_1):PAGE233_I12@PURE_QUANTA.CONN60_101062636003K02LF(CHIPS)':
 'P2_5': CDS_PINID='P2_5';
NODE_NAME     J45 P2_6
 '@S9S_MB_2U_LIB.S9S_MB_2U(SCH_1):PAGE233_I12@PURE_QUANTA.CONN60_101062636003K02LF(CHIPS)':
 'P2_6': CDS_PINID='P2_6';
NODE_NAME     J45 P2_7
 '@S9S_MB_2U_LIB.S9S_MB_2U(SCH_1):PAGE233_I12@PURE_QUANTA.CONN60_101062636003K02LF(CHIPS)':
 'P2_7': CDS_PINID='P2_7';
NODE_NAME     J45 P2_8
 '@S9S_MB_2U_LIB.S9S_MB_2U(SCH_1):PAGE233_I12@PURE_QUANTA.CONN60_101062636003K02LF(CHIPS)':
 'P2_8': CDS_PINID='P2_8';
NODE_NAME     J45 P3_1
 '@S9S_MB_2U_LIB.S9S_MB_2U(SCH_1):PAGE233_I12@PURE_QUANTA.CONN60_101062636003K02LF(CHIPS)':
 'P3_1': CDS_PINID='P3_1';
NODE_NAME     J45 P3_2
 '@S9S_MB_2U_LIB.S9S_MB_2U(SCH_1):PAGE233_I12@PURE_QUANTA.CONN60_101062636003K02LF(CHIPS)':
 'P3_2': CDS_PINID='P3_2';
NODE_NAME     J45 P3_3
 '@S9S_MB_2U_LIB.S9S_MB_2U(SCH_1):PAGE233_I12@PURE_QUANTA.CONN60_101062636003K02LF(CHIPS)':
 'P3_3': CDS_PINID='P3_3';
NODE_NAME     J45 P3_4
 '@S9S_MB_2U_LIB.S9S_MB_2U(SCH_1):PAGE233_I12@PURE_QUANTA.CONN60_101062636003K02LF(CHIPS)':
 'P3_4': CDS_PINID='P3_4';
NODE_NAME     J45 P3_5
 '@S9S_MB_2U_LIB.S9S_MB_2U(SCH_1):PAGE233_I12@PURE_QUANTA.CONN60_101062636003K02LF(CHIPS)':
 'P3_5': CDS_PINID='P3_5';
NODE_NAME     J45 P3_6
 '@S9S_MB_2U_LIB.S9S_MB_2U(SCH_1):PAGE233_I12@PURE_QUANTA.CONN60_101062636003K02LF(CHIPS)':
 'P3_6': CDS_PINID='P3_6';
NODE_NAME     J45 P3_7
 '@S9S_MB_2U_LIB.S9S_MB_2U(SCH_1):PAGE233_I12@PURE_QUANTA.CONN60_101062636003K02LF(CHIPS)':
 'P3_7': CDS_PINID='P3_7';
NODE_NAME     J45 P3_8
 '@S9S_MB_2U_LIB.S9S_MB_2U(SCH_1):PAGE233_I12@PURE_QUANTA.CONN60_101062636003K02LF(CHIPS)':
 'P3_8': CDS_PINID='P3_8';
NODE_NAME     U192 4
 '@S9S_MB_2U_LIB.S9S_MB_2U(SCH_1):PAGE233_I16@PURE_QUANTA.LTC4307CMS8(CHIPS)':
 'GND': CDS_PINID='GND';
NODE_NAME     C1751 2
 '@S9S_MB_2U_LIB.S9S_MB_2U(SCH_1):PAGE233_I19@PURE_QUANTA.Q_CAP(CHIPS)':
 'B': CDS_PINID='B';
NODE_NAME     C2371 2
 '@S9S_MB_2U_LIB.S9S_MB_2U(SCH_1):PAGE233_I51@PURE_QUANTA.Q_CAP(CHIPS)':
 'B': CDS_PINID='B';
NODE_NAME     C2297 2
 '@S9S_MB_2U_LIB.S9S_MB_2U(SCH_1):PAGE233_I52@PURE_QUANTA.Q_CAP(CHIPS)':
 'B': CDS_PINID='B';
NODE_NAME     C2296 2
 '@S9S_MB_2U_LIB.S9S_MB_2U(SCH_1):PAGE233_I53@PURE_QUANTA.Q_CAP(CHIPS)':
 'B': CDS_PINID='B';
NODE_NAME     C2295 2
 '@S9S_MB_2U_LIB.S9S_MB_2U(SCH_1):PAGE233_I54@PURE_QUANTA.Q_CAP(CHIPS)':
 'B': CDS_PINID='B';
NODE_NAME     C2294 2
 '@S9S_MB_2U_LIB.S9S_MB_2U(SCH_1):PAGE233_I55@PURE_QUANTA.Q_CAP(CHIPS)':
 'B': CDS_PINID='B';
NODE_NAME     C2293 2
 '@S9S_MB_2U_LIB.S9S_MB_2U(SCH_1):PAGE233_I57@PURE_QUANTA.Q_CAP(CHIPS)':
 'B': CDS_PINID='B';
NODE_NAME     R661 2
 '@S9S_MB_2U_LIB.S9S_MB_2U(SCH_1):PAGE218_I4@PURE_QUANTA.Q_RES(CHIPS)':
 'B': CDS_PINID='B';
NODE_NAME     U14 8
 '@S9S_MB_2U_LIB.S9S_MB_2U(SCH_1):PAGE218_I12@PURE_QUANTA.QS3VH257QG8(CHIPS)':
 'GND': CDS_PINID='GND';
NODE_NAME     C537 2
 '@S9S_MB_2U_LIB.S9S_MB_2U(SCH_1):PAGE218_I25@PURE_QUANTA.Q_CAP(CHIPS)':
 'B': CDS_PINID='B';
NODE_NAME     U200 4
 '@S9S_MB_2U_LIB.S9S_MB_2U(SCH_1):PAGE222_I11@PURE_QUANTA.LTC4307CMS8(CHIPS)':
 'GND': CDS_PINID='GND';
NODE_NAME     C1796 2
 '@S9S_MB_2U_LIB.S9S_MB_2U(SCH_1):PAGE222_I20@PURE_QUANTA.Q_CAP(CHIPS)':
 'B': CDS_PINID='B';
NODE_NAME     U176 4
 '@S9S_MB_2U_LIB.S9S_MB_2U(SCH_1):PAGE222_I31@PURE_QUANTA.LTC4307CMS8(CHIPS)':
 'GND': CDS_PINID='GND';
NODE_NAME     R4603 2
 '@S9S_MB_2U_LIB.S9S_MB_2U(SCH_1):PAGE222_I48@PURE_QUANTA.Q_RES(CHIPS)':
 'B': CDS_PINID='B';
NODE_NAME     U175 4
 '@S9S_MB_2U_LIB.S9S_MB_2U(SCH_1):PAGE222_I50@PURE_QUANTA.LTC4307CMS8(CHIPS)':
 'GND': CDS_PINID='GND';
NODE_NAME     C1707 2
 '@S9S_MB_2U_LIB.S9S_MB_2U(SCH_1):PAGE222_I58@PURE_QUANTA.Q_CAP(CHIPS)':
 'B': CDS_PINID='B';
NODE_NAME     U194 4
 '@S9S_MB_2U_LIB.S9S_MB_2U(SCH_1):PAGE222_I63@PURE_QUANTA.LTC4307CMS8(CHIPS)':
 'GND': CDS_PINID='GND';
NODE_NAME     R587 2
 '@S9S_MB_2U_LIB.S9S_MB_2U(SCH_1):PAGE219_I8@PURE_QUANTA.Q_RES(CHIPS)':
 'B': CDS_PINID='B';
NODE_NAME     U36 12
 '@S9S_MB_2U_LIB.S9S_MB_2U(SCH_1):PAGE219_I45@PURE_QUANTA.TCA9548APWR(CHIPS)':
 'GND': CDS_PINID='GND';
NODE_NAME     C174 2
 '@S9S_MB_2U_LIB.S9S_MB_2U(SCH_1):PAGE219_I47@PURE_QUANTA.Q_CAP(CHIPS)':
 'B': CDS_PINID='B';
NODE_NAME     C1302 2
 '@S9S_MB_2U_LIB.S9S_MB_2U(SCH_1):PAGE227_I82@PURE_QUANTA.Q_CAP(CHIPS)':
 'B': CDS_PINID='B';
NODE_NAME     R4635 2
 '@S9S_MB_2U_LIB.S9S_MB_2U(SCH_1):PAGE235_I3@PURE_QUANTA.Q_RES(CHIPS)':
 'B': CDS_PINID='B';
NODE_NAME     JP16 3
 '@S9S_MB_2U_LIB.S9S_MB_2U(SCH_1):PAGE235_I13@PURE_QUANTA.CONN3_210HP1030BR1(CHIPS)':
 '3': CDS_PINID='\3\';
NODE_NAME     U327 7
 '@S9S_MB_2U_LIB.S9S_MB_2U(SCH_1):PAGE235_I19@PURE_QUANTA.74CBTLV3126PW(CHIPS)':
 'GND': CDS_PINID='GND';
NODE_NAME     C2348 2
 '@S9S_MB_2U_LIB.S9S_MB_2U(SCH_1):PAGE235_I23@PURE_QUANTA.Q_CAP(CHIPS)':
 'B': CDS_PINID='B';
NODE_NAME     U331 10
 '@S9S_MB_2U_LIB.S9S_MB_2U(SCH_1):PAGE240_I39@PURE_QUANTA.INA230AIRGTR(CHIPS)':
 'GND': CDS_PINID='GND';
NODE_NAME     U331 TH
 '@S9S_MB_2U_LIB.S9S_MB_2U(SCH_1):PAGE240_I39@PURE_QUANTA.INA230AIRGTR(CHIPS)':
 'TH': CDS_PINID='TH';
NODE_NAME     R2973 2
 '@S9S_MB_2U_LIB.S9S_MB_2U(SCH_1):PAGE184_I69@PURE_QUANTA.Q_RES(CHIPS)':
 'B': CDS_PINID='B';
NODE_NAME     R2975 2
 '@S9S_MB_2U_LIB.S9S_MB_2U(SCH_1):PAGE184_I70@PURE_QUANTA.Q_RES(CHIPS)':
 'B': CDS_PINID='B';
NODE_NAME     R2978 2
 '@S9S_MB_2U_LIB.S9S_MB_2U(SCH_1):PAGE184_I74@PURE_QUANTA.Q_RES(CHIPS)':
 'B': CDS_PINID='B';
NODE_NAME     R4809 2
 '@S9S_MB_2U_LIB.S9S_MB_2U(SCH_1):PAGE227_I2@PURE_QUANTA.Q_RES(CHIPS)':
 'B': CDS_PINID='B';
NODE_NAME     R1801 2
 '@S9S_MB_2U_LIB.S9S_MB_2U(SCH_1):PAGE227_I172@PURE_QUANTA.Q_RES(CHIPS)':
 'B': CDS_PINID='B';
NODE_NAME     J41 OB4
 '@S9S_MB_2U_LIB.S9S_MB_2U(SCH_1):PAGE227_I173@PURE_QUANTA.SCONN168_ME1016810202011(CHIPS)':
 'DATA_IN': CDS_PINID='DATA_IN';
NODE_NAME     J41 G1
 '@S9S_MB_2U_LIB.S9S_MB_2U(SCH_1):PAGE227_I173@PURE_QUANTA.SCONN168_ME1016810202011(CHIPS)':
 'G1': CDS_PINID='G1';
NODE_NAME     J41 G2
 '@S9S_MB_2U_LIB.S9S_MB_2U(SCH_1):PAGE227_I173@PURE_QUANTA.SCONN168_ME1016810202011(CHIPS)':
 'G2': CDS_PINID='G2';
NODE_NAME     J41 G3
 '@S9S_MB_2U_LIB.S9S_MB_2U(SCH_1):PAGE227_I173@PURE_QUANTA.SCONN168_ME1016810202011(CHIPS)':
 'G3': CDS_PINID='G3';
NODE_NAME     J41 G4
 '@S9S_MB_2U_LIB.S9S_MB_2U(SCH_1):PAGE227_I173@PURE_QUANTA.SCONN168_ME1016810202011(CHIPS)':
 'G4': CDS_PINID='G4';
NODE_NAME     J41 G5
 '@S9S_MB_2U_LIB.S9S_MB_2U(SCH_1):PAGE227_I173@PURE_QUANTA.SCONN168_ME1016810202011(CHIPS)':
 'G5': CDS_PINID='G5';
NODE_NAME     J41 A13
 '@S9S_MB_2U_LIB.S9S_MB_2U(SCH_1):PAGE227_I173@PURE_QUANTA.SCONN168_ME1016810202011(CHIPS)':
 'GND_A13': CDS_PINID='GND_A13';
NODE_NAME     J41 A16
 '@S9S_MB_2U_LIB.S9S_MB_2U(SCH_1):PAGE227_I173@PURE_QUANTA.SCONN168_ME1016810202011(CHIPS)':
 'GND_A16': CDS_PINID='GND_A16';
NODE_NAME     J41 A19
 '@S9S_MB_2U_LIB.S9S_MB_2U(SCH_1):PAGE227_I173@PURE_QUANTA.SCONN168_ME1016810202011(CHIPS)':
 'GND_A19': CDS_PINID='GND_A19';
NODE_NAME     J41 A22
 '@S9S_MB_2U_LIB.S9S_MB_2U(SCH_1):PAGE227_I173@PURE_QUANTA.SCONN168_ME1016810202011(CHIPS)':
 'GND_A22': CDS_PINID='GND_A22';
NODE_NAME     J41 A58
 '@S9S_MB_2U_LIB.S9S_MB_2U(SCH_1):PAGE227_I173@PURE_QUANTA.SCONN168_ME1016810202011(CHIPS)':
 'GND_A58': CDS_PINID='GND_A58';
NODE_NAME     J41 A61
 '@S9S_MB_2U_LIB.S9S_MB_2U(SCH_1):PAGE227_I173@PURE_QUANTA.SCONN168_ME1016810202011(CHIPS)':
 'GND_A61': CDS_PINID='GND_A61';
NODE_NAME     J41 A64
 '@S9S_MB_2U_LIB.S9S_MB_2U(SCH_1):PAGE227_I173@PURE_QUANTA.SCONN168_ME1016810202011(CHIPS)':
 'GND_A64': CDS_PINID='GND_A64';
NODE_NAME     J41 A67
 '@S9S_MB_2U_LIB.S9S_MB_2U(SCH_1):PAGE227_I173@PURE_QUANTA.SCONN168_ME1016810202011(CHIPS)':
 'GND_A67': CDS_PINID='GND_A67';
NODE_NAME     J41 B38
 '@S9S_MB_2U_LIB.S9S_MB_2U(SCH_1):PAGE227_I173@PURE_QUANTA.SCONN168_ME1016810202011(CHIPS)':
 'GND_B38': CDS_PINID='GND_B38';
NODE_NAME     J41 B49
 '@S9S_MB_2U_LIB.S9S_MB_2U(SCH_1):PAGE227_I173@PURE_QUANTA.SCONN168_ME1016810202011(CHIPS)':
 'GND_B49': CDS_PINID='GND_B49';
NODE_NAME     J41 B52
 '@S9S_MB_2U_LIB.S9S_MB_2U(SCH_1):PAGE227_I173@PURE_QUANTA.SCONN168_ME1016810202011(CHIPS)':
 'GND_B52': CDS_PINID='GND_B52';
NODE_NAME     J41 B55
 '@S9S_MB_2U_LIB.S9S_MB_2U(SCH_1):PAGE227_I173@PURE_QUANTA.SCONN168_ME1016810202011(CHIPS)':
 'GND_B55': CDS_PINID='GND_B55';
NODE_NAME     J41 B58
 '@S9S_MB_2U_LIB.S9S_MB_2U(SCH_1):PAGE227_I173@PURE_QUANTA.SCONN168_ME1016810202011(CHIPS)':
 'GND_B58': CDS_PINID='GND_B58';
NODE_NAME     J41 B61
 '@S9S_MB_2U_LIB.S9S_MB_2U(SCH_1):PAGE227_I173@PURE_QUANTA.SCONN168_ME1016810202011(CHIPS)':
 'GND_B61': CDS_PINID='GND_B61';
NODE_NAME     J41 B64
 '@S9S_MB_2U_LIB.S9S_MB_2U(SCH_1):PAGE227_I173@PURE_QUANTA.SCONN168_ME1016810202011(CHIPS)':
 'GND_B64': CDS_PINID='GND_B64';
NODE_NAME     J41 B67
 '@S9S_MB_2U_LIB.S9S_MB_2U(SCH_1):PAGE227_I173@PURE_QUANTA.SCONN168_ME1016810202011(CHIPS)':
 'GND_B67': CDS_PINID='GND_B67';
NODE_NAME     J41 OA13
 '@S9S_MB_2U_LIB.S9S_MB_2U(SCH_1):PAGE227_I173@PURE_QUANTA.SCONN168_ME1016810202011(CHIPS)':
 'GND_OA13': CDS_PINID='GND_OA13';
NODE_NAME     J41 OB10
 '@S9S_MB_2U_LIB.S9S_MB_2U(SCH_1):PAGE227_I173@PURE_QUANTA.SCONN168_ME1016810202011(CHIPS)':
 'GND_OB10': CDS_PINID='GND_OB10';
NODE_NAME     J41 A33
 '@S9S_MB_2U_LIB.S9S_MB_2U(SCH_1):PAGE227_I173@PURE_QUANTA.SCONN168_ME1016810202011(CHIPS)':
 'PERN5': CDS_PINID='PERN5';
NODE_NAME     J41 B10
 '@S9S_MB_2U_LIB.S9S_MB_2U(SCH_1):PAGE227_I173@PURE_QUANTA.SCONN168_ME1016810202011(CHIPS)':
 'PERST0#': CDS_PINID='\perst0#\';
NODE_NAME     J41 B17
 '@S9S_MB_2U_LIB.S9S_MB_2U(SCH_1):PAGE227_I173@PURE_QUANTA.SCONN168_ME1016810202011(CHIPS)':
 'PETN0': CDS_PINID='PETN0';
NODE_NAME     J41 B26
 '@S9S_MB_2U_LIB.S9S_MB_2U(SCH_1):PAGE227_I173@PURE_QUANTA.SCONN168_ME1016810202011(CHIPS)':
 'PETN3': CDS_PINID='PETN3';
NODE_NAME     J41 B33
 '@S9S_MB_2U_LIB.S9S_MB_2U(SCH_1):PAGE227_I173@PURE_QUANTA.SCONN168_ME1016810202011(CHIPS)':
 'PETN5': CDS_PINID='PETN5';
NODE_NAME     J41 A42
 '@S9S_MB_2U_LIB.S9S_MB_2U(SCH_1):PAGE227_I173@PURE_QUANTA.SCONN168_ME1016810202011(CHIPS)':
 'PRSNTB1#': CDS_PINID='\prsntb1#\';
NODE_NAME     J41 B70
 '@S9S_MB_2U_LIB.S9S_MB_2U(SCH_1):PAGE227_I173@PURE_QUANTA.SCONN168_ME1016810202011(CHIPS)':
 'PRSNTB3#': CDS_PINID='\prsntb3#\';
NODE_NAME     J41 A70
 '@S9S_MB_2U_LIB.S9S_MB_2U(SCH_1):PAGE227_I173@PURE_QUANTA.SCONN168_ME1016810202011(CHIPS)':
 'PWRBRK0#': CDS_PINID='\pwrbrk0#\';
NODE_NAME     J41 OA4
 '@S9S_MB_2U_LIB.S9S_MB_2U(SCH_1):PAGE227_I173@PURE_QUANTA.SCONN168_ME1016810202011(CHIPS)':
 'RBT_ARB_IN': CDS_PINID='RBT_ARB_IN';
NODE_NAME     J41 OB7
 '@S9S_MB_2U_LIB.S9S_MB_2U(SCH_1):PAGE227_I173@PURE_QUANTA.SCONN168_ME1016810202011(CHIPS)':
 'SLOT_ID0': CDS_PINID='SLOT_ID0';
NODE_NAME     J41 OA3
 '@S9S_MB_2U_LIB.S9S_MB_2U(SCH_1):PAGE227_I173@PURE_QUANTA.SCONN168_ME1016810202011(CHIPS)':
 'WAKE#': CDS_PINID='\wake#\';
NODE_NAME     U247 10
 '@S9S_MB_2U_LIB.S9S_MB_2U(SCH_1):PAGE201_I167@PURE_QUANTA.9FGL0251DKILFT(CHIPS)':
 'GND_10': CDS_PINID='GND_10';
NODE_NAME     U247 21
 '@S9S_MB_2U_LIB.S9S_MB_2U(SCH_1):PAGE201_I167@PURE_QUANTA.9FGL0251DKILFT(CHIPS)':
 'GND_21': CDS_PINID='GND_21';
NODE_NAME     U247 15
 '@S9S_MB_2U_LIB.S9S_MB_2U(SCH_1):PAGE201_I167@PURE_QUANTA.9FGL0251DKILFT(CHIPS)':
 'GNDA': CDS_PINID='GNDA';
NODE_NAME     U247 6
 '@S9S_MB_2U_LIB.S9S_MB_2U(SCH_1):PAGE201_I167@PURE_QUANTA.9FGL0251DKILFT(CHIPS)':
 'GNDDIG': CDS_PINID='GNDDIG';
NODE_NAME     U247 5
 '@S9S_MB_2U_LIB.S9S_MB_2U(SCH_1):PAGE201_I167@PURE_QUANTA.9FGL0251DKILFT(CHIPS)':
 'GNDREF': CDS_PINID='GNDREF';
NODE_NAME     U247 24
 '@S9S_MB_2U_LIB.S9S_MB_2U(SCH_1):PAGE201_I167@PURE_QUANTA.9FGL0251DKILFT(CHIPS)':
 'GNDXTAL': CDS_PINID='GNDXTAL';
NODE_NAME     U247 25
 '@S9S_MB_2U_LIB.S9S_MB_2U(SCH_1):PAGE201_I167@PURE_QUANTA.9FGL0251DKILFT(CHIPS)':
 'TH_GND': CDS_PINID='TH_GND';
NET_NAME
'GPU_3V3IO_RSVD0_FFU'
 '@S9S_MB_2U_LIB.S9S_MB_2U(SCH_1):GPU_3V3IO_RSVD0_FFU':
 C_SIGNAL='@s9s_mb_2u_lib.s9s_mb_2u(sch_1):gpu_3v3io_rsvd0_ffu';
NODE_NAME     J109 N4
 '@S9S_MB_2U_LIB.S9S_MB_2U(SCH_1):PAGE319_I53@PURE_QUANTA.CONN112_10137002101LF(CHIPS)':
 'N4': CDS_PINID='N4';
NODE_NAME     Q128 2
 '@S9S_MB_2U_LIB.S9S_MB_2U(SCH_1):PAGE143_I11@PURE_QUANTA.MOSFET_NCH_DUAL(CHIPS)':
 'G1': CDS_PINID='G1';
NODE_NAME     R4119 2
 '@S9S_MB_2U_LIB.S9S_MB_2U(SCH_1):PAGE143_I13@PURE_QUANTA.Q_RES(CHIPS)':
 'B': CDS_PINID='B';
NODE_NAME     R4120 1
 '@S9S_MB_2U_LIB.S9S_MB_2U(SCH_1):PAGE143_I14@PURE_QUANTA.Q_RES(CHIPS)':
 'A': CDS_PINID='A';
NODE_NAME     R4575 1
 '@S9S_MB_2U_LIB.S9S_MB_2U(SCH_1):PAGE143_I142@PURE_QUANTA.Q_RES(CHIPS)':
 'A': CDS_PINID='A';
NET_NAME
'GPU_3V3IO_RSVD0_FFU_ISO'
 '@S9S_MB_2U_LIB.S9S_MB_2U(SCH_1):GPU_3V3IO_RSVD0_FFU_ISO':
 C_SIGNAL='@s9s_mb_2u_lib.s9s_mb_2u(sch_1):gpu_3v3io_rsvd0_ffu_iso';
NODE_NAME     C2264 1
 '@S9S_MB_2U_LIB.S9S_MB_2U(SCH_1):PAGE143_I2@PURE_QUANTA.Q_CAP(CHIPS)':
 'A': CDS_PINID='A';
NODE_NAME     R4128 2
 '@S9S_MB_2U_LIB.S9S_MB_2U(SCH_1):PAGE143_I5@PURE_QUANTA.Q_RES(CHIPS)':
 'B': CDS_PINID='B';
NODE_NAME     Q128 3
 '@S9S_MB_2U_LIB.S9S_MB_2U(SCH_1):PAGE143_I6@PURE_QUANTA.MOSFET_NCH_DUAL(CHIPS)':
 'D2': CDS_PINID='D2';
NODE_NAME     R4143 1
 '@S9S_MB_2U_LIB.S9S_MB_2U(SCH_1):PAGE312_I89@PURE_QUANTA.Q_RES(CHIPS)':
 'A': CDS_PINID='A';
NODE_NAME     R4575 2
 '@S9S_MB_2U_LIB.S9S_MB_2U(SCH_1):PAGE143_I142@PURE_QUANTA.Q_RES(CHIPS)':
 'B': CDS_PINID='B';
NET_NAME
'GPU_3V3IO_RSVD0_FFU_ISO_R'
 '@S9S_MB_2U_LIB.S9S_MB_2U(SCH_1):GPU_3V3IO_RSVD0_FFU_ISO_R':
 C_SIGNAL='@s9s_mb_2u_lib.s9s_mb_2u(sch_1):gpu_3v3io_rsvd0_ffu_iso_r';
NODE_NAME     U249 T11
 '@S9S_MB_2U_LIB.S9S_MB_2U(SCH_1):PAGE312_I1@PURE_QUANTA.LCMXO3LF9400C5BG484C(CHIPS)':
 'PB22C': CDS_PINID='PB22C';
NODE_NAME     R4143 2
 '@S9S_MB_2U_LIB.S9S_MB_2U(SCH_1):PAGE312_I89@PURE_QUANTA.Q_RES(CHIPS)':
 'B': CDS_PINID='B';
NET_NAME
'GPU_3V3IO_RSVD0_FFU_N'
 '@S9S_MB_2U_LIB.S9S_MB_2U(SCH_1):GPU_3V3IO_RSVD0_FFU_N':
 C_SIGNAL='@s9s_mb_2u_lib.s9s_mb_2u(sch_1):gpu_3v3io_rsvd0_ffu_n';
NODE_NAME     Q128 5
 '@S9S_MB_2U_LIB.S9S_MB_2U(SCH_1):PAGE143_I6@PURE_QUANTA.MOSFET_NCH_DUAL(CHIPS)':
 'G2': CDS_PINID='G2';
NODE_NAME     R4125 2
 '@S9S_MB_2U_LIB.S9S_MB_2U(SCH_1):PAGE143_I9@PURE_QUANTA.Q_RES(CHIPS)':
 'B': CDS_PINID='B';
NODE_NAME     Q128 6
 '@S9S_MB_2U_LIB.S9S_MB_2U(SCH_1):PAGE143_I11@PURE_QUANTA.MOSFET_NCH_DUAL(CHIPS)':
 'D1': CDS_PINID='D1';
NET_NAME
'GPU_3V3IO_RSVD1'
 '@S9S_MB_2U_LIB.S9S_MB_2U(SCH_1):GPU_3V3IO_RSVD1':
 C_SIGNAL='@s9s_mb_2u_lib.s9s_mb_2u(sch_1):gpu_3v3io_rsvd1';
NODE_NAME     J105 A7
 '@S9S_MB_2U_LIB.S9S_MB_2U(SCH_1):PAGE142_I68@PURE_QUANTA.CONN112_10137002101LF(CHIPS)':
 'A7': CDS_PINID='A7';
NODE_NAME     R4159 1
 '@S9S_MB_2U_LIB.S9S_MB_2U(SCH_1):PAGE139_I13@PURE_QUANTA.Q_RES(CHIPS)':
 'A': CDS_PINID='A';
NODE_NAME     R4158 2
 '@S9S_MB_2U_LIB.S9S_MB_2U(SCH_1):PAGE139_I14@PURE_QUANTA.Q_RES(CHIPS)':
 'B': CDS_PINID='B';
NODE_NAME     Q135 2
 '@S9S_MB_2U_LIB.S9S_MB_2U(SCH_1):PAGE139_I25@PURE_QUANTA.MOSFET_NCH_DUAL(CHIPS)':
 'G1': CDS_PINID='G1';
NODE_NAME     R4569 1
 '@S9S_MB_2U_LIB.S9S_MB_2U(SCH_1):PAGE139_I107@PURE_QUANTA.Q_RES(CHIPS)':
 'A': CDS_PINID='A';
NET_NAME
'GPU_3V3IO_RSVD1_FFU'
 '@S9S_MB_2U_LIB.S9S_MB_2U(SCH_1):GPU_3V3IO_RSVD1_FFU':
 C_SIGNAL='@s9s_mb_2u_lib.s9s_mb_2u(sch_1):gpu_3v3io_rsvd1_ffu';
NODE_NAME     J109 N6
 '@S9S_MB_2U_LIB.S9S_MB_2U(SCH_1):PAGE319_I76@PURE_QUANTA.CONN112_10137002101LF(CHIPS)':
 'N6': CDS_PINID='N6';
NODE_NAME     Q131 2
 '@S9S_MB_2U_LIB.S9S_MB_2U(SCH_1):PAGE143_I29@PURE_QUANTA.MOSFET_NCH_DUAL(CHIPS)':
 'G1': CDS_PINID='G1';
NODE_NAME     R4123 2
 '@S9S_MB_2U_LIB.S9S_MB_2U(SCH_1):PAGE143_I31@PURE_QUANTA.Q_RES(CHIPS)':
 'B': CDS_PINID='B';
NODE_NAME     R4124 1
 '@S9S_MB_2U_LIB.S9S_MB_2U(SCH_1):PAGE143_I32@PURE_QUANTA.Q_RES(CHIPS)':
 'A': CDS_PINID='A';
NODE_NAME     R4572 1
 '@S9S_MB_2U_LIB.S9S_MB_2U(SCH_1):PAGE143_I141@PURE_QUANTA.Q_RES(CHIPS)':
 'A': CDS_PINID='A';
NET_NAME
'GPU_3V3IO_RSVD1_FFU_ISO'
 '@S9S_MB_2U_LIB.S9S_MB_2U(SCH_1):GPU_3V3IO_RSVD1_FFU_ISO':
 C_SIGNAL='@s9s_mb_2u_lib.s9s_mb_2u(sch_1):gpu_3v3io_rsvd1_ffu_iso';
NODE_NAME     Q131 3
 '@S9S_MB_2U_LIB.S9S_MB_2U(SCH_1):PAGE143_I19@PURE_QUANTA.MOSFET_NCH_DUAL(CHIPS)':
 'D2': CDS_PINID='D2';
NODE_NAME     R4130 2
 '@S9S_MB_2U_LIB.S9S_MB_2U(SCH_1):PAGE143_I21@PURE_QUANTA.Q_RES(CHIPS)':
 'B': CDS_PINID='B';
NODE_NAME     C2266 1
 '@S9S_MB_2U_LIB.S9S_MB_2U(SCH_1):PAGE143_I23@PURE_QUANTA.Q_CAP(CHIPS)':
 'A': CDS_PINID='A';
NODE_NAME     R4144 1
 '@S9S_MB_2U_LIB.S9S_MB_2U(SCH_1):PAGE312_I93@PURE_QUANTA.Q_RES(CHIPS)':
 'A': CDS_PINID='A';
NODE_NAME     R4572 2
 '@S9S_MB_2U_LIB.S9S_MB_2U(SCH_1):PAGE143_I141@PURE_QUANTA.Q_RES(CHIPS)':
 'B': CDS_PINID='B';
NET_NAME
'GPU_3V3IO_RSVD1_FFU_ISO_R'
 '@S9S_MB_2U_LIB.S9S_MB_2U(SCH_1):GPU_3V3IO_RSVD1_FFU_ISO_R':
 C_SIGNAL='@s9s_mb_2u_lib.s9s_mb_2u(sch_1):gpu_3v3io_rsvd1_ffu_iso_r';
NODE_NAME     U249 U11
 '@S9S_MB_2U_LIB.S9S_MB_2U(SCH_1):PAGE312_I1@PURE_QUANTA.LCMXO3LF9400C5BG484C(CHIPS)':
 'PB22D': CDS_PINID='PB22D';
NODE_NAME     R4144 2
 '@S9S_MB_2U_LIB.S9S_MB_2U(SCH_1):PAGE312_I93@PURE_QUANTA.Q_RES(CHIPS)':
 'B': CDS_PINID='B';
NET_NAME
'GPU_3V3IO_RSVD1_FFU_N'
 '@S9S_MB_2U_LIB.S9S_MB_2U(SCH_1):GPU_3V3IO_RSVD1_FFU_N':
 C_SIGNAL='@s9s_mb_2u_lib.s9s_mb_2u(sch_1):gpu_3v3io_rsvd1_ffu_n';
NODE_NAME     Q131 5
 '@S9S_MB_2U_LIB.S9S_MB_2U(SCH_1):PAGE143_I19@PURE_QUANTA.MOSFET_NCH_DUAL(CHIPS)':
 'G2': CDS_PINID='G2';
NODE_NAME     R4127 2
 '@S9S_MB_2U_LIB.S9S_MB_2U(SCH_1):PAGE143_I27@PURE_QUANTA.Q_RES(CHIPS)':
 'B': CDS_PINID='B';
NODE_NAME     Q131 6
 '@S9S_MB_2U_LIB.S9S_MB_2U(SCH_1):PAGE143_I29@PURE_QUANTA.MOSFET_NCH_DUAL(CHIPS)':
 'D1': CDS_PINID='D1';
NET_NAME
'GPU_3V3IO_RSVD1_ISO'
 '@S9S_MB_2U_LIB.S9S_MB_2U(SCH_1):GPU_3V3IO_RSVD1_ISO':
 C_SIGNAL='@s9s_mb_2u_lib.s9s_mb_2u(sch_1):gpu_3v3io_rsvd1_iso';
NODE_NAME     Q135 3
 '@S9S_MB_2U_LIB.S9S_MB_2U(SCH_1):PAGE139_I29@PURE_QUANTA.MOSFET_NCH_DUAL(CHIPS)':
 'D2': CDS_PINID='D2';
NODE_NAME     C2271 1
 '@S9S_MB_2U_LIB.S9S_MB_2U(SCH_1):PAGE139_I44@PURE_QUANTA.Q_CAP(CHIPS)':
 'A': CDS_PINID='A';
NODE_NAME     R4167 2
 '@S9S_MB_2U_LIB.S9S_MB_2U(SCH_1):PAGE139_I47@PURE_QUANTA.Q_RES(CHIPS)':
 'B': CDS_PINID='B';
NODE_NAME     R4170 1
 '@S9S_MB_2U_LIB.S9S_MB_2U(SCH_1):PAGE312_I120@PURE_QUANTA.Q_RES(CHIPS)':
 'A': CDS_PINID='A';
NODE_NAME     R4569 2
 '@S9S_MB_2U_LIB.S9S_MB_2U(SCH_1):PAGE139_I107@PURE_QUANTA.Q_RES(CHIPS)':
 'B': CDS_PINID='B';
NET_NAME
'GPU_3V3IO_RSVD1_ISO_R'
 '@S9S_MB_2U_LIB.S9S_MB_2U(SCH_1):GPU_3V3IO_RSVD1_ISO_R':
 C_SIGNAL='@s9s_mb_2u_lib.s9s_mb_2u(sch_1):gpu_3v3io_rsvd1_iso_r';
NODE_NAME     U249 T12
 '@S9S_MB_2U_LIB.S9S_MB_2U(SCH_1):PAGE312_I1@PURE_QUANTA.LCMXO3LF9400C5BG484C(CHIPS)':
 'PB27B': CDS_PINID='PB27B';
NODE_NAME     R4170 2
 '@S9S_MB_2U_LIB.S9S_MB_2U(SCH_1):PAGE312_I120@PURE_QUANTA.Q_RES(CHIPS)':
 'B': CDS_PINID='B';
NET_NAME
'GPU_3V3IO_RSVD1_N'
 '@S9S_MB_2U_LIB.S9S_MB_2U(SCH_1):GPU_3V3IO_RSVD1_N':
 C_SIGNAL='@s9s_mb_2u_lib.s9s_mb_2u(sch_1):gpu_3v3io_rsvd1_n';
NODE_NAME     Q135 6
 '@S9S_MB_2U_LIB.S9S_MB_2U(SCH_1):PAGE139_I25@PURE_QUANTA.MOSFET_NCH_DUAL(CHIPS)':
 'D1': CDS_PINID='D1';
NODE_NAME     R4164 2
 '@S9S_MB_2U_LIB.S9S_MB_2U(SCH_1):PAGE139_I27@PURE_QUANTA.Q_RES(CHIPS)':
 'B': CDS_PINID='B';
NODE_NAME     Q135 5
 '@S9S_MB_2U_LIB.S9S_MB_2U(SCH_1):PAGE139_I29@PURE_QUANTA.MOSFET_NCH_DUAL(CHIPS)':
 'G2': CDS_PINID='G2';
NET_NAME
'GPU_3V3IO_RSVD3'
 '@S9S_MB_2U_LIB.S9S_MB_2U(SCH_1):GPU_3V3IO_RSVD3':
 C_SIGNAL='@s9s_mb_2u_lib.s9s_mb_2u(sch_1):gpu_3v3io_rsvd3';
NODE_NAME     J105 A5
 '@S9S_MB_2U_LIB.S9S_MB_2U(SCH_1):PAGE142_I68@PURE_QUANTA.CONN112_10137002101LF(CHIPS)':
 'A5': CDS_PINID='A5';
NODE_NAME     R4163 1
 '@S9S_MB_2U_LIB.S9S_MB_2U(SCH_1):PAGE139_I8@PURE_QUANTA.Q_RES(CHIPS)':
 'A': CDS_PINID='A';
NODE_NAME     R4162 2
 '@S9S_MB_2U_LIB.S9S_MB_2U(SCH_1):PAGE139_I9@PURE_QUANTA.Q_RES(CHIPS)':
 'B': CDS_PINID='B';
NODE_NAME     Q137 2
 '@S9S_MB_2U_LIB.S9S_MB_2U(SCH_1):PAGE139_I21@PURE_QUANTA.MOSFET_NCH_DUAL(CHIPS)':
 'G1': CDS_PINID='G1';
NODE_NAME     R4570 1
 '@S9S_MB_2U_LIB.S9S_MB_2U(SCH_1):PAGE139_I109@PURE_QUANTA.Q_RES(CHIPS)':
 'A': CDS_PINID='A';
NET_NAME
'GPU_3V3IO_RSVD3_FFU'
 '@S9S_MB_2U_LIB.S9S_MB_2U(SCH_1):GPU_3V3IO_RSVD3_FFU':
 C_SIGNAL='@s9s_mb_2u_lib.s9s_mb_2u(sch_1):gpu_3v3io_rsvd3_ffu';
NODE_NAME     J108 A1
 '@S9S_MB_2U_LIB.S9S_MB_2U(SCH_1):PAGE320_I57@PURE_QUANTA.CONN112_10137002101LF(CHIPS)':
 'A1': CDS_PINID='A1';
NODE_NAME     Q130 2
 '@S9S_MB_2U_LIB.S9S_MB_2U(SCH_1):PAGE143_I74@PURE_QUANTA.MOSFET_NCH_DUAL(CHIPS)':
 'G1': CDS_PINID='G1';
NODE_NAME     R4131 2
 '@S9S_MB_2U_LIB.S9S_MB_2U(SCH_1):PAGE143_I85@PURE_QUANTA.Q_RES(CHIPS)':
 'B': CDS_PINID='B';
NODE_NAME     R4132 1
 '@S9S_MB_2U_LIB.S9S_MB_2U(SCH_1):PAGE143_I86@PURE_QUANTA.Q_RES(CHIPS)':
 'A': CDS_PINID='A';
NODE_NAME     R4577 1
 '@S9S_MB_2U_LIB.S9S_MB_2U(SCH_1):PAGE143_I137@PURE_QUANTA.Q_RES(CHIPS)':
 'A': CDS_PINID='A';
NET_NAME
'GPU_3V3IO_RSVD3_FFU_ISO'
 '@S9S_MB_2U_LIB.S9S_MB_2U(SCH_1):GPU_3V3IO_RSVD3_FFU_ISO':
 C_SIGNAL='@s9s_mb_2u_lib.s9s_mb_2u(sch_1):gpu_3v3io_rsvd3_ffu_iso';
NODE_NAME     R4140 2
 '@S9S_MB_2U_LIB.S9S_MB_2U(SCH_1):PAGE143_I52@PURE_QUANTA.Q_RES(CHIPS)':
 'B': CDS_PINID='B';
NODE_NAME     C2267 1
 '@S9S_MB_2U_LIB.S9S_MB_2U(SCH_1):PAGE143_I55@PURE_QUANTA.Q_CAP(CHIPS)':
 'A': CDS_PINID='A';
NODE_NAME     Q130 3
 '@S9S_MB_2U_LIB.S9S_MB_2U(SCH_1):PAGE143_I70@PURE_QUANTA.MOSFET_NCH_DUAL(CHIPS)':
 'D2': CDS_PINID='D2';
NODE_NAME     R4146 1
 '@S9S_MB_2U_LIB.S9S_MB_2U(SCH_1):PAGE312_I98@PURE_QUANTA.Q_RES(CHIPS)':
 'A': CDS_PINID='A';
NODE_NAME     R4577 2
 '@S9S_MB_2U_LIB.S9S_MB_2U(SCH_1):PAGE143_I137@PURE_QUANTA.Q_RES(CHIPS)':
 'B': CDS_PINID='B';
NET_NAME
'GPU_3V3IO_RSVD3_FFU_ISO_R'
 '@S9S_MB_2U_LIB.S9S_MB_2U(SCH_1):GPU_3V3IO_RSVD3_FFU_ISO_R':
 C_SIGNAL='@s9s_mb_2u_lib.s9s_mb_2u(sch_1):gpu_3v3io_rsvd3_ffu_iso_r';
NODE_NAME     U249 AB11
 '@S9S_MB_2U_LIB.S9S_MB_2U(SCH_1):PAGE312_I1@PURE_QUANTA.LCMXO3LF9400C5BG484C(CHIPS)':
 'PB24B': CDS_PINID='PB24B';
NODE_NAME     R4146 2
 '@S9S_MB_2U_LIB.S9S_MB_2U(SCH_1):PAGE312_I98@PURE_QUANTA.Q_RES(CHIPS)':
 'B': CDS_PINID='B';
NET_NAME
'GPU_3V3IO_RSVD3_FFU_N'
 '@S9S_MB_2U_LIB.S9S_MB_2U(SCH_1):GPU_3V3IO_RSVD3_FFU_N':
 C_SIGNAL='@s9s_mb_2u_lib.s9s_mb_2u(sch_1):gpu_3v3io_rsvd3_ffu_n';
NODE_NAME     Q130 5
 '@S9S_MB_2U_LIB.S9S_MB_2U(SCH_1):PAGE143_I70@PURE_QUANTA.MOSFET_NCH_DUAL(CHIPS)':
 'G2': CDS_PINID='G2';
NODE_NAME     R4137 2
 '@S9S_MB_2U_LIB.S9S_MB_2U(SCH_1):PAGE143_I72@PURE_QUANTA.Q_RES(CHIPS)':
 'B': CDS_PINID='B';
NODE_NAME     Q130 6
 '@S9S_MB_2U_LIB.S9S_MB_2U(SCH_1):PAGE143_I74@PURE_QUANTA.MOSFET_NCH_DUAL(CHIPS)':
 'D1': CDS_PINID='D1';
NET_NAME
'GPU_3V3IO_RSVD3_ISO'
 '@S9S_MB_2U_LIB.S9S_MB_2U(SCH_1):GPU_3V3IO_RSVD3_ISO':
 C_SIGNAL='@s9s_mb_2u_lib.s9s_mb_2u(sch_1):gpu_3v3io_rsvd3_iso';
NODE_NAME     Q137 3
 '@S9S_MB_2U_LIB.S9S_MB_2U(SCH_1):PAGE139_I28@PURE_QUANTA.MOSFET_NCH_DUAL(CHIPS)':
 'D2': CDS_PINID='D2';
NODE_NAME     R4169 2
 '@S9S_MB_2U_LIB.S9S_MB_2U(SCH_1):PAGE139_I39@PURE_QUANTA.Q_RES(CHIPS)':
 'B': CDS_PINID='B';
NODE_NAME     C2273 1
 '@S9S_MB_2U_LIB.S9S_MB_2U(SCH_1):PAGE139_I42@PURE_QUANTA.Q_CAP(CHIPS)':
 'A': CDS_PINID='A';
NODE_NAME     R4171 1
 '@S9S_MB_2U_LIB.S9S_MB_2U(SCH_1):PAGE312_I121@PURE_QUANTA.Q_RES(CHIPS)':
 'A': CDS_PINID='A';
NODE_NAME     R4570 2
 '@S9S_MB_2U_LIB.S9S_MB_2U(SCH_1):PAGE139_I109@PURE_QUANTA.Q_RES(CHIPS)':
 'B': CDS_PINID='B';
NET_NAME
'GPU_3V3IO_RSVD3_ISO_R'
 '@S9S_MB_2U_LIB.S9S_MB_2U(SCH_1):GPU_3V3IO_RSVD3_ISO_R':
 C_SIGNAL='@s9s_mb_2u_lib.s9s_mb_2u(sch_1):gpu_3v3io_rsvd3_iso_r';
NODE_NAME     U249 U12
 '@S9S_MB_2U_LIB.S9S_MB_2U(SCH_1):PAGE312_I1@PURE_QUANTA.LCMXO3LF9400C5BG484C(CHIPS)':
 'PB27C': CDS_PINID='PB27C';
NODE_NAME     R4171 2
 '@S9S_MB_2U_LIB.S9S_MB_2U(SCH_1):PAGE312_I121@PURE_QUANTA.Q_RES(CHIPS)':
 'B': CDS_PINID='B';
NET_NAME
'GPU_3V3IO_RSVD3_N'
 '@S9S_MB_2U_LIB.S9S_MB_2U(SCH_1):GPU_3V3IO_RSVD3_N':
 C_SIGNAL='@s9s_mb_2u_lib.s9s_mb_2u(sch_1):gpu_3v3io_rsvd3_n';
NODE_NAME     Q137 6
 '@S9S_MB_2U_LIB.S9S_MB_2U(SCH_1):PAGE139_I21@PURE_QUANTA.MOSFET_NCH_DUAL(CHIPS)':
 'D1': CDS_PINID='D1';
NODE_NAME     R4166 2
 '@S9S_MB_2U_LIB.S9S_MB_2U(SCH_1):PAGE139_I23@PURE_QUANTA.Q_RES(CHIPS)':
 'B': CDS_PINID='B';
NODE_NAME     Q137 5
 '@S9S_MB_2U_LIB.S9S_MB_2U(SCH_1):PAGE139_I28@PURE_QUANTA.MOSFET_NCH_DUAL(CHIPS)':
 'G2': CDS_PINID='G2';
NET_NAME
'GPU_3V3IO_RSVD4'
 '@S9S_MB_2U_LIB.S9S_MB_2U(SCH_1):GPU_3V3IO_RSVD4':
 C_SIGNAL='@s9s_mb_2u_lib.s9s_mb_2u(sch_1):gpu_3v3io_rsvd4';
NODE_NAME     J105 A1
 '@S9S_MB_2U_LIB.S9S_MB_2U(SCH_1):PAGE142_I65@PURE_QUANTA.CONN112_10137002101LF(CHIPS)':
 'A1': CDS_PINID='A1';
NODE_NAME     R4161 1
 '@S9S_MB_2U_LIB.S9S_MB_2U(SCH_1):PAGE139_I2@PURE_QUANTA.Q_RES(CHIPS)':
 'A': CDS_PINID='A';
NODE_NAME     R4160 2
 '@S9S_MB_2U_LIB.S9S_MB_2U(SCH_1):PAGE139_I4@PURE_QUANTA.Q_RES(CHIPS)':
 'B': CDS_PINID='B';
NODE_NAME     Q136 2
 '@S9S_MB_2U_LIB.S9S_MB_2U(SCH_1):PAGE139_I17@PURE_QUANTA.MOSFET_NCH_DUAL(CHIPS)':
 'G1': CDS_PINID='G1';
NODE_NAME     R4571 1
 '@S9S_MB_2U_LIB.S9S_MB_2U(SCH_1):PAGE139_I108@PURE_QUANTA.Q_RES(CHIPS)':
 'A': CDS_PINID='A';
NET_NAME
'GPU_3V3IO_RSVD4_ISO'
 '@S9S_MB_2U_LIB.S9S_MB_2U(SCH_1):GPU_3V3IO_RSVD4_ISO':
 C_SIGNAL='@s9s_mb_2u_lib.s9s_mb_2u(sch_1):gpu_3v3io_rsvd4_iso';
NODE_NAME     Q136 3
 '@S9S_MB_2U_LIB.S9S_MB_2U(SCH_1):PAGE139_I22@PURE_QUANTA.MOSFET_NCH_DUAL(CHIPS)':
 'D2': CDS_PINID='D2';
NODE_NAME     C2272 1
 '@S9S_MB_2U_LIB.S9S_MB_2U(SCH_1):PAGE139_I33@PURE_QUANTA.Q_CAP(CHIPS)':
 'A': CDS_PINID='A';
NODE_NAME     R4168 2
 '@S9S_MB_2U_LIB.S9S_MB_2U(SCH_1):PAGE139_I35@PURE_QUANTA.Q_RES(CHIPS)':
 'B': CDS_PINID='B';
NODE_NAME     R4172 1
 '@S9S_MB_2U_LIB.S9S_MB_2U(SCH_1):PAGE312_I122@PURE_QUANTA.Q_RES(CHIPS)':
 'A': CDS_PINID='A';
NODE_NAME     R4571 2
 '@S9S_MB_2U_LIB.S9S_MB_2U(SCH_1):PAGE139_I108@PURE_QUANTA.Q_RES(CHIPS)':
 'B': CDS_PINID='B';
NET_NAME
'GPU_3V3IO_RSVD4_ISO_R'
 '@S9S_MB_2U_LIB.S9S_MB_2U(SCH_1):GPU_3V3IO_RSVD4_ISO_R':
 C_SIGNAL='@s9s_mb_2u_lib.s9s_mb_2u(sch_1):gpu_3v3io_rsvd4_iso_r';
NODE_NAME     U249 V12
 '@S9S_MB_2U_LIB.S9S_MB_2U(SCH_1):PAGE312_I1@PURE_QUANTA.LCMXO3LF9400C5BG484C(CHIPS)':
 'PB27D': CDS_PINID='PB27D';
NODE_NAME     R4172 2
 '@S9S_MB_2U_LIB.S9S_MB_2U(SCH_1):PAGE312_I122@PURE_QUANTA.Q_RES(CHIPS)':
 'B': CDS_PINID='B';
NET_NAME
'GPU_3V3IO_RSVD4_N'
 '@S9S_MB_2U_LIB.S9S_MB_2U(SCH_1):GPU_3V3IO_RSVD4_N':
 C_SIGNAL='@s9s_mb_2u_lib.s9s_mb_2u(sch_1):gpu_3v3io_rsvd4_n';
NODE_NAME     Q136 6
 '@S9S_MB_2U_LIB.S9S_MB_2U(SCH_1):PAGE139_I17@PURE_QUANTA.MOSFET_NCH_DUAL(CHIPS)':
 'D1': CDS_PINID='D1';
NODE_NAME     R4165 2
 '@S9S_MB_2U_LIB.S9S_MB_2U(SCH_1):PAGE139_I18@PURE_QUANTA.Q_RES(CHIPS)':
 'B': CDS_PINID='B';
NODE_NAME     Q136 5
 '@S9S_MB_2U_LIB.S9S_MB_2U(SCH_1):PAGE139_I22@PURE_QUANTA.MOSFET_NCH_DUAL(CHIPS)':
 'G2': CDS_PINID='G2';
NET_NAME
'GPU_3V3IO_RSVD5_FFU'
 '@S9S_MB_2U_LIB.S9S_MB_2U(SCH_1):GPU_3V3IO_RSVD5_FFU':
 C_SIGNAL='@s9s_mb_2u_lib.s9s_mb_2u(sch_1):gpu_3v3io_rsvd5_ffu';
NODE_NAME     J108 A5
 '@S9S_MB_2U_LIB.S9S_MB_2U(SCH_1):PAGE320_I76@PURE_QUANTA.CONN112_10137002101LF(CHIPS)':
 'A5': CDS_PINID='A5';
NODE_NAME     Q129 2
 '@S9S_MB_2U_LIB.S9S_MB_2U(SCH_1):PAGE143_I83@PURE_QUANTA.MOSFET_NCH_DUAL(CHIPS)':
 'G1': CDS_PINID='G1';
NODE_NAME     R4133 2
 '@S9S_MB_2U_LIB.S9S_MB_2U(SCH_1):PAGE143_I95@PURE_QUANTA.Q_RES(CHIPS)':
 'B': CDS_PINID='B';
NODE_NAME     R4134 1
 '@S9S_MB_2U_LIB.S9S_MB_2U(SCH_1):PAGE143_I96@PURE_QUANTA.Q_RES(CHIPS)':
 'A': CDS_PINID='A';
NODE_NAME     R4576 1
 '@S9S_MB_2U_LIB.S9S_MB_2U(SCH_1):PAGE143_I139@PURE_QUANTA.Q_RES(CHIPS)':
 'A': CDS_PINID='A';
NET_NAME
'GPU_3V3IO_RSVD5_FFU_ISO'
 '@S9S_MB_2U_LIB.S9S_MB_2U(SCH_1):GPU_3V3IO_RSVD5_FFU_ISO':
 C_SIGNAL='@s9s_mb_2u_lib.s9s_mb_2u(sch_1):gpu_3v3io_rsvd5_ffu_iso';
NODE_NAME     R4141 2
 '@S9S_MB_2U_LIB.S9S_MB_2U(SCH_1):PAGE143_I64@PURE_QUANTA.Q_RES(CHIPS)':
 'B': CDS_PINID='B';
NODE_NAME     C2268 1
 '@S9S_MB_2U_LIB.S9S_MB_2U(SCH_1):PAGE143_I66@PURE_QUANTA.Q_CAP(CHIPS)':
 'A': CDS_PINID='A';
NODE_NAME     Q129 3
 '@S9S_MB_2U_LIB.S9S_MB_2U(SCH_1):PAGE143_I77@PURE_QUANTA.MOSFET_NCH_DUAL(CHIPS)':
 'D2': CDS_PINID='D2';
NODE_NAME     R4148 1
 '@S9S_MB_2U_LIB.S9S_MB_2U(SCH_1):PAGE312_I103@PURE_QUANTA.Q_RES(CHIPS)':
 'A': CDS_PINID='A';
NODE_NAME     R4576 2
 '@S9S_MB_2U_LIB.S9S_MB_2U(SCH_1):PAGE143_I139@PURE_QUANTA.Q_RES(CHIPS)':
 'B': CDS_PINID='B';
NET_NAME
'GPU_3V3IO_RSVD5_FFU_ISO_R'
 '@S9S_MB_2U_LIB.S9S_MB_2U(SCH_1):GPU_3V3IO_RSVD5_FFU_ISO_R':
 C_SIGNAL='@s9s_mb_2u_lib.s9s_mb_2u(sch_1):gpu_3v3io_rsvd5_ffu_iso_r';
NODE_NAME     U249 Y11
 '@S9S_MB_2U_LIB.S9S_MB_2U(SCH_1):PAGE312_I1@PURE_QUANTA.LCMXO3LF9400C5BG484C(CHIPS)':
 'PB24D': CDS_PINID='PB24D';
NODE_NAME     R4148 2
 '@S9S_MB_2U_LIB.S9S_MB_2U(SCH_1):PAGE312_I103@PURE_QUANTA.Q_RES(CHIPS)':
 'B': CDS_PINID='B';
NET_NAME
'GPU_3V3IO_RSVD5_FFU_N'
 '@S9S_MB_2U_LIB.S9S_MB_2U(SCH_1):GPU_3V3IO_RSVD5_FFU_N':
 C_SIGNAL='@s9s_mb_2u_lib.s9s_mb_2u(sch_1):gpu_3v3io_rsvd5_ffu_n';
NODE_NAME     Q129 5
 '@S9S_MB_2U_LIB.S9S_MB_2U(SCH_1):PAGE143_I77@PURE_QUANTA.MOSFET_NCH_DUAL(CHIPS)':
 'G2': CDS_PINID='G2';
NODE_NAME     R4138 2
 '@S9S_MB_2U_LIB.S9S_MB_2U(SCH_1):PAGE143_I81@PURE_QUANTA.Q_RES(CHIPS)':
 'B': CDS_PINID='B';
NODE_NAME     Q129 6
 '@S9S_MB_2U_LIB.S9S_MB_2U(SCH_1):PAGE143_I83@PURE_QUANTA.MOSFET_NCH_DUAL(CHIPS)':
 'D1': CDS_PINID='D1';
NET_NAME
'GPU_BASE_HMC_READY'
 '@S9S_MB_2U_LIB.S9S_MB_2U(SCH_1):GPU_BASE_HMC_READY':
 C_SIGNAL='@s9s_mb_2u_lib.s9s_mb_2u(sch_1):gpu_base_hmc_ready';
NODE_NAME     J110 A5
 '@S9S_MB_2U_LIB.S9S_MB_2U(SCH_1):PAGE318_I16@PURE_QUANTA.CONN112_10137002101LF(CHIPS)':
 'A5': CDS_PINID='A5';
NODE_NAME     Q102 2
 '@S9S_MB_2U_LIB.S9S_MB_2U(SCH_1):PAGE299_I40@PURE_QUANTA.MOSFET_NCH_DUAL(CHIPS)':
 'G1': CDS_PINID='G1';
NODE_NAME     R3429 2
 '@S9S_MB_2U_LIB.S9S_MB_2U(SCH_1):PAGE299_I130@PURE_QUANTA.Q_RES(CHIPS)':
 'B': CDS_PINID='B';
NODE_NAME     R3463 1
 '@S9S_MB_2U_LIB.S9S_MB_2U(SCH_1):PAGE299_I131@PURE_QUANTA.Q_RES(CHIPS)':
 'A': CDS_PINID='A';
NET_NAME
'GPU_BASE_HMC_READY_ISO'
 '@S9S_MB_2U_LIB.S9S_MB_2U(SCH_1):GPU_BASE_HMC_READY_ISO':
 C_SIGNAL='@s9s_mb_2u_lib.s9s_mb_2u(sch_1):gpu_base_hmc_ready_iso';
NODE_NAME     Q102 3
 '@S9S_MB_2U_LIB.S9S_MB_2U(SCH_1):PAGE299_I48@PURE_QUANTA.MOSFET_NCH_DUAL(CHIPS)':
 'D2': CDS_PINID='D2';
NODE_NAME     R3438 2
 '@S9S_MB_2U_LIB.S9S_MB_2U(SCH_1):PAGE299_I55@PURE_QUANTA.Q_RES(CHIPS)':
 'B': CDS_PINID='B';
NODE_NAME     C1973 1
 '@S9S_MB_2U_LIB.S9S_MB_2U(SCH_1):PAGE299_I71@PURE_QUANTA.Q_CAP(CHIPS)':
 'A': CDS_PINID='A';
NODE_NAME     R3480 1
 '@S9S_MB_2U_LIB.S9S_MB_2U(SCH_1):PAGE314_I21@PURE_QUANTA.Q_RES(CHIPS)':
 'A': CDS_PINID='A';
NET_NAME
'GPU_BASE_HMC_READY_ISO_R'
 '@S9S_MB_2U_LIB.S9S_MB_2U(SCH_1):GPU_BASE_HMC_READY_ISO_R':
 C_SIGNAL='@s9s_mb_2u_lib.s9s_mb_2u(sch_1):gpu_base_hmc_ready_iso_r';
NODE_NAME     R3480 2
 '@S9S_MB_2U_LIB.S9S_MB_2U(SCH_1):PAGE314_I21@PURE_QUANTA.Q_RES(CHIPS)':
 'B': CDS_PINID='B';
NODE_NAME     U249 F10
 '@S9S_MB_2U_LIB.S9S_MB_2U(SCH_1):PAGE314_I188@PURE_QUANTA.LCMXO3LF9400C5BG484C(CHIPS)':
 'PT22A': CDS_PINID='PT22A';
NET_NAME
'GPU_BASE_HMC_READY_N'
 '@S9S_MB_2U_LIB.S9S_MB_2U(SCH_1):GPU_BASE_HMC_READY_N':
 C_SIGNAL='@s9s_mb_2u_lib.s9s_mb_2u(sch_1):gpu_base_hmc_ready_n';
NODE_NAME     Q102 6
 '@S9S_MB_2U_LIB.S9S_MB_2U(SCH_1):PAGE299_I40@PURE_QUANTA.MOSFET_NCH_DUAL(CHIPS)':
 'D1': CDS_PINID='D1';
NODE_NAME     Q102 5
 '@S9S_MB_2U_LIB.S9S_MB_2U(SCH_1):PAGE299_I48@PURE_QUANTA.MOSFET_NCH_DUAL(CHIPS)':
 'G2': CDS_PINID='G2';
NODE_NAME     R3433 2
 '@S9S_MB_2U_LIB.S9S_MB_2U(SCH_1):PAGE299_I49@PURE_QUANTA.Q_RES(CHIPS)':
 'B': CDS_PINID='B';
NET_NAME
'GPU_BASE_ID0'
 '@S9S_MB_2U_LIB.S9S_MB_2U(SCH_1):GPU_BASE_ID0':
 C_SIGNAL='@s9s_mb_2u_lib.s9s_mb_2u(sch_1):gpu_base_id0';
NODE_NAME     J111 A3
 '@S9S_MB_2U_LIB.S9S_MB_2U(SCH_1):PAGE148_I75@PURE_QUANTA.CONN112_10137002101LF(CHIPS)':
 'A3': CDS_PINID='A3';
NODE_NAME     R3440 1
 '@S9S_MB_2U_LIB.S9S_MB_2U(SCH_1):PAGE147_I8@PURE_QUANTA.Q_RES(CHIPS)':
 'A': CDS_PINID='A';
NODE_NAME     R3516 1
 '@S9S_MB_2U_LIB.S9S_MB_2U(SCH_1):PAGE214_I127@PURE_QUANTA.Q_RES(CHIPS)':
 'A': CDS_PINID='A';
NET_NAME
'GPU_BASE_ID0_R'
 '@S9S_MB_2U_LIB.S9S_MB_2U(SCH_1):GPU_BASE_ID0_R':
 C_SIGNAL='@s9s_mb_2u_lib.s9s_mb_2u(sch_1):gpu_base_id0_r';
NODE_NAME     U181 15
 '@S9S_MB_2U_LIB.S9S_MB_2U(SCH_1):PAGE214_I66@PURE_QUANTA.PCA9539RPW(CHIPS)':
 'IO1_2': CDS_PINID='IO1_2';
NODE_NAME     R3516 2
 '@S9S_MB_2U_LIB.S9S_MB_2U(SCH_1):PAGE214_I127@PURE_QUANTA.Q_RES(CHIPS)':
 'B': CDS_PINID='B';
NET_NAME
'GPU_BASE_ID1'
 '@S9S_MB_2U_LIB.S9S_MB_2U(SCH_1):GPU_BASE_ID1':
 C_SIGNAL='@s9s_mb_2u_lib.s9s_mb_2u(sch_1):gpu_base_id1';
NODE_NAME     J111 N8
 '@S9S_MB_2U_LIB.S9S_MB_2U(SCH_1):PAGE148_I74@PURE_QUANTA.CONN112_10137002101LF(CHIPS)':
 'N8': CDS_PINID='N8';
NODE_NAME     R3499 1
 '@S9S_MB_2U_LIB.S9S_MB_2U(SCH_1):PAGE214_I118@PURE_QUANTA.Q_RES(CHIPS)':
 'A': CDS_PINID='A';
NODE_NAME     R3441 1
 '@S9S_MB_2U_LIB.S9S_MB_2U(SCH_1):PAGE147_I7@PURE_QUANTA.Q_RES(CHIPS)':
 'A': CDS_PINID='A';
NET_NAME
'GPU_BASE_ID1_R'
 '@S9S_MB_2U_LIB.S9S_MB_2U(SCH_1):GPU_BASE_ID1_R':
 C_SIGNAL='@s9s_mb_2u_lib.s9s_mb_2u(sch_1):gpu_base_id1_r';
NODE_NAME     U181 16
 '@S9S_MB_2U_LIB.S9S_MB_2U(SCH_1):PAGE214_I66@PURE_QUANTA.PCA9539RPW(CHIPS)':
 'IO1_3': CDS_PINID='IO1_3';
NODE_NAME     R3499 2
 '@S9S_MB_2U_LIB.S9S_MB_2U(SCH_1):PAGE214_I118@PURE_QUANTA.Q_RES(CHIPS)':
 'B': CDS_PINID='B';
NET_NAME
'GPU_BASE_STBY_EN'
 '@S9S_MB_2U_LIB.S9S_MB_2U(SCH_1):GPU_BASE_STBY_EN':
 C_SIGNAL='@s9s_mb_2u_lib.s9s_mb_2u(sch_1):gpu_base_stby_en';
NODE_NAME     U253 3
 '@S9S_MB_2U_LIB.S9S_MB_2U(SCH_1):PAGE160_I26@PURE_QUANTA.74LVC2G17GW(CHIPS)':
 'A1': CDS_PINID='A1';
NODE_NAME     R3452 1
 '@S9S_MB_2U_LIB.S9S_MB_2U(SCH_1):PAGE160_I95@PURE_QUANTA.Q_RES(CHIPS)':
 'A': CDS_PINID='A';
NODE_NAME     R3451 2
 '@S9S_MB_2U_LIB.S9S_MB_2U(SCH_1):PAGE160_I127@PURE_QUANTA.Q_RES(CHIPS)':
 'B': CDS_PINID='B';
NODE_NAME     R3479 1
 '@S9S_MB_2U_LIB.S9S_MB_2U(SCH_1):PAGE314_I24@PURE_QUANTA.Q_RES(CHIPS)':
 'A': CDS_PINID='A';
NET_NAME
'GPU_BASE_STBY_EN_BUF'
 '@S9S_MB_2U_LIB.S9S_MB_2U(SCH_1):GPU_BASE_STBY_EN_BUF':
 C_SIGNAL='@s9s_mb_2u_lib.s9s_mb_2u(sch_1):gpu_base_stby_en_buf';
NODE_NAME     J110 A7
 '@S9S_MB_2U_LIB.S9S_MB_2U(SCH_1):PAGE318_I16@PURE_QUANTA.CONN112_10137002101LF(CHIPS)':
 'A7': CDS_PINID='A7';
NODE_NAME     R3392 2
 '@S9S_MB_2U_LIB.S9S_MB_2U(SCH_1):PAGE160_I202@PURE_QUANTA.Q_RES(CHIPS)':
 'B': CDS_PINID='B';
NET_NAME
'GPU_BASE_STBY_EN_BUF_R'
 '@S9S_MB_2U_LIB.S9S_MB_2U(SCH_1):GPU_BASE_STBY_EN_BUF_R':
 C_SIGNAL='@s9s_mb_2u_lib.s9s_mb_2u(sch_1):gpu_base_stby_en_buf_r';
NODE_NAME     U253 4
 '@S9S_MB_2U_LIB.S9S_MB_2U(SCH_1):PAGE160_I26@PURE_QUANTA.74LVC2G17GW(CHIPS)':
 'B1': CDS_PINID='B1';
NODE_NAME     R3457 1
 '@S9S_MB_2U_LIB.S9S_MB_2U(SCH_1):PAGE160_I123@PURE_QUANTA.Q_RES(CHIPS)':
 'A': CDS_PINID='A';
NODE_NAME     R3456 2
 '@S9S_MB_2U_LIB.S9S_MB_2U(SCH_1):PAGE160_I124@PURE_QUANTA.Q_RES(CHIPS)':
 'B': CDS_PINID='B';
NODE_NAME     R3392 1
 '@S9S_MB_2U_LIB.S9S_MB_2U(SCH_1):PAGE160_I202@PURE_QUANTA.Q_RES(CHIPS)':
 'A': CDS_PINID='A';
NET_NAME
'GPU_BASE_STBY_EN_R'
 '@S9S_MB_2U_LIB.S9S_MB_2U(SCH_1):GPU_BASE_STBY_EN_R':
 C_SIGNAL='@s9s_mb_2u_lib.s9s_mb_2u(sch_1):gpu_base_stby_en_r';
NODE_NAME     R3479 2
 '@S9S_MB_2U_LIB.S9S_MB_2U(SCH_1):PAGE314_I24@PURE_QUANTA.Q_RES(CHIPS)':
 'B': CDS_PINID='B';
NODE_NAME     U249 G9
 '@S9S_MB_2U_LIB.S9S_MB_2U(SCH_1):PAGE314_I188@PURE_QUANTA.LCMXO3LF9400C5BG484C(CHIPS)':
 'PT21D': CDS_PINID='PT21D';
NET_NAME
'GPU_FPGA_BOOT_EN'
 '@S9S_MB_2U_LIB.S9S_MB_2U(SCH_1):GPU_FPGA_BOOT_EN':
 C_SIGNAL='@s9s_mb_2u_lib.s9s_mb_2u(sch_1):gpu_fpga_boot_en';
NODE_NAME     U253 1
 '@S9S_MB_2U_LIB.S9S_MB_2U(SCH_1):PAGE160_I26@PURE_QUANTA.74LVC2G17GW(CHIPS)':
 'A0': CDS_PINID='A0';
NODE_NAME     R3448 2
 '@S9S_MB_2U_LIB.S9S_MB_2U(SCH_1):PAGE160_I168@PURE_QUANTA.Q_RES(CHIPS)':
 'B': CDS_PINID='B';
NODE_NAME     R3449 1
 '@S9S_MB_2U_LIB.S9S_MB_2U(SCH_1):PAGE160_I170@PURE_QUANTA.Q_RES(CHIPS)':
 'A': CDS_PINID='A';
NODE_NAME     R3482 1
 '@S9S_MB_2U_LIB.S9S_MB_2U(SCH_1):PAGE314_I19@PURE_QUANTA.Q_RES(CHIPS)':
 'A': CDS_PINID='A';
NET_NAME
'GPU_FPGA_BOOT_EN_BUF'
 '@S9S_MB_2U_LIB.S9S_MB_2U(SCH_1):GPU_FPGA_BOOT_EN_BUF':
 C_SIGNAL='@s9s_mb_2u_lib.s9s_mb_2u(sch_1):gpu_fpga_boot_en_buf';
NODE_NAME     J110 N2
 '@S9S_MB_2U_LIB.S9S_MB_2U(SCH_1):PAGE318_I54@PURE_QUANTA.CONN112_10137002101LF(CHIPS)':
 'N2': CDS_PINID='N2';
NODE_NAME     R3390 2
 '@S9S_MB_2U_LIB.S9S_MB_2U(SCH_1):PAGE160_I201@PURE_QUANTA.Q_RES(CHIPS)':
 'B': CDS_PINID='B';
NET_NAME
'GPU_FPGA_BOOT_EN_BUF_R'
 '@S9S_MB_2U_LIB.S9S_MB_2U(SCH_1):GPU_FPGA_BOOT_EN_BUF_R':
 C_SIGNAL='@s9s_mb_2u_lib.s9s_mb_2u(sch_1):gpu_fpga_boot_en_buf_r';
NODE_NAME     U253 6
 '@S9S_MB_2U_LIB.S9S_MB_2U(SCH_1):PAGE160_I26@PURE_QUANTA.74LVC2G17GW(CHIPS)':
 'B0': CDS_PINID='B0';
NODE_NAME     R3453 2
 '@S9S_MB_2U_LIB.S9S_MB_2U(SCH_1):PAGE160_I164@PURE_QUANTA.Q_RES(CHIPS)':
 'B': CDS_PINID='B';
NODE_NAME     R3454 1
 '@S9S_MB_2U_LIB.S9S_MB_2U(SCH_1):PAGE160_I165@PURE_QUANTA.Q_RES(CHIPS)':
 'A': CDS_PINID='A';
NODE_NAME     R3390 1
 '@S9S_MB_2U_LIB.S9S_MB_2U(SCH_1):PAGE160_I201@PURE_QUANTA.Q_RES(CHIPS)':
 'A': CDS_PINID='A';
NET_NAME
'GPU_FPGA_BOOT_EN_R'
 '@S9S_MB_2U_LIB.S9S_MB_2U(SCH_1):GPU_FPGA_BOOT_EN_R':
 C_SIGNAL='@s9s_mb_2u_lib.s9s_mb_2u(sch_1):gpu_fpga_boot_en_r';
NODE_NAME     R3482 2
 '@S9S_MB_2U_LIB.S9S_MB_2U(SCH_1):PAGE314_I19@PURE_QUANTA.Q_RES(CHIPS)':
 'B': CDS_PINID='B';
NODE_NAME     U249 G11
 '@S9S_MB_2U_LIB.S9S_MB_2U(SCH_1):PAGE314_I188@PURE_QUANTA.LCMXO3LF9400C5BG484C(CHIPS)':
 'PT23C': CDS_PINID='PT23C';
NET_NAME
'GPU_FPGA_EROT_FATALERR'
 '@S9S_MB_2U_LIB.S9S_MB_2U(SCH_1):GPU_FPGA_EROT_FATALERR':
 C_SIGNAL='@s9s_mb_2u_lib.s9s_mb_2u(sch_1):gpu_fpga_erot_fatalerr';
NODE_NAME     Q108 5
 '@S9S_MB_2U_LIB.S9S_MB_2U(SCH_1):PAGE299_I168@PURE_QUANTA.MOSFET_NCH_DUAL(CHIPS)':
 'G2': CDS_PINID='G2';
NODE_NAME     Q108 6
 '@S9S_MB_2U_LIB.S9S_MB_2U(SCH_1):PAGE299_I169@PURE_QUANTA.MOSFET_NCH_DUAL(CHIPS)':
 'D1': CDS_PINID='D1';
NODE_NAME     R3503 2
 '@S9S_MB_2U_LIB.S9S_MB_2U(SCH_1):PAGE299_I177@PURE_QUANTA.Q_RES(CHIPS)':
 'B': CDS_PINID='B';
NET_NAME
'GPU_FPGA_EROT_FATALERR_ISO_N'
 '@S9S_MB_2U_LIB.S9S_MB_2U(SCH_1):GPU_FPGA_EROT_FATALERR_ISO_N':
 C_SIGNAL='@s9s_mb_2u_lib.s9s_mb_2u(sch_1):gpu_fpga_erot_fatalerr_iso_n';
NODE_NAME     Q108 3
 '@S9S_MB_2U_LIB.S9S_MB_2U(SCH_1):PAGE299_I168@PURE_QUANTA.MOSFET_NCH_DUAL(CHIPS)':
 'D2': CDS_PINID='D2';
NODE_NAME     C1988 1
 '@S9S_MB_2U_LIB.S9S_MB_2U(SCH_1):PAGE299_I171@PURE_QUANTA.Q_CAP(CHIPS)':
 'A': CDS_PINID='A';
NODE_NAME     R3504 2
 '@S9S_MB_2U_LIB.S9S_MB_2U(SCH_1):PAGE299_I174@PURE_QUANTA.Q_RES(CHIPS)':
 'B': CDS_PINID='B';
NODE_NAME     R3505 1
 '@S9S_MB_2U_LIB.S9S_MB_2U(SCH_1):PAGE314_I16@PURE_QUANTA.Q_RES(CHIPS)':
 'A': CDS_PINID='A';
NET_NAME
'GPU_FPGA_EROT_FATALERR_ISO_R_N'
 '@S9S_MB_2U_LIB.S9S_MB_2U(SCH_1):GPU_FPGA_EROT_FATALERR_ISO_R_N':
 C_SIGNAL='@s9s_mb_2u_lib.s9s_mb_2u(sch_1):gpu_fpga_erot_fatalerr_iso_r_n';
NODE_NAME     R3505 2
 '@S9S_MB_2U_LIB.S9S_MB_2U(SCH_1):PAGE314_I16@PURE_QUANTA.Q_RES(CHIPS)':
 'B': CDS_PINID='B';
NODE_NAME     U249 D11
 '@S9S_MB_2U_LIB.S9S_MB_2U(SCH_1):PAGE314_I188@PURE_QUANTA.LCMXO3LF9400C5BG484C(CHIPS)':
 'PT24D': CDS_PINID='PT24D';
NET_NAME
'GPU_FPGA_EROT_FATALERR_N'
 '@S9S_MB_2U_LIB.S9S_MB_2U(SCH_1):GPU_FPGA_EROT_FATALERR_N':
 C_SIGNAL='@s9s_mb_2u_lib.s9s_mb_2u(sch_1):gpu_fpga_erot_fatalerr_n';
NODE_NAME     J109 N2
 '@S9S_MB_2U_LIB.S9S_MB_2U(SCH_1):PAGE319_I53@PURE_QUANTA.CONN112_10137002101LF(CHIPS)':
 'N2': CDS_PINID='N2';
NODE_NAME     Q108 2
 '@S9S_MB_2U_LIB.S9S_MB_2U(SCH_1):PAGE299_I169@PURE_QUANTA.MOSFET_NCH_DUAL(CHIPS)':
 'G1': CDS_PINID='G1';
NODE_NAME     R3502 1
 '@S9S_MB_2U_LIB.S9S_MB_2U(SCH_1):PAGE299_I181@PURE_QUANTA.Q_RES(CHIPS)':
 'A': CDS_PINID='A';
NODE_NAME     R3525 2
 '@S9S_MB_2U_LIB.S9S_MB_2U(SCH_1):PAGE299_I184@PURE_QUANTA.Q_RES(CHIPS)':
 'B': CDS_PINID='B';
NET_NAME
'GPU_FPGA_EROT_RECOV_BUF_N'
 '@S9S_MB_2U_LIB.S9S_MB_2U(SCH_1):GPU_FPGA_EROT_RECOV_BUF_N':
 C_SIGNAL='@s9s_mb_2u_lib.s9s_mb_2u(sch_1):gpu_fpga_erot_recov_buf_n';
NODE_NAME     J110 A1
 '@S9S_MB_2U_LIB.S9S_MB_2U(SCH_1):PAGE318_I54@PURE_QUANTA.CONN112_10137002101LF(CHIPS)':
 'A1': CDS_PINID='A1';
NODE_NAME     R3497 2
 '@S9S_MB_2U_LIB.S9S_MB_2U(SCH_1):PAGE296_I53@PURE_QUANTA.Q_RES(CHIPS)':
 'B': CDS_PINID='B';
NET_NAME
'GPU_FPGA_EROT_RECOV_BUF_R_N'
 '@S9S_MB_2U_LIB.S9S_MB_2U(SCH_1):GPU_FPGA_EROT_RECOV_BUF_R_N':
 C_SIGNAL='@s9s_mb_2u_lib.s9s_mb_2u(sch_1):gpu_fpga_erot_recov_buf_r_n';
NODE_NAME     U257 6
 '@S9S_MB_2U_LIB.S9S_MB_2U(SCH_1):PAGE296_I50@PURE_QUANTA.74LVC2G07DW7(CHIPS)':
 '1Y': CDS_PINID='\1y\';
NODE_NAME     R3497 1
 '@S9S_MB_2U_LIB.S9S_MB_2U(SCH_1):PAGE296_I53@PURE_QUANTA.Q_RES(CHIPS)':
 'A': CDS_PINID='A';
NODE_NAME     R3494 2
 '@S9S_MB_2U_LIB.S9S_MB_2U(SCH_1):PAGE296_I55@PURE_QUANTA.Q_RES(CHIPS)':
 'B': CDS_PINID='B';
NODE_NAME     R3495 1
 '@S9S_MB_2U_LIB.S9S_MB_2U(SCH_1):PAGE296_I62@PURE_QUANTA.Q_RES(CHIPS)':
 'A': CDS_PINID='A';
NET_NAME
'GPU_FPGA_EROT_RECOV_N'
 '@S9S_MB_2U_LIB.S9S_MB_2U(SCH_1):GPU_FPGA_EROT_RECOV_N':
 C_SIGNAL='@s9s_mb_2u_lib.s9s_mb_2u(sch_1):gpu_fpga_erot_recov_n';
NODE_NAME     U257 1
 '@S9S_MB_2U_LIB.S9S_MB_2U(SCH_1):PAGE296_I50@PURE_QUANTA.74LVC2G07DW7(CHIPS)':
 '1A': CDS_PINID='\1a\';
NODE_NAME     R3490 2
 '@S9S_MB_2U_LIB.S9S_MB_2U(SCH_1):PAGE296_I57@PURE_QUANTA.Q_RES(CHIPS)':
 'B': CDS_PINID='B';
NODE_NAME     R3491 1
 '@S9S_MB_2U_LIB.S9S_MB_2U(SCH_1):PAGE296_I70@PURE_QUANTA.Q_RES(CHIPS)':
 'A': CDS_PINID='A';
NODE_NAME     R3483 1
 '@S9S_MB_2U_LIB.S9S_MB_2U(SCH_1):PAGE314_I20@PURE_QUANTA.Q_RES(CHIPS)':
 'A': CDS_PINID='A';
NET_NAME
'GPU_FPGA_EROT_RECOV_R_N'
 '@S9S_MB_2U_LIB.S9S_MB_2U(SCH_1):GPU_FPGA_EROT_RECOV_R_N':
 C_SIGNAL='@s9s_mb_2u_lib.s9s_mb_2u(sch_1):gpu_fpga_erot_recov_r_n';
NODE_NAME     R3483 2
 '@S9S_MB_2U_LIB.S9S_MB_2U(SCH_1):PAGE314_I20@PURE_QUANTA.Q_RES(CHIPS)':
 'B': CDS_PINID='B';
NODE_NAME     U249 F11
 '@S9S_MB_2U_LIB.S9S_MB_2U(SCH_1):PAGE314_I188@PURE_QUANTA.LCMXO3LF9400C5BG484C(CHIPS)':
 'PT23D': CDS_PINID='PT23D';
NET_NAME
'GPU_FPGA_EROT_RST_BUF_N'
 '@S9S_MB_2U_LIB.S9S_MB_2U(SCH_1):GPU_FPGA_EROT_RST_BUF_N':
 C_SIGNAL='@s9s_mb_2u_lib.s9s_mb_2u(sch_1):gpu_fpga_erot_rst_buf_n';
NODE_NAME     J110 N8
 '@S9S_MB_2U_LIB.S9S_MB_2U(SCH_1):PAGE318_I16@PURE_QUANTA.CONN112_10137002101LF(CHIPS)':
 'N8': CDS_PINID='N8';
NODE_NAME     R3496 2
 '@S9S_MB_2U_LIB.S9S_MB_2U(SCH_1):PAGE296_I45@PURE_QUANTA.Q_RES(CHIPS)':
 'B': CDS_PINID='B';
NET_NAME
'GPU_FPGA_EROT_RST_BUF_R_N'
 '@S9S_MB_2U_LIB.S9S_MB_2U(SCH_1):GPU_FPGA_EROT_RST_BUF_R_N':
 C_SIGNAL='@s9s_mb_2u_lib.s9s_mb_2u(sch_1):gpu_fpga_erot_rst_buf_r_n';
NODE_NAME     U255 4
 '@S9S_MB_2U_LIB.S9S_MB_2U(SCH_1):PAGE296_I16@PURE_QUANTA.74LVC2G07DW7(CHIPS)':
 '2Y': CDS_PINID='\2y\';
NODE_NAME     R3496 1
 '@S9S_MB_2U_LIB.S9S_MB_2U(SCH_1):PAGE296_I45@PURE_QUANTA.Q_RES(CHIPS)':
 'A': CDS_PINID='A';
NODE_NAME     R3492 2
 '@S9S_MB_2U_LIB.S9S_MB_2U(SCH_1):PAGE296_I47@PURE_QUANTA.Q_RES(CHIPS)':
 'B': CDS_PINID='B';
NODE_NAME     R3493 1
 '@S9S_MB_2U_LIB.S9S_MB_2U(SCH_1):PAGE296_I48@PURE_QUANTA.Q_RES(CHIPS)':
 'A': CDS_PINID='A';
NET_NAME
'GPU_FPGA_EROT_RST_N'
 '@S9S_MB_2U_LIB.S9S_MB_2U(SCH_1):GPU_FPGA_EROT_RST_N':
 C_SIGNAL='@s9s_mb_2u_lib.s9s_mb_2u(sch_1):gpu_fpga_erot_rst_n';
NODE_NAME     U255 3
 '@S9S_MB_2U_LIB.S9S_MB_2U(SCH_1):PAGE296_I16@PURE_QUANTA.74LVC2G07DW7(CHIPS)':
 '2A': CDS_PINID='\2a\';
NODE_NAME     R3488 2
 '@S9S_MB_2U_LIB.S9S_MB_2U(SCH_1):PAGE296_I40@PURE_QUANTA.Q_RES(CHIPS)':
 'B': CDS_PINID='B';
NODE_NAME     R3489 1
 '@S9S_MB_2U_LIB.S9S_MB_2U(SCH_1):PAGE296_I42@PURE_QUANTA.Q_RES(CHIPS)':
 'A': CDS_PINID='A';
NODE_NAME     R3478 1
 '@S9S_MB_2U_LIB.S9S_MB_2U(SCH_1):PAGE314_I23@PURE_QUANTA.Q_RES(CHIPS)':
 'A': CDS_PINID='A';
NET_NAME
'GPU_FPGA_EROT_RST_R_N'
 '@S9S_MB_2U_LIB.S9S_MB_2U(SCH_1):GPU_FPGA_EROT_RST_R_N':
 C_SIGNAL='@s9s_mb_2u_lib.s9s_mb_2u(sch_1):gpu_fpga_erot_rst_r_n';
NODE_NAME     R3478 2
 '@S9S_MB_2U_LIB.S9S_MB_2U(SCH_1):PAGE314_I23@PURE_QUANTA.Q_RES(CHIPS)':
 'B': CDS_PINID='B';
NODE_NAME     U249 F9
 '@S9S_MB_2U_LIB.S9S_MB_2U(SCH_1):PAGE314_I188@PURE_QUANTA.LCMXO3LF9400C5BG484C(CHIPS)':
 'PT21C': CDS_PINID='PT21C';
NET_NAME
'GPU_FPGA_OVERT'
 '@S9S_MB_2U_LIB.S9S_MB_2U(SCH_1):GPU_FPGA_OVERT':
 C_SIGNAL='@s9s_mb_2u_lib.s9s_mb_2u(sch_1):gpu_fpga_overt';
NODE_NAME     Q104 6
 '@S9S_MB_2U_LIB.S9S_MB_2U(SCH_1):PAGE299_I21@PURE_QUANTA.MOSFET_NCH_DUAL(CHIPS)':
 'D1': CDS_PINID='D1';
NODE_NAME     R3435 2
 '@S9S_MB_2U_LIB.S9S_MB_2U(SCH_1):PAGE299_I23@PURE_QUANTA.Q_RES(CHIPS)':
 'B': CDS_PINID='B';
NODE_NAME     Q104 5
 '@S9S_MB_2U_LIB.S9S_MB_2U(SCH_1):PAGE299_I26@PURE_QUANTA.MOSFET_NCH_DUAL(CHIPS)':
 'G2': CDS_PINID='G2';
NET_NAME
'GPU_FPGA_OVERT_ISO_N'
 '@S9S_MB_2U_LIB.S9S_MB_2U(SCH_1):GPU_FPGA_OVERT_ISO_N':
 C_SIGNAL='@s9s_mb_2u_lib.s9s_mb_2u(sch_1):gpu_fpga_overt_iso_n';
NODE_NAME     Q104 3
 '@S9S_MB_2U_LIB.S9S_MB_2U(SCH_1):PAGE299_I26@PURE_QUANTA.MOSFET_NCH_DUAL(CHIPS)':
 'D2': CDS_PINID='D2';
NODE_NAME     R3437 2
 '@S9S_MB_2U_LIB.S9S_MB_2U(SCH_1):PAGE299_I27@PURE_QUANTA.Q_RES(CHIPS)':
 'B': CDS_PINID='B';
NODE_NAME     C1976 1
 '@S9S_MB_2U_LIB.S9S_MB_2U(SCH_1):PAGE299_I30@PURE_QUANTA.Q_CAP(CHIPS)':
 'A': CDS_PINID='A';
NODE_NAME     R3484 1
 '@S9S_MB_2U_LIB.S9S_MB_2U(SCH_1):PAGE314_I17@PURE_QUANTA.Q_RES(CHIPS)':
 'A': CDS_PINID='A';
NET_NAME
'GPU_FPGA_OVERT_ISO_R_N'
 '@S9S_MB_2U_LIB.S9S_MB_2U(SCH_1):GPU_FPGA_OVERT_ISO_R_N':
 C_SIGNAL='@s9s_mb_2u_lib.s9s_mb_2u(sch_1):gpu_fpga_overt_iso_r_n';
NODE_NAME     R3484 2
 '@S9S_MB_2U_LIB.S9S_MB_2U(SCH_1):PAGE314_I17@PURE_QUANTA.Q_RES(CHIPS)':
 'B': CDS_PINID='B';
NODE_NAME     U249 B11
 '@S9S_MB_2U_LIB.S9S_MB_2U(SCH_1):PAGE314_I188@PURE_QUANTA.LCMXO3LF9400C5BG484C(CHIPS)':
 'PT24A': CDS_PINID='PT24A';
NET_NAME
'GPU_FPGA_OVERT_N'
 '@S9S_MB_2U_LIB.S9S_MB_2U(SCH_1):GPU_FPGA_OVERT_N':
 C_SIGNAL='@s9s_mb_2u_lib.s9s_mb_2u(sch_1):gpu_fpga_overt_n';
NODE_NAME     J108 A7
 '@S9S_MB_2U_LIB.S9S_MB_2U(SCH_1):PAGE320_I76@PURE_QUANTA.CONN112_10137002101LF(CHIPS)':
 'A7': CDS_PINID='A7';
NODE_NAME     R3430 1
 '@S9S_MB_2U_LIB.S9S_MB_2U(SCH_1):PAGE299_I3@PURE_QUANTA.Q_RES(CHIPS)':
 'A': CDS_PINID='A';
NODE_NAME     Q104 2
 '@S9S_MB_2U_LIB.S9S_MB_2U(SCH_1):PAGE299_I21@PURE_QUANTA.MOSFET_NCH_DUAL(CHIPS)':
 'G1': CDS_PINID='G1';
NODE_NAME     R3464 2
 '@S9S_MB_2U_LIB.S9S_MB_2U(SCH_1):PAGE299_I134@PURE_QUANTA.Q_RES(CHIPS)':
 'B': CDS_PINID='B';
NET_NAME
'GPU_FPGA_READY'
 '@S9S_MB_2U_LIB.S9S_MB_2U(SCH_1):GPU_FPGA_READY':
 C_SIGNAL='@s9s_mb_2u_lib.s9s_mb_2u(sch_1):gpu_fpga_ready';
NODE_NAME     J112 T2
 '@S9S_MB_2U_LIB.S9S_MB_2U(SCH_1):PAGE149_I76@PURE_QUANTA.CONN160_10131762101LF(CHIPS)':
 'T2': CDS_PINID='T2';
NODE_NAME     Q96 2
 '@S9S_MB_2U_LIB.S9S_MB_2U(SCH_1):PAGE145_I154@PURE_QUANTA.MOSFET_NCH_DUAL(CHIPS)':
 'G1': CDS_PINID='G1';
NODE_NAME     R3318 2
 '@S9S_MB_2U_LIB.S9S_MB_2U(SCH_1):PAGE145_I171@PURE_QUANTA.Q_RES(CHIPS)':
 'B': CDS_PINID='B';
NODE_NAME     R3511 1
 '@S9S_MB_2U_LIB.S9S_MB_2U(SCH_1):PAGE145_I172@PURE_QUANTA.Q_RES(CHIPS)':
 'A': CDS_PINID='A';
NET_NAME
'GPU_FPGA_READY_ISO'
 '@S9S_MB_2U_LIB.S9S_MB_2U(SCH_1):GPU_FPGA_READY_ISO':
 C_SIGNAL='@s9s_mb_2u_lib.s9s_mb_2u(sch_1):gpu_fpga_ready_iso';
NODE_NAME     Q96 3
 '@S9S_MB_2U_LIB.S9S_MB_2U(SCH_1):PAGE145_I159@PURE_QUANTA.MOSFET_NCH_DUAL(CHIPS)':
 'D2': CDS_PINID='D2';
NODE_NAME     C1881 1
 '@S9S_MB_2U_LIB.S9S_MB_2U(SCH_1):PAGE145_I156@PURE_QUANTA.Q_CAP(CHIPS)':
 'A': CDS_PINID='A';
NODE_NAME     R3321 2
 '@S9S_MB_2U_LIB.S9S_MB_2U(SCH_1):PAGE145_I158@PURE_QUANTA.Q_RES(CHIPS)':
 'B': CDS_PINID='B';
NODE_NAME     R3324 1
 '@S9S_MB_2U_LIB.S9S_MB_2U(SCH_1):PAGE314_I108@PURE_QUANTA.Q_RES(CHIPS)':
 'A': CDS_PINID='A';
NET_NAME
'GPU_FPGA_READY_ISO_R'
 '@S9S_MB_2U_LIB.S9S_MB_2U(SCH_1):GPU_FPGA_READY_ISO_R':
 C_SIGNAL='@s9s_mb_2u_lib.s9s_mb_2u(sch_1):gpu_fpga_ready_iso_r';
NODE_NAME     R3324 2
 '@S9S_MB_2U_LIB.S9S_MB_2U(SCH_1):PAGE314_I108@PURE_QUANTA.Q_RES(CHIPS)':
 'B': CDS_PINID='B';
NODE_NAME     U249 A18
 '@S9S_MB_2U_LIB.S9S_MB_2U(SCH_1):PAGE314_I188@PURE_QUANTA.LCMXO3LF9400C5BG484C(CHIPS)':
 'PT41A': CDS_PINID='PT41A';
NET_NAME
'GPU_FPGA_READY_N'
 '@S9S_MB_2U_LIB.S9S_MB_2U(SCH_1):GPU_FPGA_READY_N':
 C_SIGNAL='@s9s_mb_2u_lib.s9s_mb_2u(sch_1):gpu_fpga_ready_n';
NODE_NAME     Q96 5
 '@S9S_MB_2U_LIB.S9S_MB_2U(SCH_1):PAGE145_I159@PURE_QUANTA.MOSFET_NCH_DUAL(CHIPS)':
 'G2': CDS_PINID='G2';
NODE_NAME     Q96 6
 '@S9S_MB_2U_LIB.S9S_MB_2U(SCH_1):PAGE145_I154@PURE_QUANTA.MOSFET_NCH_DUAL(CHIPS)':
 'D1': CDS_PINID='D1';
NODE_NAME     R3320 2
 '@S9S_MB_2U_LIB.S9S_MB_2U(SCH_1):PAGE145_I162@PURE_QUANTA.Q_RES(CHIPS)':
 'B': CDS_PINID='B';
NODE_NAME     R3326 1
 '@S9S_MB_2U_LIB.S9S_MB_2U(SCH_1):PAGE201_I84@PURE_QUANTA.Q_RES(CHIPS)':
 'A': CDS_PINID='A';
NET_NAME
'GPU_FPGA_READY_R_N'
 '@S9S_MB_2U_LIB.S9S_MB_2U(SCH_1):GPU_FPGA_READY_R_N':
 C_SIGNAL='@s9s_mb_2u_lib.s9s_mb_2u(sch_1):gpu_fpga_ready_r_n';
NODE_NAME     R3326 2
 '@S9S_MB_2U_LIB.S9S_MB_2U(SCH_1):PAGE201_I84@PURE_QUANTA.Q_RES(CHIPS)':
 'B': CDS_PINID='B';
NODE_NAME     U248 1
 '@S9S_MB_2U_LIB.S9S_MB_2U(SCH_1):PAGE201_I158@PURE_QUANTA.74LVC1G32GW(CHIPS)':
 'I0': CDS_PINID='I0';
NET_NAME
'GPU_FPGA_RST_N'
 '@S9S_MB_2U_LIB.S9S_MB_2U(SCH_1):GPU_FPGA_RST_N':
 C_SIGNAL='@s9s_mb_2u_lib.s9s_mb_2u(sch_1):gpu_fpga_rst_n';
NODE_NAME     U249 Y21
 '@S9S_MB_2U_LIB.S9S_MB_2U(SCH_1):PAGE313_I1@PURE_QUANTA.LCMXO3LF9400C5BG484C(CHIPS)':
 'PR29B': CDS_PINID='PR29B';
NODE_NAME     R4608 1
 '@S9S_MB_2U_LIB.S9S_MB_2U(SCH_1):PAGE313_I190@PURE_QUANTA.Q_RES(CHIPS)':
 'A': CDS_PINID='A';
NET_NAME
'GPU_FPGA_RST_R1_BUF_N'
 '@S9S_MB_2U_LIB.S9S_MB_2U(SCH_1):GPU_FPGA_RST_R1_BUF_N':
 C_SIGNAL='@s9s_mb_2u_lib.s9s_mb_2u(sch_1):gpu_fpga_rst_r1_buf_n';
NODE_NAME     U196 4
 '@S9S_MB_2U_LIB.S9S_MB_2U(SCH_1):PAGE140_I127@PURE_QUANTA.74LVC2G17GW(CHIPS)':
 'B1': CDS_PINID='B1';
NODE_NAME     R3317 2
 '@S9S_MB_2U_LIB.S9S_MB_2U(SCH_1):PAGE140_I190@PURE_QUANTA.Q_RES(CHIPS)':
 'B': CDS_PINID='B';
NODE_NAME     R3509 1
 '@S9S_MB_2U_LIB.S9S_MB_2U(SCH_1):PAGE140_I191@PURE_QUANTA.Q_RES(CHIPS)':
 'A': CDS_PINID='A';
NODE_NAME     R3315 1
 '@S9S_MB_2U_LIB.S9S_MB_2U(SCH_1):PAGE140_I205@PURE_QUANTA.Q_RES(CHIPS)':
 'A': CDS_PINID='A';
NET_NAME
'GPU_FPGA_RST_R_BUF_N'
 '@S9S_MB_2U_LIB.S9S_MB_2U(SCH_1):GPU_FPGA_RST_R_BUF_N':
 C_SIGNAL='@s9s_mb_2u_lib.s9s_mb_2u(sch_1):gpu_fpga_rst_r_buf_n';
NODE_NAME     J111 A7
 '@S9S_MB_2U_LIB.S9S_MB_2U(SCH_1):PAGE148_I74@PURE_QUANTA.CONN112_10137002101LF(CHIPS)':
 'A7': CDS_PINID='A7';
NODE_NAME     R3315 2
 '@S9S_MB_2U_LIB.S9S_MB_2U(SCH_1):PAGE140_I205@PURE_QUANTA.Q_RES(CHIPS)':
 'B': CDS_PINID='B';
NET_NAME
'GPU_FPGA_RST_R_N'
 '@S9S_MB_2U_LIB.S9S_MB_2U(SCH_1):GPU_FPGA_RST_R_N':
 C_SIGNAL='@s9s_mb_2u_lib.s9s_mb_2u(sch_1):gpu_fpga_rst_r_n';
NODE_NAME     U196 3
 '@S9S_MB_2U_LIB.S9S_MB_2U(SCH_1):PAGE140_I127@PURE_QUANTA.74LVC2G17GW(CHIPS)':
 'A1': CDS_PINID='A1';
NODE_NAME     R3507 1
 '@S9S_MB_2U_LIB.S9S_MB_2U(SCH_1):PAGE140_I192@PURE_QUANTA.Q_RES(CHIPS)':
 'A': CDS_PINID='A';
NODE_NAME     R3506 2
 '@S9S_MB_2U_LIB.S9S_MB_2U(SCH_1):PAGE140_I193@PURE_QUANTA.Q_RES(CHIPS)':
 'B': CDS_PINID='B';
NODE_NAME     R4608 2
 '@S9S_MB_2U_LIB.S9S_MB_2U(SCH_1):PAGE313_I190@PURE_QUANTA.Q_RES(CHIPS)':
 'B': CDS_PINID='B';
NET_NAME
'GPU_FPGA_THERM_OVERT'
 '@S9S_MB_2U_LIB.S9S_MB_2U(SCH_1):GPU_FPGA_THERM_OVERT':
 C_SIGNAL='@s9s_mb_2u_lib.s9s_mb_2u(sch_1):gpu_fpga_therm_overt';
NODE_NAME     Q101 6
 '@S9S_MB_2U_LIB.S9S_MB_2U(SCH_1):PAGE299_I52@PURE_QUANTA.MOSFET_NCH_DUAL(CHIPS)':
 'D1': CDS_PINID='D1';
NODE_NAME     R3432 2
 '@S9S_MB_2U_LIB.S9S_MB_2U(SCH_1):PAGE299_I53@PURE_QUANTA.Q_RES(CHIPS)':
 'B': CDS_PINID='B';
NODE_NAME     Q101 5
 '@S9S_MB_2U_LIB.S9S_MB_2U(SCH_1):PAGE299_I57@PURE_QUANTA.MOSFET_NCH_DUAL(CHIPS)':
 'G2': CDS_PINID='G2';
NET_NAME
'GPU_FPGA_THERM_OVERT_ISO_N'
 '@S9S_MB_2U_LIB.S9S_MB_2U(SCH_1):GPU_FPGA_THERM_OVERT_ISO_N':
 C_SIGNAL='@s9s_mb_2u_lib.s9s_mb_2u(sch_1):gpu_fpga_therm_overt_iso_n';
NODE_NAME     Q101 3
 '@S9S_MB_2U_LIB.S9S_MB_2U(SCH_1):PAGE299_I57@PURE_QUANTA.MOSFET_NCH_DUAL(CHIPS)':
 'D2': CDS_PINID='D2';
NODE_NAME     R3439 2
 '@S9S_MB_2U_LIB.S9S_MB_2U(SCH_1):PAGE299_I59@PURE_QUANTA.Q_RES(CHIPS)':
 'B': CDS_PINID='B';
NODE_NAME     C1974 1
 '@S9S_MB_2U_LIB.S9S_MB_2U(SCH_1):PAGE299_I74@PURE_QUANTA.Q_CAP(CHIPS)':
 'A': CDS_PINID='A';
NODE_NAME     R3476 1
 '@S9S_MB_2U_LIB.S9S_MB_2U(SCH_1):PAGE314_I25@PURE_QUANTA.Q_RES(CHIPS)':
 'A': CDS_PINID='A';
NET_NAME
'GPU_FPGA_THERM_OVERT_ISO_R_N'
 '@S9S_MB_2U_LIB.S9S_MB_2U(SCH_1):GPU_FPGA_THERM_OVERT_ISO_R_N':
 C_SIGNAL='@s9s_mb_2u_lib.s9s_mb_2u(sch_1):gpu_fpga_therm_overt_iso_r_n';
NODE_NAME     R3476 2
 '@S9S_MB_2U_LIB.S9S_MB_2U(SCH_1):PAGE314_I25@PURE_QUANTA.Q_RES(CHIPS)':
 'B': CDS_PINID='B';
NODE_NAME     U249 B9
 '@S9S_MB_2U_LIB.S9S_MB_2U(SCH_1):PAGE314_I188@PURE_QUANTA.LCMXO3LF9400C5BG484C(CHIPS)':
 'PT21A': CDS_PINID='PT21A';
NET_NAME
'GPU_FPGA_THERM_OVERT_N'
 '@S9S_MB_2U_LIB.S9S_MB_2U(SCH_1):GPU_FPGA_THERM_OVERT_N':
 C_SIGNAL='@s9s_mb_2u_lib.s9s_mb_2u(sch_1):gpu_fpga_therm_overt_n';
NODE_NAME     J112 T6
 '@S9S_MB_2U_LIB.S9S_MB_2U(SCH_1):PAGE149_I75@PURE_QUANTA.CONN160_10131762101LF(CHIPS)':
 'T6': CDS_PINID='T6';
NODE_NAME     R3428 1
 '@S9S_MB_2U_LIB.S9S_MB_2U(SCH_1):PAGE299_I17@PURE_QUANTA.Q_RES(CHIPS)':
 'A': CDS_PINID='A';
NODE_NAME     Q101 2
 '@S9S_MB_2U_LIB.S9S_MB_2U(SCH_1):PAGE299_I52@PURE_QUANTA.MOSFET_NCH_DUAL(CHIPS)':
 'G1': CDS_PINID='G1';
NODE_NAME     R3498 2
 '@S9S_MB_2U_LIB.S9S_MB_2U(SCH_1):PAGE299_I167@PURE_QUANTA.Q_RES(CHIPS)':
 'B': CDS_PINID='B';
NET_NAME
'GPU_HMC_PRSNT'
 '@S9S_MB_2U_LIB.S9S_MB_2U(SCH_1):GPU_HMC_PRSNT':
 C_SIGNAL='@s9s_mb_2u_lib.s9s_mb_2u(sch_1):gpu_hmc_prsnt';
NODE_NAME     Q103 6
 '@S9S_MB_2U_LIB.S9S_MB_2U(SCH_1):PAGE299_I37@PURE_QUANTA.MOSFET_NCH_DUAL(CHIPS)':
 'D1': CDS_PINID='D1';
NODE_NAME     R3434 2
 '@S9S_MB_2U_LIB.S9S_MB_2U(SCH_1):PAGE299_I39@PURE_QUANTA.Q_RES(CHIPS)':
 'B': CDS_PINID='B';
NODE_NAME     Q103 5
 '@S9S_MB_2U_LIB.S9S_MB_2U(SCH_1):PAGE299_I43@PURE_QUANTA.MOSFET_NCH_DUAL(CHIPS)':
 'G2': CDS_PINID='G2';
NET_NAME
'GPU_HMC_PRSNT_ISO_N'
 '@S9S_MB_2U_LIB.S9S_MB_2U(SCH_1):GPU_HMC_PRSNT_ISO_N':
 C_SIGNAL='@s9s_mb_2u_lib.s9s_mb_2u(sch_1):gpu_hmc_prsnt_iso_n';
NODE_NAME     Q103 3
 '@S9S_MB_2U_LIB.S9S_MB_2U(SCH_1):PAGE299_I43@PURE_QUANTA.MOSFET_NCH_DUAL(CHIPS)':
 'D2': CDS_PINID='D2';
NODE_NAME     R3436 2
 '@S9S_MB_2U_LIB.S9S_MB_2U(SCH_1):PAGE299_I45@PURE_QUANTA.Q_RES(CHIPS)':
 'B': CDS_PINID='B';
NODE_NAME     C1975 1
 '@S9S_MB_2U_LIB.S9S_MB_2U(SCH_1):PAGE299_I129@PURE_QUANTA.Q_CAP(CHIPS)':
 'A': CDS_PINID='A';
NODE_NAME     R3481 1
 '@S9S_MB_2U_LIB.S9S_MB_2U(SCH_1):PAGE314_I22@PURE_QUANTA.Q_RES(CHIPS)':
 'A': CDS_PINID='A';
NET_NAME
'GPU_HMC_PRSNT_ISO_R_N'
 '@S9S_MB_2U_LIB.S9S_MB_2U(SCH_1):GPU_HMC_PRSNT_ISO_R_N':
 C_SIGNAL='@s9s_mb_2u_lib.s9s_mb_2u(sch_1):gpu_hmc_prsnt_iso_r_n';
NODE_NAME     R3481 2
 '@S9S_MB_2U_LIB.S9S_MB_2U(SCH_1):PAGE314_I22@PURE_QUANTA.Q_RES(CHIPS)':
 'B': CDS_PINID='B';
NODE_NAME     U249 E10
 '@S9S_MB_2U_LIB.S9S_MB_2U(SCH_1):PAGE314_I188@PURE_QUANTA.LCMXO3LF9400C5BG484C(CHIPS)':
 'PT22B': CDS_PINID='PT22B';
NET_NAME
'GPU_HMC_PRSNT_N'
 '@S9S_MB_2U_LIB.S9S_MB_2U(SCH_1):GPU_HMC_PRSNT_N':
 C_SIGNAL='@s9s_mb_2u_lib.s9s_mb_2u(sch_1):gpu_hmc_prsnt_n';
NODE_NAME     J110 A3
 '@S9S_MB_2U_LIB.S9S_MB_2U(SCH_1):PAGE318_I54@PURE_QUANTA.CONN112_10137002101LF(CHIPS)':
 'A3': CDS_PINID='A3';
NODE_NAME     Q103 2
 '@S9S_MB_2U_LIB.S9S_MB_2U(SCH_1):PAGE299_I37@PURE_QUANTA.MOSFET_NCH_DUAL(CHIPS)':
 'G1': CDS_PINID='G1';
NODE_NAME     R3465 2
 '@S9S_MB_2U_LIB.S9S_MB_2U(SCH_1):PAGE299_I132@PURE_QUANTA.Q_RES(CHIPS)':
 'B': CDS_PINID='B';
NODE_NAME     R3431 1
 '@S9S_MB_2U_LIB.S9S_MB_2U(SCH_1):PAGE299_I133@PURE_QUANTA.Q_RES(CHIPS)':
 'A': CDS_PINID='A';
NET_NAME
'GPU_NVS_PWR_BRAKE_N'
 '@S9S_MB_2U_LIB.S9S_MB_2U(SCH_1):GPU_NVS_PWR_BRAKE_N':
 C_SIGNAL='@s9s_mb_2u_lib.s9s_mb_2u(sch_1):gpu_nvs_pwr_brake_n';
NODE_NAME     U255 1
 '@S9S_MB_2U_LIB.S9S_MB_2U(SCH_1):PAGE296_I16@PURE_QUANTA.74LVC2G07DW7(CHIPS)':
 '1A': CDS_PINID='\1a\';
NODE_NAME     R3459 2
 '@S9S_MB_2U_LIB.S9S_MB_2U(SCH_1):PAGE296_I29@PURE_QUANTA.Q_RES(CHIPS)':
 'B': CDS_PINID='B';
NODE_NAME     R3460 1
 '@S9S_MB_2U_LIB.S9S_MB_2U(SCH_1):PAGE296_I31@PURE_QUANTA.Q_RES(CHIPS)':
 'A': CDS_PINID='A';
NODE_NAME     R3477 1
 '@S9S_MB_2U_LIB.S9S_MB_2U(SCH_1):PAGE314_I26@PURE_QUANTA.Q_RES(CHIPS)':
 'A': CDS_PINID='A';
NET_NAME
'GPU_NVS_PWR_BRAKE_N_BUF'
 '@S9S_MB_2U_LIB.S9S_MB_2U(SCH_1):GPU_NVS_PWR_BRAKE_N_BUF':
 C_SIGNAL='@s9s_mb_2u_lib.s9s_mb_2u(sch_1):gpu_nvs_pwr_brake_n_buf';
NODE_NAME     J112 T4
 '@S9S_MB_2U_LIB.S9S_MB_2U(SCH_1):PAGE149_I76@PURE_QUANTA.CONN160_10131762101LF(CHIPS)':
 'T4': CDS_PINID='T4';
NODE_NAME     R3397 2
 '@S9S_MB_2U_LIB.S9S_MB_2U(SCH_1):PAGE296_I37@PURE_QUANTA.Q_RES(CHIPS)':
 'B': CDS_PINID='B';
NET_NAME
'GPU_NVS_PWR_BRAKE_N_R'
 '@S9S_MB_2U_LIB.S9S_MB_2U(SCH_1):GPU_NVS_PWR_BRAKE_N_R':
 C_SIGNAL='@s9s_mb_2u_lib.s9s_mb_2u(sch_1):gpu_nvs_pwr_brake_n_r';
NODE_NAME     U255 6
 '@S9S_MB_2U_LIB.S9S_MB_2U(SCH_1):PAGE296_I16@PURE_QUANTA.74LVC2G07DW7(CHIPS)':
 '1Y': CDS_PINID='\1y\';
NODE_NAME     R3462 1
 '@S9S_MB_2U_LIB.S9S_MB_2U(SCH_1):PAGE296_I33@PURE_QUANTA.Q_RES(CHIPS)':
 'A': CDS_PINID='A';
NODE_NAME     R3461 2
 '@S9S_MB_2U_LIB.S9S_MB_2U(SCH_1):PAGE296_I35@PURE_QUANTA.Q_RES(CHIPS)':
 'B': CDS_PINID='B';
NODE_NAME     R3397 1
 '@S9S_MB_2U_LIB.S9S_MB_2U(SCH_1):PAGE296_I37@PURE_QUANTA.Q_RES(CHIPS)':
 'A': CDS_PINID='A';
NET_NAME
'GPU_NVS_PWR_BRAKE_R_N'
 '@S9S_MB_2U_LIB.S9S_MB_2U(SCH_1):GPU_NVS_PWR_BRAKE_R_N':
 C_SIGNAL='@s9s_mb_2u_lib.s9s_mb_2u(sch_1):gpu_nvs_pwr_brake_r_n';
NODE_NAME     R3477 2
 '@S9S_MB_2U_LIB.S9S_MB_2U(SCH_1):PAGE314_I26@PURE_QUANTA.Q_RES(CHIPS)':
 'B': CDS_PINID='B';
NODE_NAME     U249 A9
 '@S9S_MB_2U_LIB.S9S_MB_2U(SCH_1):PAGE314_I188@PURE_QUANTA.LCMXO3LF9400C5BG484C(CHIPS)':
 'PT21B': CDS_PINID='PT21B';
NET_NAME
'GPU_PEX_STRAP0'
 '@S9S_MB_2U_LIB.S9S_MB_2U(SCH_1):GPU_PEX_STRAP0':
 C_SIGNAL='@s9s_mb_2u_lib.s9s_mb_2u(sch_1):gpu_pex_strap0';
NODE_NAME     J111 A5
 '@S9S_MB_2U_LIB.S9S_MB_2U(SCH_1):PAGE148_I74@PURE_QUANTA.CONN112_10137002101LF(CHIPS)':
 'A5': CDS_PINID='A5';
NODE_NAME     R3518 1
 '@S9S_MB_2U_LIB.S9S_MB_2U(SCH_1):PAGE214_I129@PURE_QUANTA.Q_RES(CHIPS)':
 'A': CDS_PINID='A';
NODE_NAME     R3442 1
 '@S9S_MB_2U_LIB.S9S_MB_2U(SCH_1):PAGE147_I6@PURE_QUANTA.Q_RES(CHIPS)':
 'A': CDS_PINID='A';
NET_NAME
'GPU_PEX_STRAP0_R'
 '@S9S_MB_2U_LIB.S9S_MB_2U(SCH_1):GPU_PEX_STRAP0_R':
 C_SIGNAL='@s9s_mb_2u_lib.s9s_mb_2u(sch_1):gpu_pex_strap0_r';
NODE_NAME     U181 17
 '@S9S_MB_2U_LIB.S9S_MB_2U(SCH_1):PAGE214_I66@PURE_QUANTA.PCA9539RPW(CHIPS)':
 'IO1_4': CDS_PINID='IO1_4';
NODE_NAME     R3518 2
 '@S9S_MB_2U_LIB.S9S_MB_2U(SCH_1):PAGE214_I129@PURE_QUANTA.Q_RES(CHIPS)':
 'B': CDS_PINID='B';
NET_NAME
'GPU_PEX_STRAP1'
 '@S9S_MB_2U_LIB.S9S_MB_2U(SCH_1):GPU_PEX_STRAP1':
 C_SIGNAL='@s9s_mb_2u_lib.s9s_mb_2u(sch_1):gpu_pex_strap1';
NODE_NAME     J111 A1
 '@S9S_MB_2U_LIB.S9S_MB_2U(SCH_1):PAGE148_I75@PURE_QUANTA.CONN112_10137002101LF(CHIPS)':
 'A1': CDS_PINID='A1';
NODE_NAME     R3443 1
 '@S9S_MB_2U_LIB.S9S_MB_2U(SCH_1):PAGE147_I5@PURE_QUANTA.Q_RES(CHIPS)':
 'A': CDS_PINID='A';
NODE_NAME     R3517 1
 '@S9S_MB_2U_LIB.S9S_MB_2U(SCH_1):PAGE214_I128@PURE_QUANTA.Q_RES(CHIPS)':
 'A': CDS_PINID='A';
NET_NAME
'GPU_PEX_STRAP1_R'
 '@S9S_MB_2U_LIB.S9S_MB_2U(SCH_1):GPU_PEX_STRAP1_R':
 C_SIGNAL='@s9s_mb_2u_lib.s9s_mb_2u(sch_1):gpu_pex_strap1_r';
NODE_NAME     U181 18
 '@S9S_MB_2U_LIB.S9S_MB_2U(SCH_1):PAGE214_I66@PURE_QUANTA.PCA9539RPW(CHIPS)':
 'IO1_5': CDS_PINID='IO1_5';
NODE_NAME     R3517 2
 '@S9S_MB_2U_LIB.S9S_MB_2U(SCH_1):PAGE214_I128@PURE_QUANTA.Q_RES(CHIPS)':
 'B': CDS_PINID='B';
NET_NAME
'GPU_PRSNT'
 '@S9S_MB_2U_LIB.S9S_MB_2U(SCH_1):GPU_PRSNT':
 C_SIGNAL='@s9s_mb_2u_lib.s9s_mb_2u(sch_1):gpu_prsnt';
NODE_NAME     Q107 5
 '@S9S_MB_2U_LIB.S9S_MB_2U(SCH_1):PAGE299_I157@PURE_QUANTA.MOSFET_NCH_DUAL(CHIPS)':
 'G2': CDS_PINID='G2';
NODE_NAME     R3474 2
 '@S9S_MB_2U_LIB.S9S_MB_2U(SCH_1):PAGE299_I158@PURE_QUANTA.Q_RES(CHIPS)':
 'B': CDS_PINID='B';
NODE_NAME     Q107 6
 '@S9S_MB_2U_LIB.S9S_MB_2U(SCH_1):PAGE299_I160@PURE_QUANTA.MOSFET_NCH_DUAL(CHIPS)':
 'D1': CDS_PINID='D1';
NODE_NAME     R3770 1
 '@S9S_MB_2U_LIB.S9S_MB_2U(SCH_1):PAGE230_I34@PURE_QUANTA.Q_RES(CHIPS)':
 'A': CDS_PINID='A';
NET_NAME
'GPU_PRSNT_N'
 '@S9S_MB_2U_LIB.S9S_MB_2U(SCH_1):GPU_PRSNT_N':
 C_SIGNAL='@s9s_mb_2u_lib.s9s_mb_2u(sch_1):gpu_prsnt_n';
NODE_NAME     J111 N2
 '@S9S_MB_2U_LIB.S9S_MB_2U(SCH_1):PAGE148_I75@PURE_QUANTA.CONN112_10137002101LF(CHIPS)':
 'N2': CDS_PINID='N2';
NODE_NAME     Q107 2
 '@S9S_MB_2U_LIB.S9S_MB_2U(SCH_1):PAGE299_I160@PURE_QUANTA.MOSFET_NCH_DUAL(CHIPS)':
 'G1': CDS_PINID='G1';
NODE_NAME     R3473 1
 '@S9S_MB_2U_LIB.S9S_MB_2U(SCH_1):PAGE299_I163@PURE_QUANTA.Q_RES(CHIPS)':
 'A': CDS_PINID='A';
NODE_NAME     R3487 2
 '@S9S_MB_2U_LIB.S9S_MB_2U(SCH_1):PAGE299_I166@PURE_QUANTA.Q_RES(CHIPS)':
 'B': CDS_PINID='B';
NET_NAME
'GPU_PRSNT_N_ISO'
 '@S9S_MB_2U_LIB.S9S_MB_2U(SCH_1):GPU_PRSNT_N_ISO':
 C_SIGNAL='@s9s_mb_2u_lib.s9s_mb_2u(sch_1):gpu_prsnt_n_iso';
NODE_NAME     C1978 1
 '@S9S_MB_2U_LIB.S9S_MB_2U(SCH_1):PAGE299_I152@PURE_QUANTA.Q_CAP(CHIPS)':
 'A': CDS_PINID='A';
NODE_NAME     R3475 2
 '@S9S_MB_2U_LIB.S9S_MB_2U(SCH_1):PAGE299_I154@PURE_QUANTA.Q_RES(CHIPS)':
 'B': CDS_PINID='B';
NODE_NAME     Q107 3
 '@S9S_MB_2U_LIB.S9S_MB_2U(SCH_1):PAGE299_I157@PURE_QUANTA.MOSFET_NCH_DUAL(CHIPS)':
 'D2': CDS_PINID='D2';
NODE_NAME     R3486 1
 '@S9S_MB_2U_LIB.S9S_MB_2U(SCH_1):PAGE314_I15@PURE_QUANTA.Q_RES(CHIPS)':
 'A': CDS_PINID='A';
NODE_NAME     R4729 1
 '@S9S_MB_2U_LIB.S9S_MB_2U(SCH_1):PAGE214_I140@PURE_QUANTA.Q_RES(CHIPS)':
 'A': CDS_PINID='A';
NET_NAME
'GPU_PRSNT_N_ISO_R'
 '@S9S_MB_2U_LIB.S9S_MB_2U(SCH_1):GPU_PRSNT_N_ISO_R':
 C_SIGNAL='@s9s_mb_2u_lib.s9s_mb_2u(sch_1):gpu_prsnt_n_iso_r';
NODE_NAME     R3486 2
 '@S9S_MB_2U_LIB.S9S_MB_2U(SCH_1):PAGE314_I15@PURE_QUANTA.Q_RES(CHIPS)':
 'B': CDS_PINID='B';
NODE_NAME     U249 E11
 '@S9S_MB_2U_LIB.S9S_MB_2U(SCH_1):PAGE314_I188@PURE_QUANTA.LCMXO3LF9400C5BG484C(CHIPS)':
 'PT24C': CDS_PINID='PT24C';
NET_NAME
'GPU_PRSNT_N_ISO_R1'
 '@S9S_MB_2U_LIB.S9S_MB_2U(SCH_1):GPU_PRSNT_N_ISO_R1':
 C_SIGNAL='@s9s_mb_2u_lib.s9s_mb_2u(sch_1):gpu_prsnt_n_iso_r1';
NODE_NAME     U181 9
 '@S9S_MB_2U_LIB.S9S_MB_2U(SCH_1):PAGE214_I66@PURE_QUANTA.PCA9539RPW(CHIPS)':
 'IO0_5': CDS_PINID='IO0_5';
NODE_NAME     R4729 2
 '@S9S_MB_2U_LIB.S9S_MB_2U(SCH_1):PAGE214_I140@PURE_QUANTA.Q_RES(CHIPS)':
 'B': CDS_PINID='B';
NET_NAME
'GPU_PRSNT_R'
 '@S9S_MB_2U_LIB.S9S_MB_2U(SCH_1):GPU_PRSNT_R':
 C_SIGNAL='@s9s_mb_2u_lib.s9s_mb_2u(sch_1):gpu_prsnt_r';
NODE_NAME     U278 2
 '@S9S_MB_2U_LIB.S9S_MB_2U(SCH_1):PAGE230_I31@PURE_QUANTA.74LVC1G08W57(CHIPS)':
 'B': CDS_PINID='B';
NODE_NAME     R3770 2
 '@S9S_MB_2U_LIB.S9S_MB_2U(SCH_1):PAGE230_I34@PURE_QUANTA.Q_RES(CHIPS)':
 'B': CDS_PINID='B';
NET_NAME
'GPU_WP_HW_CTRL_ISO'
 '@S9S_MB_2U_LIB.S9S_MB_2U(SCH_1):GPU_WP_HW_CTRL_ISO':
 C_SIGNAL='@s9s_mb_2u_lib.s9s_mb_2u(sch_1):gpu_wp_hw_ctrl_iso';
NODE_NAME     J105 A3
 '@S9S_MB_2U_LIB.S9S_MB_2U(SCH_1):PAGE142_I65@PURE_QUANTA.CONN112_10137002101LF(CHIPS)':
 'A3': CDS_PINID='A3';
NODE_NAME     Q106 6
 '@S9S_MB_2U_LIB.S9S_MB_2U(SCH_1):PAGE299_I135@PURE_QUANTA.MOSFET_NCH_DUAL(CHIPS)':
 'D1': CDS_PINID='D1';
NODE_NAME     R3472 2
 '@S9S_MB_2U_LIB.S9S_MB_2U(SCH_1):PAGE299_I147@PURE_QUANTA.Q_RES(CHIPS)':
 'B': CDS_PINID='B';
NET_NAME
'GPU_WP_HW_CTRL_N'
 '@S9S_MB_2U_LIB.S9S_MB_2U(SCH_1):GPU_WP_HW_CTRL_N':
 C_SIGNAL='@s9s_mb_2u_lib.s9s_mb_2u(sch_1):gpu_wp_hw_ctrl_n';
NODE_NAME     Q106 2
 '@S9S_MB_2U_LIB.S9S_MB_2U(SCH_1):PAGE299_I135@PURE_QUANTA.MOSFET_NCH_DUAL(CHIPS)':
 'G1': CDS_PINID='G1';
NODE_NAME     R3471 1
 '@S9S_MB_2U_LIB.S9S_MB_2U(SCH_1):PAGE299_I144@PURE_QUANTA.Q_RES(CHIPS)':
 'A': CDS_PINID='A';
NODE_NAME     R3470 2
 '@S9S_MB_2U_LIB.S9S_MB_2U(SCH_1):PAGE299_I145@PURE_QUANTA.Q_RES(CHIPS)':
 'B': CDS_PINID='B';
NODE_NAME     R3485 1
 '@S9S_MB_2U_LIB.S9S_MB_2U(SCH_1):PAGE314_I18@PURE_QUANTA.Q_RES(CHIPS)':
 'A': CDS_PINID='A';
NET_NAME
'GPU_WP_HW_CTRL_R_N'
 '@S9S_MB_2U_LIB.S9S_MB_2U(SCH_1):GPU_WP_HW_CTRL_R_N':
 C_SIGNAL='@s9s_mb_2u_lib.s9s_mb_2u(sch_1):gpu_wp_hw_ctrl_r_n';
NODE_NAME     R3485 2
 '@S9S_MB_2U_LIB.S9S_MB_2U(SCH_1):PAGE314_I18@PURE_QUANTA.Q_RES(CHIPS)':
 'B': CDS_PINID='B';
NODE_NAME     U249 A11
 '@S9S_MB_2U_LIB.S9S_MB_2U(SCH_1):PAGE314_I188@PURE_QUANTA.LCMXO3LF9400C5BG484C(CHIPS)':
 'PT24B': CDS_PINID='PT24B';
NET_NAME
'HDD_ACTIVITY_BUF'
 '@S9S_MB_2U_LIB.S9S_MB_2U(SCH_1):HDD_ACTIVITY_BUF':
 C_SIGNAL='@s9s_mb_2u_lib.s9s_mb_2u(sch_1):hdd_activity_buf';
NODE_NAME     R3296 2
 '@S9S_MB_2U_LIB.S9S_MB_2U(SCH_1):PAGE182_I324@PURE_QUANTA.Q_RES(CHIPS)':
 'B': CDS_PINID='B';
NODE_NAME     U259 6
 '@S9S_MB_2U_LIB.S9S_MB_2U(SCH_1):PAGE182_I327@PURE_QUANTA.SN74LVC2G07DCKR(CHIPS)':
 '1Y': CDS_PINID='\1y\';
NODE_NAME     Q95 2
 '@S9S_MB_2U_LIB.S9S_MB_2U(SCH_1):PAGE182_I342@PURE_QUANTA.MOSFET_NCH_DUAL(CHIPS)':
 'G1': CDS_PINID='G1';
NET_NAME
'HDD_ACTIVITY_BUF_N'
 '@S9S_MB_2U_LIB.S9S_MB_2U(SCH_1):HDD_ACTIVITY_BUF_N':
 C_SIGNAL='@s9s_mb_2u_lib.s9s_mb_2u(sch_1):hdd_activity_buf_n';
NODE_NAME     R3298 2
 '@S9S_MB_2U_LIB.S9S_MB_2U(SCH_1):PAGE182_I306@PURE_QUANTA.Q_RES(CHIPS)':
 'B': CDS_PINID='B';
NODE_NAME     R5377 1
 '@S9S_MB_2U_LIB.S9S_MB_2U(SCH_1):PAGE182_I312@PURE_QUANTA.Q_RES(CHIPS)':
 'A': CDS_PINID='A';
NODE_NAME     Q95 6
 '@S9S_MB_2U_LIB.S9S_MB_2U(SCH_1):PAGE182_I342@PURE_QUANTA.MOSFET_NCH_DUAL(CHIPS)':
 'D1': CDS_PINID='D1';
NET_NAME
'HGX_DETECT'
 '@S9S_MB_2U_LIB.S9S_MB_2U(SCH_1):HGX_DETECT':
 C_SIGNAL='@s9s_mb_2u_lib.s9s_mb_2u(sch_1):hgx_detect';
NODE_NAME     Q148 5
 '@S9S_MB_2U_LIB.S9S_MB_2U(SCH_1):PAGE139_I55@PURE_QUANTA.MOSFET_NCH_DUAL(CHIPS)':
 'G2': CDS_PINID='G2';
NODE_NAME     R4545 2
 '@S9S_MB_2U_LIB.S9S_MB_2U(SCH_1):PAGE139_I57@PURE_QUANTA.Q_RES(CHIPS)':
 'B': CDS_PINID='B';
NODE_NAME     Q148 6
 '@S9S_MB_2U_LIB.S9S_MB_2U(SCH_1):PAGE139_I61@PURE_QUANTA.MOSFET_NCH_DUAL(CHIPS)':
 'D1': CDS_PINID='D1';
NET_NAME
'HGX_DETECT_N'
 '@S9S_MB_2U_LIB.S9S_MB_2U(SCH_1):HGX_DETECT_N':
 C_SIGNAL='@s9s_mb_2u_lib.s9s_mb_2u(sch_1):hgx_detect_n';
NODE_NAME     Q148 2
 '@S9S_MB_2U_LIB.S9S_MB_2U(SCH_1):PAGE139_I61@PURE_QUANTA.MOSFET_NCH_DUAL(CHIPS)':
 'G1': CDS_PINID='G1';
NODE_NAME     R4544 1
 '@S9S_MB_2U_LIB.S9S_MB_2U(SCH_1):PAGE139_I62@PURE_QUANTA.Q_RES(CHIPS)':
 'A': CDS_PINID='A';
NODE_NAME     R4556 2
 '@S9S_MB_2U_LIB.S9S_MB_2U(SCH_1):PAGE312_I143@PURE_QUANTA.Q_RES(CHIPS)':
 'B': CDS_PINID='B';
NODE_NAME     R4543 2
 '@S9S_MB_2U_LIB.S9S_MB_2U(SCH_1):PAGE139_I85@PURE_QUANTA.Q_RES(CHIPS)':
 'B': CDS_PINID='B';
NET_NAME
'HGX_DETECT_N_ISO'
 '@S9S_MB_2U_LIB.S9S_MB_2U(SCH_1):HGX_DETECT_N_ISO':
 C_SIGNAL='@s9s_mb_2u_lib.s9s_mb_2u(sch_1):hgx_detect_n_iso';
NODE_NAME     J112 A3
 '@S9S_MB_2U_LIB.S9S_MB_2U(SCH_1):PAGE149_I76@PURE_QUANTA.CONN160_10131762101LF(CHIPS)':
 'A3': CDS_PINID='A3';
NODE_NAME     R2656 1
 '@S9S_MB_2U_LIB.S9S_MB_2U(SCH_1):PAGE147_I11@PURE_QUANTA.Q_RES(CHIPS)':
 'A': CDS_PINID='A';
NODE_NAME     R4546 2
 '@S9S_MB_2U_LIB.S9S_MB_2U(SCH_1):PAGE139_I50@PURE_QUANTA.Q_RES(CHIPS)':
 'B': CDS_PINID='B';
NODE_NAME     C2340 1
 '@S9S_MB_2U_LIB.S9S_MB_2U(SCH_1):PAGE139_I52@PURE_QUANTA.Q_CAP(CHIPS)':
 'A': CDS_PINID='A';
NODE_NAME     Q148 3
 '@S9S_MB_2U_LIB.S9S_MB_2U(SCH_1):PAGE139_I55@PURE_QUANTA.MOSFET_NCH_DUAL(CHIPS)':
 'D2': CDS_PINID='D2';
NET_NAME
'HGX_DETECT_N_R'
 '@S9S_MB_2U_LIB.S9S_MB_2U(SCH_1):HGX_DETECT_N_R':
 C_SIGNAL='@s9s_mb_2u_lib.s9s_mb_2u(sch_1):hgx_detect_n_r';
NODE_NAME     U249 AB20
 '@S9S_MB_2U_LIB.S9S_MB_2U(SCH_1):PAGE312_I1@PURE_QUANTA.LCMXO3LF9400C5BG484C(CHIPS)':
 'PB44A': CDS_PINID='PB44A';
NODE_NAME     R4556 1
 '@S9S_MB_2U_LIB.S9S_MB_2U(SCH_1):PAGE312_I143@PURE_QUANTA.Q_RES(CHIPS)':
 'A': CDS_PINID='A';
NET_NAME
'HPDB_HSC_PWRGD'
 '@S9S_MB_2U_LIB.S9S_MB_2U(SCH_1):HPDB_HSC_PWRGD':
 C_SIGNAL='@s9s_mb_2u_lib.s9s_mb_2u(sch_1):hpdb_hsc_pwrgd';
NODE_NAME     R4552 1
 '@S9S_MB_2U_LIB.S9S_MB_2U(SCH_1):PAGE230_I50@PURE_QUANTA.Q_RES(CHIPS)':
 'A': CDS_PINID='A';
NODE_NAME     R4551 2
 '@S9S_MB_2U_LIB.S9S_MB_2U(SCH_1):PAGE230_I51@PURE_QUANTA.Q_RES(CHIPS)':
 'B': CDS_PINID='B';
NODE_NAME     Q145 2
 '@S9S_MB_2U_LIB.S9S_MB_2U(SCH_1):PAGE230_I53@PURE_QUANTA.MOSFET_NCH_DUAL(CHIPS)':
 'G1': CDS_PINID='G1';
NODE_NAME     R2802 2
 '@S9S_MB_2U_LIB.S9S_MB_2U(SCH_1):PAGE233_I39@PURE_QUANTA.Q_RES(CHIPS)':
 'B': CDS_PINID='B';
NET_NAME
'HPDB_HSC_PWRGD_ISO'
 '@S9S_MB_2U_LIB.S9S_MB_2U(SCH_1):HPDB_HSC_PWRGD_ISO':
 C_SIGNAL='@s9s_mb_2u_lib.s9s_mb_2u(sch_1):hpdb_hsc_pwrgd_iso';
NODE_NAME     R4557 1
 '@S9S_MB_2U_LIB.S9S_MB_2U(SCH_1):PAGE312_I145@PURE_QUANTA.Q_RES(CHIPS)':
 'A': CDS_PINID='A';
NODE_NAME     Q145 3
 '@S9S_MB_2U_LIB.S9S_MB_2U(SCH_1):PAGE230_I58@PURE_QUANTA.MOSFET_NCH_DUAL(CHIPS)':
 'D2': CDS_PINID='D2';
NODE_NAME     R4554 2
 '@S9S_MB_2U_LIB.S9S_MB_2U(SCH_1):PAGE230_I59@PURE_QUANTA.Q_RES(CHIPS)':
 'B': CDS_PINID='B';
NODE_NAME     C2342 1
 '@S9S_MB_2U_LIB.S9S_MB_2U(SCH_1):PAGE230_I62@PURE_QUANTA.Q_CAP(CHIPS)':
 'A': CDS_PINID='A';
NET_NAME
'HPDB_HSC_PWRGD_ISO_R'
 '@S9S_MB_2U_LIB.S9S_MB_2U(SCH_1):HPDB_HSC_PWRGD_ISO_R':
 C_SIGNAL='@s9s_mb_2u_lib.s9s_mb_2u(sch_1):hpdb_hsc_pwrgd_iso_r';
NODE_NAME     U249 AA20
 '@S9S_MB_2U_LIB.S9S_MB_2U(SCH_1):PAGE312_I1@PURE_QUANTA.LCMXO3LF9400C5BG484C(CHIPS)':
 'PB44B': CDS_PINID='PB44B';
NODE_NAME     R4557 2
 '@S9S_MB_2U_LIB.S9S_MB_2U(SCH_1):PAGE312_I145@PURE_QUANTA.Q_RES(CHIPS)':
 'B': CDS_PINID='B';
NET_NAME
'HPDB_HSC_PWRGD_N'
 '@S9S_MB_2U_LIB.S9S_MB_2U(SCH_1):HPDB_HSC_PWRGD_N':
 C_SIGNAL='@s9s_mb_2u_lib.s9s_mb_2u(sch_1):hpdb_hsc_pwrgd_n';
NODE_NAME     Q145 6
 '@S9S_MB_2U_LIB.S9S_MB_2U(SCH_1):PAGE230_I53@PURE_QUANTA.MOSFET_NCH_DUAL(CHIPS)':
 'D1': CDS_PINID='D1';
NODE_NAME     R4553 2
 '@S9S_MB_2U_LIB.S9S_MB_2U(SCH_1):PAGE230_I55@PURE_QUANTA.Q_RES(CHIPS)':
 'B': CDS_PINID='B';
NODE_NAME     Q145 5
 '@S9S_MB_2U_LIB.S9S_MB_2U(SCH_1):PAGE230_I58@PURE_QUANTA.MOSFET_NCH_DUAL(CHIPS)':
 'G2': CDS_PINID='G2';
NET_NAME
'HPDB_HSC_PWRGD_R'
 '@S9S_MB_2U_LIB.S9S_MB_2U(SCH_1):HPDB_HSC_PWRGD_R':
 C_SIGNAL='@s9s_mb_2u_lib.s9s_mb_2u(sch_1):hpdb_hsc_pwrgd_r';
NODE_NAME     J45 C3
 '@S9S_MB_2U_LIB.S9S_MB_2U(SCH_1):PAGE233_I12@PURE_QUANTA.CONN60_101062636003K02LF(CHIPS)':
 'C3': CDS_PINID='C3';
NODE_NAME     R2802 1
 '@S9S_MB_2U_LIB.S9S_MB_2U(SCH_1):PAGE233_I39@PURE_QUANTA.Q_RES(CHIPS)':
 'A': CDS_PINID='A';
NODE_NAME     C2295 1
 '@S9S_MB_2U_LIB.S9S_MB_2U(SCH_1):PAGE233_I54@PURE_QUANTA.Q_CAP(CHIPS)':
 'A': CDS_PINID='A';
NET_NAME
'HP_E1S_0_P3V3_PWRGD'
 '@S9S_MB_2U_LIB.S9S_MB_2U(SCH_1):HP_E1S_0_P3V3_PWRGD':
 C_SIGNAL='@s9s_mb_2u_lib.s9s_mb_2u(sch_1):hp_e1s_0_p3v3_pwrgd';
NODE_NAME     U336 2
 '@S9S_MB_2U_LIB.S9S_MB_2U(SCH_1):PAGE297_I329@PURE_QUANTA.APX80929SAG7(CHIPS)':
 'RESET_L': CDS_PINID='RESET_L';
NODE_NAME     R4767 1
 '@S9S_MB_2U_LIB.S9S_MB_2U(SCH_1):PAGE297_I331@PURE_QUANTA.Q_RES(CHIPS)':
 'A': CDS_PINID='A';
NET_NAME
'HP_E1S_0_P3V3_PWRGD_PLD'
 '@S9S_MB_2U_LIB.S9S_MB_2U(SCH_1):HP_E1S_0_P3V3_PWRGD_PLD':
 C_SIGNAL='@s9s_mb_2u_lib.s9s_mb_2u(sch_1):hp_e1s_0_p3v3_pwrgd_pld';
NODE_NAME     U249 K1
 '@S9S_MB_2U_LIB.S9S_MB_2U(SCH_1):PAGE311_I33@PURE_QUANTA.LCMXO3LF9400C5BG484C(CHIPS)':
 'PL14B': CDS_PINID='PL14B';
NODE_NAME     R4767 2
 '@S9S_MB_2U_LIB.S9S_MB_2U(SCH_1):PAGE297_I331@PURE_QUANTA.Q_RES(CHIPS)':
 'B': CDS_PINID='B';
NET_NAME
'HP_LVC3_E1S_0_HSC_PWRGD'
 '@S9S_MB_2U_LIB.S9S_MB_2U(SCH_1):HP_LVC3_E1S_0_HSC_PWRGD':
 C_SIGNAL='@s9s_mb_2u_lib.s9s_mb_2u(sch_1):hp_lvc3_e1s_0_hsc_pwrgd';
NODE_NAME     R3972 2
 '@S9S_MB_2U_LIB.S9S_MB_2U(SCH_1):PAGE324_I68@PURE_QUANTA.Q_RES(CHIPS)':
 'B': CDS_PINID='B';
NODE_NAME     R3978 2
 '@S9S_MB_2U_LIB.S9S_MB_2U(SCH_1):PAGE324_I76@PURE_QUANTA.Q_RES(CHIPS)':
 'B': CDS_PINID='B';
NODE_NAME     PU292 10
 '@S9S_MB_2U_LIB.S9S_MB_2U(SCH_1):PAGE323_I49@PURE_QUANTA.RS31312R(CHIPS)':
 'PG': CDS_PINID='PG';
NODE_NAME     R4765 1
 '@S9S_MB_2U_LIB.S9S_MB_2U(SCH_1):PAGE311_I90@PURE_QUANTA.Q_RES(CHIPS)':
 'A': CDS_PINID='A';
NODE_NAME     R3948 2
 '@S9S_MB_2U_LIB.S9S_MB_2U(SCH_1):PAGE323_I64@PURE_QUANTA.Q_RES(CHIPS)':
 'B': CDS_PINID='B';
NET_NAME
'HP_LVC3_E1S_0_HSC_PWRGD_PLD'
 '@S9S_MB_2U_LIB.S9S_MB_2U(SCH_1):HP_LVC3_E1S_0_HSC_PWRGD_PLD':
 C_SIGNAL='@s9s_mb_2u_lib.s9s_mb_2u(sch_1):hp_lvc3_e1s_0_hsc_pwrgd_pld';
NODE_NAME     U249 K2
 '@S9S_MB_2U_LIB.S9S_MB_2U(SCH_1):PAGE311_I33@PURE_QUANTA.LCMXO3LF9400C5BG484C(CHIPS)':
 'PL14A': CDS_PINID='PL14A';
NODE_NAME     R4765 2
 '@S9S_MB_2U_LIB.S9S_MB_2U(SCH_1):PAGE311_I90@PURE_QUANTA.Q_RES(CHIPS)':
 'B': CDS_PINID='B';
NET_NAME
'HP_LVC3_OCP_V3_1_ATTN_OUT_SW_N'
 '@S9S_MB_2U_LIB.S9S_MB_2U(SCH_1):HP_LVC3_OCP_V3_1_ATTN_OUT_SW_N':
 C_SIGNAL='@s9s_mb_2u_lib.s9s_mb_2u(sch_1):hp_lvc3_ocp_v3_1_attn_out_sw_n';
NODE_NAME     R1147 2
 '@S9S_MB_2U_LIB.S9S_MB_2U(SCH_1):PAGE153_I47@PURE_QUANTA.Q_RES(CHIPS)':
 'B': CDS_PINID='B';
NODE_NAME     R1149 2
 '@S9S_MB_2U_LIB.S9S_MB_2U(SCH_1):PAGE153_I50@PURE_QUANTA.Q_RES(CHIPS)':
 'B': CDS_PINID='B';
NODE_NAME     U209 7
 '@S9S_MB_2U_LIB.S9S_MB_2U(SCH_1):PAGE154_I206@PURE_QUANTA.PCA9555APW(CHIPS)':
 'P0_3': CDS_PINID='P0_3';
NET_NAME
'HP_LVC3_OCP_V3_1_EN'
 '@S9S_MB_2U_LIB.S9S_MB_2U(SCH_1):HP_LVC3_OCP_V3_1_EN':
 C_SIGNAL='@s9s_mb_2u_lib.s9s_mb_2u(sch_1):hp_lvc3_ocp_v3_1_en';
NODE_NAME     U208 4
 '@S9S_MB_2U_LIB.S9S_MB_2U(SCH_1):PAGE154_I190@PURE_QUANTA.74LVC1G08W57(CHIPS)':
 'Y': CDS_PINID='Y';
NODE_NAME     R3263 2
 '@S9S_MB_2U_LIB.S9S_MB_2U(SCH_1):PAGE216_I21@PURE_QUANTA.Q_RES(CHIPS)':
 'B': CDS_PINID='B';
NODE_NAME     R3845 1
 '@S9S_MB_2U_LIB.S9S_MB_2U(SCH_1):PAGE236_I46@PURE_QUANTA.Q_RES(CHIPS)':
 'A': CDS_PINID='A';
NODE_NAME     R4061 1
 '@S9S_MB_2U_LIB.S9S_MB_2U(SCH_1):PAGE153_I4@PURE_QUANTA.Q_RES(CHIPS)':
 'A': CDS_PINID='A';
NODE_NAME     R5487 1
 '@S9S_MB_2U_LIB.S9S_MB_2U(SCH_1):PAGE153_I19@PURE_QUANTA.Q_RES(CHIPS)':
 'A': CDS_PINID='A';
NODE_NAME     R3834 1
 '@S9S_MB_2U_LIB.S9S_MB_2U(SCH_1):PAGE236_I65@PURE_QUANTA.Q_RES(CHIPS)':
 'A': CDS_PINID='A';
NET_NAME
'HP_LVC3_OCP_V3_1_FUSE_PWRGD'
 '@S9S_MB_2U_LIB.S9S_MB_2U(SCH_1):HP_LVC3_OCP_V3_1_FUSE_PWRGD':
 C_SIGNAL='@s9s_mb_2u_lib.s9s_mb_2u(sch_1):hp_lvc3_ocp_v3_1_fuse_pwrgd';
NODE_NAME     U249 L7
 '@S9S_MB_2U_LIB.S9S_MB_2U(SCH_1):PAGE311_I33@PURE_QUANTA.LCMXO3LF9400C5BG484C(CHIPS)':
 'PL13A': CDS_PINID='PL13A';
NODE_NAME     R4751 2
 '@S9S_MB_2U_LIB.S9S_MB_2U(SCH_1):PAGE311_I79@PURE_QUANTA.Q_RES(CHIPS)':
 'B': CDS_PINID='B';
NET_NAME
'HP_LVC3_OCP_V3_1_HSC_PWRGD_PLD_'
 '@S9S_MB_2U_LIB.S9S_MB_2U(SCH_1):HP_LVC3_OCP_V3_1_HSC_PWRGD_PLD_R':
 C_SIGNAL='@s9s_mb_2u_lib.s9s_mb_2u(sch_1):hp_lvc3_ocp_v3_1_hsc_pwrgd_pld_r';
NODE_NAME     U249 Y22
 '@S9S_MB_2U_LIB.S9S_MB_2U(SCH_1):PAGE313_I1@PURE_QUANTA.LCMXO3LF9400C5BG484C(CHIPS)':
 'PR28A': CDS_PINID='PR28A';
NODE_NAME     R4600 2
 '@S9S_MB_2U_LIB.S9S_MB_2U(SCH_1):PAGE313_I160@PURE_QUANTA.Q_RES(CHIPS)':
 'B': CDS_PINID='B';
NET_NAME
'HP_LVC3_OCP_V3_1_P12V_PWRGD'
 '@S9S_MB_2U_LIB.S9S_MB_2U(SCH_1):HP_LVC3_OCP_V3_1_P12V_PWRGD':
 C_SIGNAL='@s9s_mb_2u_lib.s9s_mb_2u(sch_1):hp_lvc3_ocp_v3_1_p12v_pwrgd';
NODE_NAME     R3144 2
 '@S9S_MB_2U_LIB.S9S_MB_2U(SCH_1):PAGE153_I82@PURE_QUANTA.Q_RES(CHIPS)':
 'B': CDS_PINID='B';
NODE_NAME     R3797 2
 '@S9S_MB_2U_LIB.S9S_MB_2U(SCH_1):PAGE153_I92@PURE_QUANTA.Q_RES(CHIPS)':
 'B': CDS_PINID='B';
NODE_NAME     R4600 1
 '@S9S_MB_2U_LIB.S9S_MB_2U(SCH_1):PAGE313_I160@PURE_QUANTA.Q_RES(CHIPS)':
 'A': CDS_PINID='A';
NODE_NAME     U322 2
 '@S9S_MB_2U_LIB.S9S_MB_2U(SCH_1):PAGE154_I221@PURE_QUANTA.74LVC1G08W57(CHIPS)':
 'B': CDS_PINID='B';
NODE_NAME     PU204 10
 '@S9S_MB_2U_LIB.S9S_MB_2U(SCH_1):PAGE236_I70@PURE_QUANTA.RS31312R(CHIPS)':
 'PG': CDS_PINID='PG';
NODE_NAME     R4532 2
 '@S9S_MB_2U_LIB.S9S_MB_2U(SCH_1):PAGE236_I76@PURE_QUANTA.Q_RES(CHIPS)':
 'B': CDS_PINID='B';
NET_NAME
'HP_LVC3_OCP_V3_1_PRSNT2'
 '@S9S_MB_2U_LIB.S9S_MB_2U(SCH_1):HP_LVC3_OCP_V3_1_PRSNT2':
 C_SIGNAL='@s9s_mb_2u_lib.s9s_mb_2u(sch_1):hp_lvc3_ocp_v3_1_prsnt2';
NODE_NAME     R1129 2
 '@S9S_MB_2U_LIB.S9S_MB_2U(SCH_1):PAGE154_I172@PURE_QUANTA.Q_RES(CHIPS)':
 'B': CDS_PINID='B';
NODE_NAME     U49 D
 '@S9S_MB_2U_LIB.S9S_MB_2U(SCH_1):PAGE154_I177@PURE_QUANTA.MOSFET_N(CHIPS)':
 'DRAIN': CDS_PINID='DRAIN';
NODE_NAME     U208 2
 '@S9S_MB_2U_LIB.S9S_MB_2U(SCH_1):PAGE154_I190@PURE_QUANTA.74LVC1G08W57(CHIPS)':
 'B': CDS_PINID='B';
NET_NAME
'HP_LVC3_OCP_V3_1_PRSNT2_N'
 '@S9S_MB_2U_LIB.S9S_MB_2U(SCH_1):HP_LVC3_OCP_V3_1_PRSNT2_N':
 C_SIGNAL='@s9s_mb_2u_lib.s9s_mb_2u(sch_1):hp_lvc3_ocp_v3_1_prsnt2_n';
NODE_NAME     U49 G
 '@S9S_MB_2U_LIB.S9S_MB_2U(SCH_1):PAGE154_I177@PURE_QUANTA.MOSFET_N(CHIPS)':
 'GATE': CDS_PINID='GATE';
NODE_NAME     R1150 2
 '@S9S_MB_2U_LIB.S9S_MB_2U(SCH_1):PAGE153_I74@PURE_QUANTA.Q_RES(CHIPS)':
 'B': CDS_PINID='B';
NODE_NAME     U209 8
 '@S9S_MB_2U_LIB.S9S_MB_2U(SCH_1):PAGE154_I206@PURE_QUANTA.PCA9555APW(CHIPS)':
 'P0_4': CDS_PINID='P0_4';
NODE_NAME     R1148 2
 '@S9S_MB_2U_LIB.S9S_MB_2U(SCH_1):PAGE153_I46@PURE_QUANTA.Q_RES(CHIPS)':
 'B': CDS_PINID='B';
NET_NAME
'HP_LVC3_OCP_V3_1_PRSNT2_N_R'
 '@S9S_MB_2U_LIB.S9S_MB_2U(SCH_1):HP_LVC3_OCP_V3_1_PRSNT2_N_R':
 C_SIGNAL='@s9s_mb_2u_lib.s9s_mb_2u(sch_1):hp_lvc3_ocp_v3_1_prsnt2_n_r';
NODE_NAME     R4752 1
 '@S9S_MB_2U_LIB.S9S_MB_2U(SCH_1):PAGE153_I45@PURE_QUANTA.Q_RES(CHIPS)':
 'A': CDS_PINID='A';
NODE_NAME     R1147 1
 '@S9S_MB_2U_LIB.S9S_MB_2U(SCH_1):PAGE153_I47@PURE_QUANTA.Q_RES(CHIPS)':
 'A': CDS_PINID='A';
NODE_NAME     U212 6
 '@S9S_MB_2U_LIB.S9S_MB_2U(SCH_1):PAGE153_I23@PURE_QUANTA.74LVC2G07DW7(CHIPS)':
 '1Y': CDS_PINID='\1y\';
NODE_NAME     U212 4
 '@S9S_MB_2U_LIB.S9S_MB_2U(SCH_1):PAGE153_I23@PURE_QUANTA.74LVC2G07DW7(CHIPS)':
 '2Y': CDS_PINID='\2y\';
NODE_NAME     U211 6
 '@S9S_MB_2U_LIB.S9S_MB_2U(SCH_1):PAGE153_I26@PURE_QUANTA.74LVC2G07DW7(CHIPS)':
 '1Y': CDS_PINID='\1y\';
NODE_NAME     U211 4
 '@S9S_MB_2U_LIB.S9S_MB_2U(SCH_1):PAGE153_I26@PURE_QUANTA.74LVC2G07DW7(CHIPS)':
 '2Y': CDS_PINID='\2y\';
NODE_NAME     R1148 1
 '@S9S_MB_2U_LIB.S9S_MB_2U(SCH_1):PAGE153_I46@PURE_QUANTA.Q_RES(CHIPS)':
 'A': CDS_PINID='A';
NET_NAME
'HP_LVC3_OCP_V3_1_PRSNT2_PLD_N'
 '@S9S_MB_2U_LIB.S9S_MB_2U(SCH_1):HP_LVC3_OCP_V3_1_PRSNT2_PLD_N':
 C_SIGNAL='@s9s_mb_2u_lib.s9s_mb_2u(sch_1):hp_lvc3_ocp_v3_1_prsnt2_pld_n';
NODE_NAME     U249 K4
 '@S9S_MB_2U_LIB.S9S_MB_2U(SCH_1):PAGE311_I33@PURE_QUANTA.LCMXO3LF9400C5BG484C(CHIPS)':
 'PL13C': CDS_PINID='PL13C';
NODE_NAME     R4752 2
 '@S9S_MB_2U_LIB.S9S_MB_2U(SCH_1):PAGE153_I45@PURE_QUANTA.Q_RES(CHIPS)':
 'B': CDS_PINID='B';
NODE_NAME     R4762 2
 '@S9S_MB_2U_LIB.S9S_MB_2U(SCH_1):PAGE153_I76@PURE_QUANTA.Q_RES(CHIPS)':
 'B': CDS_PINID='B';
NET_NAME
'HP_LVC3_OCP_V3_1_PWRGD'
 '@S9S_MB_2U_LIB.S9S_MB_2U(SCH_1):HP_LVC3_OCP_V3_1_PWRGD':
 C_SIGNAL='@s9s_mb_2u_lib.s9s_mb_2u(sch_1):hp_lvc3_ocp_v3_1_pwrgd';
NODE_NAME     U322 4
 '@S9S_MB_2U_LIB.S9S_MB_2U(SCH_1):PAGE154_I221@PURE_QUANTA.74LVC1G08W57(CHIPS)':
 'Y': CDS_PINID='Y';
NODE_NAME     R4618 1
 '@S9S_MB_2U_LIB.S9S_MB_2U(SCH_1):PAGE154_I237@PURE_QUANTA.Q_RES(CHIPS)':
 'A': CDS_PINID='A';
NET_NAME
'HP_LVC3_OCP_V3_1_PWRGD_R'
 '@S9S_MB_2U_LIB.S9S_MB_2U(SCH_1):HP_LVC3_OCP_V3_1_PWRGD_R':
 C_SIGNAL='@s9s_mb_2u_lib.s9s_mb_2u(sch_1):hp_lvc3_ocp_v3_1_pwrgd_r';
NODE_NAME     U210 1
 '@S9S_MB_2U_LIB.S9S_MB_2U(SCH_1):PAGE154_I189@PURE_QUANTA.74LVC1G08W57(CHIPS)':
 'A': CDS_PINID='A';
NODE_NAME     R4618 2
 '@S9S_MB_2U_LIB.S9S_MB_2U(SCH_1):PAGE154_I237@PURE_QUANTA.Q_RES(CHIPS)':
 'B': CDS_PINID='B';
NODE_NAME     R4746 1
 '@S9S_MB_2U_LIB.S9S_MB_2U(SCH_1):PAGE154_I245@PURE_QUANTA.Q_RES(CHIPS)':
 'A': CDS_PINID='A';
NODE_NAME     R4751 1
 '@S9S_MB_2U_LIB.S9S_MB_2U(SCH_1):PAGE311_I79@PURE_QUANTA.Q_RES(CHIPS)':
 'A': CDS_PINID='A';
NET_NAME
'HP_LVC3_OCP_V3_1_PWRGD_R2'
 '@S9S_MB_2U_LIB.S9S_MB_2U(SCH_1):HP_LVC3_OCP_V3_1_PWRGD_R2':
 C_SIGNAL='@s9s_mb_2u_lib.s9s_mb_2u(sch_1):hp_lvc3_ocp_v3_1_pwrgd_r2';
NODE_NAME     U334 1
 '@S9S_MB_2U_LIB.S9S_MB_2U(SCH_1):PAGE154_I243@PURE_QUANTA.74LVC1G08W57(CHIPS)':
 'A': CDS_PINID='A';
NODE_NAME     R4746 2
 '@S9S_MB_2U_LIB.S9S_MB_2U(SCH_1):PAGE154_I245@PURE_QUANTA.Q_RES(CHIPS)':
 'B': CDS_PINID='B';
NODE_NAME     R4748 1
 '@S9S_MB_2U_LIB.S9S_MB_2U(SCH_1):PAGE154_I253@PURE_QUANTA.Q_RES(CHIPS)':
 'A': CDS_PINID='A';
NET_NAME
'HP_LVC3_OCP_V3_1_R_EN'
 '@S9S_MB_2U_LIB.S9S_MB_2U(SCH_1):HP_LVC3_OCP_V3_1_R_EN':
 C_SIGNAL='@s9s_mb_2u_lib.s9s_mb_2u(sch_1):hp_lvc3_ocp_v3_1_r_en';
NODE_NAME     R3263 1
 '@S9S_MB_2U_LIB.S9S_MB_2U(SCH_1):PAGE216_I21@PURE_QUANTA.Q_RES(CHIPS)':
 'A': CDS_PINID='A';
NODE_NAME     U236 5
 '@S9S_MB_2U_LIB.S9S_MB_2U(SCH_1):PAGE216_I28@PURE_QUANTA.PCA9617ADP(CHIPS)':
 'EN': CDS_PINID='EN';
NET_NAME
'HP_LVC3_OCP_V3_2_ATTN_OUT_SW_N'
 '@S9S_MB_2U_LIB.S9S_MB_2U(SCH_1):HP_LVC3_OCP_V3_2_ATTN_OUT_SW_N':
 C_SIGNAL='@s9s_mb_2u_lib.s9s_mb_2u(sch_1):hp_lvc3_ocp_v3_2_attn_out_sw_n';
NODE_NAME     R3143 2
 '@S9S_MB_2U_LIB.S9S_MB_2U(SCH_1):PAGE131_I56@PURE_QUANTA.Q_RES(CHIPS)':
 'B': CDS_PINID='B';
NODE_NAME     U51 7
 '@S9S_MB_2U_LIB.S9S_MB_2U(SCH_1):PAGE132_I66@PURE_QUANTA.PCA9555APW(CHIPS)':
 'P0_3': CDS_PINID='P0_3';
NODE_NAME     R3145 2
 '@S9S_MB_2U_LIB.S9S_MB_2U(SCH_1):PAGE131_I64@PURE_QUANTA.Q_RES(CHIPS)':
 'B': CDS_PINID='B';
NET_NAME
'HP_LVC3_OCP_V3_2_EN'
 '@S9S_MB_2U_LIB.S9S_MB_2U(SCH_1):HP_LVC3_OCP_V3_2_EN':
 C_SIGNAL='@s9s_mb_2u_lib.s9s_mb_2u(sch_1):hp_lvc3_ocp_v3_2_en';
NODE_NAME     U50 4
 '@S9S_MB_2U_LIB.S9S_MB_2U(SCH_1):PAGE132_I9@PURE_QUANTA.74LVC1G08W57(CHIPS)':
 'Y': CDS_PINID='Y';
NODE_NAME     R3264 2
 '@S9S_MB_2U_LIB.S9S_MB_2U(SCH_1):PAGE216_I7@PURE_QUANTA.Q_RES(CHIPS)':
 'B': CDS_PINID='B';
NODE_NAME     R4060 1
 '@S9S_MB_2U_LIB.S9S_MB_2U(SCH_1):PAGE131_I35@PURE_QUANTA.Q_RES(CHIPS)':
 'A': CDS_PINID='A';
NODE_NAME     R4059 1
 '@S9S_MB_2U_LIB.S9S_MB_2U(SCH_1):PAGE131_I6@PURE_QUANTA.Q_RES(CHIPS)':
 'A': CDS_PINID='A';
NODE_NAME     R3631 1
 '@S9S_MB_2U_LIB.S9S_MB_2U(SCH_1):PAGE237_I44@PURE_QUANTA.Q_RES(CHIPS)':
 'A': CDS_PINID='A';
NODE_NAME     R3630 1
 '@S9S_MB_2U_LIB.S9S_MB_2U(SCH_1):PAGE237_I66@PURE_QUANTA.Q_RES(CHIPS)':
 'A': CDS_PINID='A';
NET_NAME
'HP_LVC3_OCP_V3_2_FUSE_PWRGD'
 '@S9S_MB_2U_LIB.S9S_MB_2U(SCH_1):HP_LVC3_OCP_V3_2_FUSE_PWRGD':
 C_SIGNAL='@s9s_mb_2u_lib.s9s_mb_2u(sch_1):hp_lvc3_ocp_v3_2_fuse_pwrgd';
NODE_NAME     U249 K5
 '@S9S_MB_2U_LIB.S9S_MB_2U(SCH_1):PAGE311_I33@PURE_QUANTA.LCMXO3LF9400C5BG484C(CHIPS)':
 'PL13B': CDS_PINID='PL13B';
NODE_NAME     R4760 2
 '@S9S_MB_2U_LIB.S9S_MB_2U(SCH_1):PAGE311_I86@PURE_QUANTA.Q_RES(CHIPS)':
 'B': CDS_PINID='B';
NET_NAME
'HP_LVC3_OCP_V3_2_HSC_PWRGD_PLD_'
 '@S9S_MB_2U_LIB.S9S_MB_2U(SCH_1):HP_LVC3_OCP_V3_2_HSC_PWRGD_PLD_R':
 C_SIGNAL='@s9s_mb_2u_lib.s9s_mb_2u(sch_1):hp_lvc3_ocp_v3_2_hsc_pwrgd_pld_r';
NODE_NAME     U249 U20
 '@S9S_MB_2U_LIB.S9S_MB_2U(SCH_1):PAGE313_I1@PURE_QUANTA.LCMXO3LF9400C5BG484C(CHIPS)':
 'PR27D': CDS_PINID='PR27D';
NODE_NAME     R4599 2
 '@S9S_MB_2U_LIB.S9S_MB_2U(SCH_1):PAGE313_I159@PURE_QUANTA.Q_RES(CHIPS)':
 'B': CDS_PINID='B';
NET_NAME
'HP_LVC3_OCP_V3_2_P12V_PWRGD'
 '@S9S_MB_2U_LIB.S9S_MB_2U(SCH_1):HP_LVC3_OCP_V3_2_P12V_PWRGD':
 C_SIGNAL='@s9s_mb_2u_lib.s9s_mb_2u(sch_1):hp_lvc3_ocp_v3_2_p12v_pwrgd';
NODE_NAME     R3831 2
 '@S9S_MB_2U_LIB.S9S_MB_2U(SCH_1):PAGE131_I78@PURE_QUANTA.Q_RES(CHIPS)':
 'B': CDS_PINID='B';
NODE_NAME     R3825 2
 '@S9S_MB_2U_LIB.S9S_MB_2U(SCH_1):PAGE131_I81@PURE_QUANTA.Q_RES(CHIPS)':
 'B': CDS_PINID='B';
NODE_NAME     R4599 1
 '@S9S_MB_2U_LIB.S9S_MB_2U(SCH_1):PAGE313_I159@PURE_QUANTA.Q_RES(CHIPS)':
 'A': CDS_PINID='A';
NODE_NAME     U323 2
 '@S9S_MB_2U_LIB.S9S_MB_2U(SCH_1):PAGE132_I92@PURE_QUANTA.74LVC1G08W57(CHIPS)':
 'B': CDS_PINID='B';
NODE_NAME     PU206 10
 '@S9S_MB_2U_LIB.S9S_MB_2U(SCH_1):PAGE237_I70@PURE_QUANTA.RS31312R(CHIPS)':
 'PG': CDS_PINID='PG';
NODE_NAME     R3848 2
 '@S9S_MB_2U_LIB.S9S_MB_2U(SCH_1):PAGE237_I75@PURE_QUANTA.Q_RES(CHIPS)':
 'B': CDS_PINID='B';
NET_NAME
'HP_LVC3_OCP_V3_2_PRSNT2'
 '@S9S_MB_2U_LIB.S9S_MB_2U(SCH_1):HP_LVC3_OCP_V3_2_PRSNT2':
 C_SIGNAL='@s9s_mb_2u_lib.s9s_mb_2u(sch_1):hp_lvc3_ocp_v3_2_prsnt2';
NODE_NAME     R3155 2
 '@S9S_MB_2U_LIB.S9S_MB_2U(SCH_1):PAGE132_I7@PURE_QUANTA.Q_RES(CHIPS)':
 'B': CDS_PINID='B';
NODE_NAME     U50 2
 '@S9S_MB_2U_LIB.S9S_MB_2U(SCH_1):PAGE132_I9@PURE_QUANTA.74LVC1G08W57(CHIPS)':
 'B': CDS_PINID='B';
NODE_NAME     U215 D
 '@S9S_MB_2U_LIB.S9S_MB_2U(SCH_1):PAGE132_I3@PURE_QUANTA.MOSFET_N(CHIPS)':
 'DRAIN': CDS_PINID='DRAIN';
NET_NAME
'HP_LVC3_OCP_V3_2_PRSNT2_N'
 '@S9S_MB_2U_LIB.S9S_MB_2U(SCH_1):HP_LVC3_OCP_V3_2_PRSNT2_N':
 C_SIGNAL='@s9s_mb_2u_lib.s9s_mb_2u(sch_1):hp_lvc3_ocp_v3_2_prsnt2_n';
NODE_NAME     U215 G
 '@S9S_MB_2U_LIB.S9S_MB_2U(SCH_1):PAGE132_I3@PURE_QUANTA.MOSFET_N(CHIPS)':
 'GATE': CDS_PINID='GATE';
NODE_NAME     R3142 2
 '@S9S_MB_2U_LIB.S9S_MB_2U(SCH_1):PAGE131_I57@PURE_QUANTA.Q_RES(CHIPS)':
 'B': CDS_PINID='B';
NODE_NAME     R3147 2
 '@S9S_MB_2U_LIB.S9S_MB_2U(SCH_1):PAGE131_I66@PURE_QUANTA.Q_RES(CHIPS)':
 'B': CDS_PINID='B';
NODE_NAME     U51 8
 '@S9S_MB_2U_LIB.S9S_MB_2U(SCH_1):PAGE132_I66@PURE_QUANTA.PCA9555APW(CHIPS)':
 'P0_4': CDS_PINID='P0_4';
NET_NAME
'HP_LVC3_OCP_V3_2_PRSNT2_N_R'
 '@S9S_MB_2U_LIB.S9S_MB_2U(SCH_1):HP_LVC3_OCP_V3_2_PRSNT2_N_R':
 C_SIGNAL='@s9s_mb_2u_lib.s9s_mb_2u(sch_1):hp_lvc3_ocp_v3_2_prsnt2_n_r';
NODE_NAME     R3142 1
 '@S9S_MB_2U_LIB.S9S_MB_2U(SCH_1):PAGE131_I57@PURE_QUANTA.Q_RES(CHIPS)':
 'A': CDS_PINID='A';
NODE_NAME     U59 6
 '@S9S_MB_2U_LIB.S9S_MB_2U(SCH_1):PAGE131_I19@PURE_QUANTA.74LVC2G07DW7(CHIPS)':
 '1Y': CDS_PINID='\1y\';
NODE_NAME     U59 4
 '@S9S_MB_2U_LIB.S9S_MB_2U(SCH_1):PAGE131_I19@PURE_QUANTA.74LVC2G07DW7(CHIPS)':
 '2Y': CDS_PINID='\2y\';
NODE_NAME     U58 6
 '@S9S_MB_2U_LIB.S9S_MB_2U(SCH_1):PAGE131_I25@PURE_QUANTA.74LVC2G07DW7(CHIPS)':
 '1Y': CDS_PINID='\1y\';
NODE_NAME     U58 4
 '@S9S_MB_2U_LIB.S9S_MB_2U(SCH_1):PAGE131_I25@PURE_QUANTA.74LVC2G07DW7(CHIPS)':
 '2Y': CDS_PINID='\2y\';
NODE_NAME     R3143 1
 '@S9S_MB_2U_LIB.S9S_MB_2U(SCH_1):PAGE131_I56@PURE_QUANTA.Q_RES(CHIPS)':
 'A': CDS_PINID='A';
NODE_NAME     R4753 1
 '@S9S_MB_2U_LIB.S9S_MB_2U(SCH_1):PAGE131_I55@PURE_QUANTA.Q_RES(CHIPS)':
 'A': CDS_PINID='A';
NET_NAME
'HP_LVC3_OCP_V3_2_PRSNT2_PLD_N'
 '@S9S_MB_2U_LIB.S9S_MB_2U(SCH_1):HP_LVC3_OCP_V3_2_PRSNT2_PLD_N':
 C_SIGNAL='@s9s_mb_2u_lib.s9s_mb_2u(sch_1):hp_lvc3_ocp_v3_2_prsnt2_pld_n';
NODE_NAME     U249 K3
 '@S9S_MB_2U_LIB.S9S_MB_2U(SCH_1):PAGE311_I33@PURE_QUANTA.LCMXO3LF9400C5BG484C(CHIPS)':
 'PL13D': CDS_PINID='PL13D';
NODE_NAME     R4761 2
 '@S9S_MB_2U_LIB.S9S_MB_2U(SCH_1):PAGE131_I70@PURE_QUANTA.Q_RES(CHIPS)':
 'B': CDS_PINID='B';
NODE_NAME     R4753 2
 '@S9S_MB_2U_LIB.S9S_MB_2U(SCH_1):PAGE131_I55@PURE_QUANTA.Q_RES(CHIPS)':
 'B': CDS_PINID='B';
NET_NAME
'HP_LVC3_OCP_V3_2_PWRGD'
 '@S9S_MB_2U_LIB.S9S_MB_2U(SCH_1):HP_LVC3_OCP_V3_2_PWRGD':
 C_SIGNAL='@s9s_mb_2u_lib.s9s_mb_2u(sch_1):hp_lvc3_ocp_v3_2_pwrgd';
NODE_NAME     U323 4
 '@S9S_MB_2U_LIB.S9S_MB_2U(SCH_1):PAGE132_I92@PURE_QUANTA.74LVC1G08W57(CHIPS)':
 'Y': CDS_PINID='Y';
NODE_NAME     R4617 1
 '@S9S_MB_2U_LIB.S9S_MB_2U(SCH_1):PAGE132_I99@PURE_QUANTA.Q_RES(CHIPS)':
 'A': CDS_PINID='A';
NET_NAME
'HP_LVC3_OCP_V3_2_PWRGD_R'
 '@S9S_MB_2U_LIB.S9S_MB_2U(SCH_1):HP_LVC3_OCP_V3_2_PWRGD_R':
 C_SIGNAL='@s9s_mb_2u_lib.s9s_mb_2u(sch_1):hp_lvc3_ocp_v3_2_pwrgd_r';
NODE_NAME     U53 1
 '@S9S_MB_2U_LIB.S9S_MB_2U(SCH_1):PAGE132_I56@PURE_QUANTA.74LVC1G08W57(CHIPS)':
 'A': CDS_PINID='A';
NODE_NAME     R4617 2
 '@S9S_MB_2U_LIB.S9S_MB_2U(SCH_1):PAGE132_I99@PURE_QUANTA.Q_RES(CHIPS)':
 'B': CDS_PINID='B';
NODE_NAME     R4754 1
 '@S9S_MB_2U_LIB.S9S_MB_2U(SCH_1):PAGE132_I104@PURE_QUANTA.Q_RES(CHIPS)':
 'A': CDS_PINID='A';
NODE_NAME     R4760 1
 '@S9S_MB_2U_LIB.S9S_MB_2U(SCH_1):PAGE311_I86@PURE_QUANTA.Q_RES(CHIPS)':
 'A': CDS_PINID='A';
NET_NAME
'HP_LVC3_OCP_V3_2_PWRGD_R2'
 '@S9S_MB_2U_LIB.S9S_MB_2U(SCH_1):HP_LVC3_OCP_V3_2_PWRGD_R2':
 C_SIGNAL='@s9s_mb_2u_lib.s9s_mb_2u(sch_1):hp_lvc3_ocp_v3_2_pwrgd_r2';
NODE_NAME     R4754 2
 '@S9S_MB_2U_LIB.S9S_MB_2U(SCH_1):PAGE132_I104@PURE_QUANTA.Q_RES(CHIPS)':
 'B': CDS_PINID='B';
NODE_NAME     U335 1
 '@S9S_MB_2U_LIB.S9S_MB_2U(SCH_1):PAGE132_I108@PURE_QUANTA.74LVC1G08W57(CHIPS)':
 'A': CDS_PINID='A';
NODE_NAME     R4757 1
 '@S9S_MB_2U_LIB.S9S_MB_2U(SCH_1):PAGE132_I112@PURE_QUANTA.Q_RES(CHIPS)':
 'A': CDS_PINID='A';
NET_NAME
'HP_LVC3_OCP_V3_2_R_EN'
 '@S9S_MB_2U_LIB.S9S_MB_2U(SCH_1):HP_LVC3_OCP_V3_2_R_EN':
 C_SIGNAL='@s9s_mb_2u_lib.s9s_mb_2u(sch_1):hp_lvc3_ocp_v3_2_r_en';
NODE_NAME     U235 5
 '@S9S_MB_2U_LIB.S9S_MB_2U(SCH_1):PAGE216_I5@PURE_QUANTA.PCA9617ADP(CHIPS)':
 'EN': CDS_PINID='EN';
NODE_NAME     R3264 1
 '@S9S_MB_2U_LIB.S9S_MB_2U(SCH_1):PAGE216_I7@PURE_QUANTA.Q_RES(CHIPS)':
 'A': CDS_PINID='A';
NET_NAME
'HP_LVC3_SCM_HSC_PWRGD'
 '@S9S_MB_2U_LIB.S9S_MB_2U(SCH_1):HP_LVC3_SCM_HSC_PWRGD':
 C_SIGNAL='@s9s_mb_2u_lib.s9s_mb_2u(sch_1):hp_lvc3_scm_hsc_pwrgd';
NODE_NAME     PR4012 2
 '@S9S_MB_2U_LIB.S9S_MB_2U(SCH_1):PAGE229_I74@PURE_QUANTA.Q_RES(CHIPS)':
 'B': CDS_PINID='B';
NODE_NAME     R4015 2
 '@S9S_MB_2U_LIB.S9S_MB_2U(SCH_1):PAGE229_I81@PURE_QUANTA.Q_RES(CHIPS)':
 'B': CDS_PINID='B';
NODE_NAME     R4771 1
 '@S9S_MB_2U_LIB.S9S_MB_2U(SCH_1):PAGE311_I95@PURE_QUANTA.Q_RES(CHIPS)':
 'A': CDS_PINID='A';
NODE_NAME     R4770 2
 '@S9S_MB_2U_LIB.S9S_MB_2U(SCH_1):PAGE229_I91@PURE_QUANTA.Q_RES(CHIPS)':
 'B': CDS_PINID='B';
NET_NAME
'HP_LVC3_SCM_HSC_PWRGD_PLD'
 '@S9S_MB_2U_LIB.S9S_MB_2U(SCH_1):HP_LVC3_SCM_HSC_PWRGD_PLD':
 C_SIGNAL='@s9s_mb_2u_lib.s9s_mb_2u(sch_1):hp_lvc3_scm_hsc_pwrgd_pld';
NODE_NAME     U249 L5
 '@S9S_MB_2U_LIB.S9S_MB_2U(SCH_1):PAGE311_I33@PURE_QUANTA.LCMXO3LF9400C5BG484C(CHIPS)':
 'PL14D': CDS_PINID='PL14D';
NODE_NAME     R4771 2
 '@S9S_MB_2U_LIB.S9S_MB_2U(SCH_1):PAGE311_I95@PURE_QUANTA.Q_RES(CHIPS)':
 'B': CDS_PINID='B';
NET_NAME
'HP_LVC3_SCM_HSC_PWRGD_R'
 '@S9S_MB_2U_LIB.S9S_MB_2U(SCH_1):HP_LVC3_SCM_HSC_PWRGD_R':
 C_SIGNAL='@s9s_mb_2u_lib.s9s_mb_2u(sch_1):hp_lvc3_scm_hsc_pwrgd_r';
NODE_NAME     PU299 10
 '@S9S_MB_2U_LIB.S9S_MB_2U(SCH_1):PAGE229_I90@PURE_QUANTA.RS31312R(CHIPS)':
 'PG': CDS_PINID='PG';
NODE_NAME     R4770 1
 '@S9S_MB_2U_LIB.S9S_MB_2U(SCH_1):PAGE229_I91@PURE_QUANTA.Q_RES(CHIPS)':
 'A': CDS_PINID='A';
NODE_NAME     R3836 2
 '@S9S_MB_2U_LIB.S9S_MB_2U(SCH_1):PAGE229_I92@PURE_QUANTA.Q_RES(CHIPS)':
 'B': CDS_PINID='B';
NET_NAME
'HP_OCP_V3_1_EN'
 '@S9S_MB_2U_LIB.S9S_MB_2U(SCH_1):HP_OCP_V3_1_EN':
 C_SIGNAL='@s9s_mb_2u_lib.s9s_mb_2u(sch_1):hp_ocp_v3_1_en';
NODE_NAME     U208 1
 '@S9S_MB_2U_LIB.S9S_MB_2U(SCH_1):PAGE154_I190@PURE_QUANTA.74LVC1G08W57(CHIPS)':
 'A': CDS_PINID='A';
NODE_NAME     U209 6
 '@S9S_MB_2U_LIB.S9S_MB_2U(SCH_1):PAGE154_I206@PURE_QUANTA.PCA9555APW(CHIPS)':
 'P0_2': CDS_PINID='P0_2';
NODE_NAME     R4764 2
 '@S9S_MB_2U_LIB.S9S_MB_2U(SCH_1):PAGE154_I257@PURE_QUANTA.Q_RES(CHIPS)':
 'B': CDS_PINID='B';
NET_NAME
'HP_OCP_V3_1_RST'
 '@S9S_MB_2U_LIB.S9S_MB_2U(SCH_1):HP_OCP_V3_1_RST':
 C_SIGNAL='@s9s_mb_2u_lib.s9s_mb_2u(sch_1):hp_ocp_v3_1_rst';
NODE_NAME     U52 2
 '@S9S_MB_2U_LIB.S9S_MB_2U(SCH_1):PAGE154_I228@PURE_QUANTA.APX80929SAG7(CHIPS)':
 'RESET_L': CDS_PINID='RESET_L';
NODE_NAME     R4614 1
 '@S9S_MB_2U_LIB.S9S_MB_2U(SCH_1):PAGE154_I238@PURE_QUANTA.Q_RES(CHIPS)':
 'A': CDS_PINID='A';
NET_NAME
'HP_OCP_V3_1_RST_R'
 '@S9S_MB_2U_LIB.S9S_MB_2U(SCH_1):HP_OCP_V3_1_RST_R':
 C_SIGNAL='@s9s_mb_2u_lib.s9s_mb_2u(sch_1):hp_ocp_v3_1_rst_r';
NODE_NAME     U322 1
 '@S9S_MB_2U_LIB.S9S_MB_2U(SCH_1):PAGE154_I221@PURE_QUANTA.74LVC1G08W57(CHIPS)':
 'A': CDS_PINID='A';
NODE_NAME     R4613 2
 '@S9S_MB_2U_LIB.S9S_MB_2U(SCH_1):PAGE154_I232@PURE_QUANTA.Q_RES(CHIPS)':
 'B': CDS_PINID='B';
NODE_NAME     R3160 2
 '@S9S_MB_2U_LIB.S9S_MB_2U(SCH_1):PAGE154_I235@PURE_QUANTA.Q_RES(CHIPS)':
 'B': CDS_PINID='B';
NODE_NAME     R4614 2
 '@S9S_MB_2U_LIB.S9S_MB_2U(SCH_1):PAGE154_I238@PURE_QUANTA.Q_RES(CHIPS)':
 'B': CDS_PINID='B';
NET_NAME
'HP_OCP_V3_2_EN'
 '@S9S_MB_2U_LIB.S9S_MB_2U(SCH_1):HP_OCP_V3_2_EN':
 C_SIGNAL='@s9s_mb_2u_lib.s9s_mb_2u(sch_1):hp_ocp_v3_2_en';
NODE_NAME     U50 1
 '@S9S_MB_2U_LIB.S9S_MB_2U(SCH_1):PAGE132_I9@PURE_QUANTA.74LVC1G08W57(CHIPS)':
 'A': CDS_PINID='A';
NODE_NAME     U51 6
 '@S9S_MB_2U_LIB.S9S_MB_2U(SCH_1):PAGE132_I66@PURE_QUANTA.PCA9555APW(CHIPS)':
 'P0_2': CDS_PINID='P0_2';
NODE_NAME     R4763 2
 '@S9S_MB_2U_LIB.S9S_MB_2U(SCH_1):PAGE132_I119@PURE_QUANTA.Q_RES(CHIPS)':
 'B': CDS_PINID='B';
NET_NAME
'HP_OCP_V3_2_RST'
 '@S9S_MB_2U_LIB.S9S_MB_2U(SCH_1):HP_OCP_V3_2_RST':
 C_SIGNAL='@s9s_mb_2u_lib.s9s_mb_2u(sch_1):hp_ocp_v3_2_rst';
NODE_NAME     U216 2
 '@S9S_MB_2U_LIB.S9S_MB_2U(SCH_1):PAGE132_I85@PURE_QUANTA.APX80929SAG7(CHIPS)':
 'RESET_L': CDS_PINID='RESET_L';
NODE_NAME     R4616 1
 '@S9S_MB_2U_LIB.S9S_MB_2U(SCH_1):PAGE132_I100@PURE_QUANTA.Q_RES(CHIPS)':
 'A': CDS_PINID='A';
NET_NAME
'HP_OCP_V3_2_RST_R'
 '@S9S_MB_2U_LIB.S9S_MB_2U(SCH_1):HP_OCP_V3_2_RST_R':
 C_SIGNAL='@s9s_mb_2u_lib.s9s_mb_2u(sch_1):hp_ocp_v3_2_rst_r';
NODE_NAME     U323 1
 '@S9S_MB_2U_LIB.S9S_MB_2U(SCH_1):PAGE132_I92@PURE_QUANTA.74LVC1G08W57(CHIPS)':
 'A': CDS_PINID='A';
NODE_NAME     R1132 2
 '@S9S_MB_2U_LIB.S9S_MB_2U(SCH_1):PAGE132_I95@PURE_QUANTA.Q_RES(CHIPS)':
 'B': CDS_PINID='B';
NODE_NAME     R4615 2
 '@S9S_MB_2U_LIB.S9S_MB_2U(SCH_1):PAGE132_I96@PURE_QUANTA.Q_RES(CHIPS)':
 'B': CDS_PINID='B';
NODE_NAME     R4616 2
 '@S9S_MB_2U_LIB.S9S_MB_2U(SCH_1):PAGE132_I100@PURE_QUANTA.Q_RES(CHIPS)':
 'B': CDS_PINID='B';
NET_NAME
'HSC_ADDR'
 '@S9S_MB_2U_LIB.S9S_MB_2U(SCH_1):HSC_ADDR':
 C_SIGNAL='@s9s_mb_2u_lib.s9s_mb_2u(sch_1):hsc_addr';
NODE_NAME     PU289 23
 '@S9S_MB_2U_LIB.S9S_MB_2U(SCH_1):PAGE303_I56@PURE_QUANTA.MP5990GMA1111Z(CHIPS)':
 'ADDR': CDS_PINID='ADDR';
NODE_NAME     PR3930 2
 '@S9S_MB_2U_LIB.S9S_MB_2U(SCH_1):PAGE303_I32@PURE_QUANTA.Q_RES(CHIPS)':
 'B': CDS_PINID='B';
NODE_NAME     PR3929 1
 '@S9S_MB_2U_LIB.S9S_MB_2U(SCH_1):PAGE303_I42@PURE_QUANTA.Q_RES(CHIPS)':
 'A': CDS_PINID='A';
NET_NAME
'HSC_CS'
 '@S9S_MB_2U_LIB.S9S_MB_2U(SCH_1):HSC_CS':
 C_SIGNAL='@s9s_mb_2u_lib.s9s_mb_2u(sch_1):hsc_cs';
NODE_NAME     PU289 20
 '@S9S_MB_2U_LIB.S9S_MB_2U(SCH_1):PAGE303_I56@PURE_QUANTA.MP5990GMA1111Z(CHIPS)':
 'CS': CDS_PINID='CS';
NODE_NAME     PR1131 1
 '@S9S_MB_2U_LIB.S9S_MB_2U(SCH_1):PAGE303_I58@PURE_QUANTA.Q_RES(CHIPS)':
 'A': CDS_PINID='A';
NET_NAME
'HSC_CSOUT'
 '@S9S_MB_2U_LIB.S9S_MB_2U(SCH_1):HSC_CSOUT':
 C_SIGNAL='@s9s_mb_2u_lib.s9s_mb_2u(sch_1):hsc_csout';
NODE_NAME     PJ42 16
 '@S9S_MB_2U_LIB.S9S_MB_2U(SCH_1):PAGE327_I34@PURE_QUANTA.SCONN21_9193031121LF(CHIPS)':
 '16': CDS_PINID='\16\';
NODE_NAME     R4667 1
 '@S9S_MB_2U_LIB.S9S_MB_2U(SCH_1):PAGE326_I14@PURE_QUANTA.Q_RES(CHIPS)':
 'A': CDS_PINID='A';
NODE_NAME     R4669 1
 '@S9S_MB_2U_LIB.S9S_MB_2U(SCH_1):PAGE326_I25@PURE_QUANTA.Q_RES(CHIPS)':
 'A': CDS_PINID='A';
NODE_NAME     R4693 1
 '@S9S_MB_2U_LIB.S9S_MB_2U(SCH_1):PAGE326_I29@PURE_QUANTA.Q_RES(CHIPS)':
 'A': CDS_PINID='A';
NODE_NAME     R4795 1
 '@S9S_MB_2U_LIB.S9S_MB_2U(SCH_1):PAGE326_I78@PURE_QUANTA.Q_RES(CHIPS)':
 'A': CDS_PINID='A';
NET_NAME
'HSC_CS_1'
 '@S9S_MB_2U_LIB.S9S_MB_2U(SCH_1):HSC_CS_1':
 C_SIGNAL='@s9s_mb_2u_lib.s9s_mb_2u(sch_1):hsc_cs_1';
NODE_NAME     PR3914 1
 '@S9S_MB_2U_LIB.S9S_MB_2U(SCH_1):PAGE301_I30@PURE_QUANTA.Q_RES(CHIPS)':
 'A': CDS_PINID='A';
NODE_NAME     PU287 23
 '@S9S_MB_2U_LIB.S9S_MB_2U(SCH_1):PAGE301_I35@PURE_QUANTA.MP5991GLUZ(CHIPS)':
 'CS': CDS_PINID='CS';
NET_NAME
'HSC_CS_2'
 '@S9S_MB_2U_LIB.S9S_MB_2U(SCH_1):HSC_CS_2':
 C_SIGNAL='@s9s_mb_2u_lib.s9s_mb_2u(sch_1):hsc_cs_2';
NODE_NAME     PR3915 1
 '@S9S_MB_2U_LIB.S9S_MB_2U(SCH_1):PAGE301_I12@PURE_QUANTA.Q_RES(CHIPS)':
 'A': CDS_PINID='A';
NODE_NAME     PU288 23
 '@S9S_MB_2U_LIB.S9S_MB_2U(SCH_1):PAGE301_I14@PURE_QUANTA.MP5991GLUZ(CHIPS)':
 'CS': CDS_PINID='CS';
NET_NAME
'HSC_CS_3'
 '@S9S_MB_2U_LIB.S9S_MB_2U(SCH_1):HSC_CS_3':
 C_SIGNAL='@s9s_mb_2u_lib.s9s_mb_2u(sch_1):hsc_cs_3';
NODE_NAME     PR3986 1
 '@S9S_MB_2U_LIB.S9S_MB_2U(SCH_1):PAGE325_I30@PURE_QUANTA.Q_RES(CHIPS)':
 'A': CDS_PINID='A';
NODE_NAME     PU296 23
 '@S9S_MB_2U_LIB.S9S_MB_2U(SCH_1):PAGE325_I35@PURE_QUANTA.MP5991GLUZ(CHIPS)':
 'CS': CDS_PINID='CS';
NET_NAME
'HSC_CS_4'
 '@S9S_MB_2U_LIB.S9S_MB_2U(SCH_1):HSC_CS_4':
 C_SIGNAL='@s9s_mb_2u_lib.s9s_mb_2u(sch_1):hsc_cs_4';
NODE_NAME     PR3987 1
 '@S9S_MB_2U_LIB.S9S_MB_2U(SCH_1):PAGE325_I12@PURE_QUANTA.Q_RES(CHIPS)':
 'A': CDS_PINID='A';
NODE_NAME     PU297 23
 '@S9S_MB_2U_LIB.S9S_MB_2U(SCH_1):PAGE325_I17@PURE_QUANTA.MP5991GLUZ(CHIPS)':
 'CS': CDS_PINID='CS';
NET_NAME
'HSC_D_OC'
 '@S9S_MB_2U_LIB.S9S_MB_2U(SCH_1):HSC_D_OC':
 C_SIGNAL='@s9s_mb_2u_lib.s9s_mb_2u(sch_1):hsc_d_oc';
NODE_NAME     R4056 1
 '@S9S_MB_2U_LIB.S9S_MB_2U(SCH_1):PAGE312_I80@PURE_QUANTA.Q_RES(CHIPS)':
 'A': CDS_PINID='A';
NODE_NAME     R3936 2
 '@S9S_MB_2U_LIB.S9S_MB_2U(SCH_1):PAGE303_I85@PURE_QUANTA.Q_RES(CHIPS)':
 'B': CDS_PINID='B';
NODE_NAME     R4693 2
 '@S9S_MB_2U_LIB.S9S_MB_2U(SCH_1):PAGE326_I29@PURE_QUANTA.Q_RES(CHIPS)':
 'B': CDS_PINID='B';
NODE_NAME     U369 6
 '@S9S_MB_2U_LIB.S9S_MB_2U(SCH_1):PAGE326_I30@PURE_QUANTA.TPS3700DDCR(CHIPS)':
 'OUTB': CDS_PINID='OUTB';
NODE_NAME     R4652 2
 '@S9S_MB_2U_LIB.S9S_MB_2U(SCH_1):PAGE326_I48@PURE_QUANTA.Q_RES(CHIPS)':
 'B': CDS_PINID='B';
NODE_NAME     R4671 2
 '@S9S_MB_2U_LIB.S9S_MB_2U(SCH_1):PAGE326_I51@PURE_QUANTA.Q_RES(CHIPS)':
 'B': CDS_PINID='B';
NODE_NAME     R3934 2
 '@S9S_MB_2U_LIB.S9S_MB_2U(SCH_1):PAGE303_I82@PURE_QUANTA.Q_RES(CHIPS)':
 'B': CDS_PINID='B';
NET_NAME
'HSC_D_OC_1'
 '@S9S_MB_2U_LIB.S9S_MB_2U(SCH_1):HSC_D_OC_1':
 C_SIGNAL='@s9s_mb_2u_lib.s9s_mb_2u(sch_1):hsc_d_oc_1';
NODE_NAME     PR3919 1
 '@S9S_MB_2U_LIB.S9S_MB_2U(SCH_1):PAGE301_I49@PURE_QUANTA.Q_RES(CHIPS)':
 'A': CDS_PINID='A';
NODE_NAME     PU287 3
 '@S9S_MB_2U_LIB.S9S_MB_2U(SCH_1):PAGE301_I35@PURE_QUANTA.MP5991GLUZ(CHIPS)':
 'D_OC': CDS_PINID='D_OC';
NET_NAME
'HSC_D_OC_2'
 '@S9S_MB_2U_LIB.S9S_MB_2U(SCH_1):HSC_D_OC_2':
 C_SIGNAL='@s9s_mb_2u_lib.s9s_mb_2u(sch_1):hsc_d_oc_2';
NODE_NAME     PR3921 1
 '@S9S_MB_2U_LIB.S9S_MB_2U(SCH_1):PAGE301_I39@PURE_QUANTA.Q_RES(CHIPS)':
 'A': CDS_PINID='A';
NODE_NAME     PU288 3
 '@S9S_MB_2U_LIB.S9S_MB_2U(SCH_1):PAGE301_I14@PURE_QUANTA.MP5991GLUZ(CHIPS)':
 'D_OC': CDS_PINID='D_OC';
NET_NAME
'HSC_D_OC_3'
 '@S9S_MB_2U_LIB.S9S_MB_2U(SCH_1):HSC_D_OC_3':
 C_SIGNAL='@s9s_mb_2u_lib.s9s_mb_2u(sch_1):hsc_d_oc_3';
NODE_NAME     PU296 3
 '@S9S_MB_2U_LIB.S9S_MB_2U(SCH_1):PAGE325_I35@PURE_QUANTA.MP5991GLUZ(CHIPS)':
 'D_OC': CDS_PINID='D_OC';
NODE_NAME     PR3992 1
 '@S9S_MB_2U_LIB.S9S_MB_2U(SCH_1):PAGE325_I50@PURE_QUANTA.Q_RES(CHIPS)':
 'A': CDS_PINID='A';
NET_NAME
'HSC_D_OC_4'
 '@S9S_MB_2U_LIB.S9S_MB_2U(SCH_1):HSC_D_OC_4':
 C_SIGNAL='@s9s_mb_2u_lib.s9s_mb_2u(sch_1):hsc_d_oc_4';
NODE_NAME     PU297 3
 '@S9S_MB_2U_LIB.S9S_MB_2U(SCH_1):PAGE325_I17@PURE_QUANTA.MP5991GLUZ(CHIPS)':
 'D_OC': CDS_PINID='D_OC';
NODE_NAME     PR3994 1
 '@S9S_MB_2U_LIB.S9S_MB_2U(SCH_1):PAGE325_I40@PURE_QUANTA.Q_RES(CHIPS)':
 'A': CDS_PINID='A';
NET_NAME
'HSC_D_OC_R'
 '@S9S_MB_2U_LIB.S9S_MB_2U(SCH_1):HSC_D_OC_R':
 C_SIGNAL='@s9s_mb_2u_lib.s9s_mb_2u(sch_1):hsc_d_oc_r';
NODE_NAME     PR3921 2
 '@S9S_MB_2U_LIB.S9S_MB_2U(SCH_1):PAGE301_I39@PURE_QUANTA.Q_RES(CHIPS)':
 'B': CDS_PINID='B';
NODE_NAME     PR3919 2
 '@S9S_MB_2U_LIB.S9S_MB_2U(SCH_1):PAGE301_I49@PURE_QUANTA.Q_RES(CHIPS)':
 'B': CDS_PINID='B';
NODE_NAME     PU289 37
 '@S9S_MB_2U_LIB.S9S_MB_2U(SCH_1):PAGE303_I56@PURE_QUANTA.MP5990GMA1111Z(CHIPS)':
 'D_OC': CDS_PINID='D_OC';
NODE_NAME     PR3994 2
 '@S9S_MB_2U_LIB.S9S_MB_2U(SCH_1):PAGE325_I40@PURE_QUANTA.Q_RES(CHIPS)':
 'B': CDS_PINID='B';
NODE_NAME     PR3992 2
 '@S9S_MB_2U_LIB.S9S_MB_2U(SCH_1):PAGE325_I50@PURE_QUANTA.Q_RES(CHIPS)':
 'B': CDS_PINID='B';
NODE_NAME     R3934 1
 '@S9S_MB_2U_LIB.S9S_MB_2U(SCH_1):PAGE303_I82@PURE_QUANTA.Q_RES(CHIPS)':
 'A': CDS_PINID='A';
NET_NAME
'HSC_D_OC_R1'
 '@S9S_MB_2U_LIB.S9S_MB_2U(SCH_1):HSC_D_OC_R1':
 C_SIGNAL='@s9s_mb_2u_lib.s9s_mb_2u(sch_1):hsc_d_oc_r1';
NODE_NAME     U249 W10
 '@S9S_MB_2U_LIB.S9S_MB_2U(SCH_1):PAGE312_I1@PURE_QUANTA.LCMXO3LF9400C5BG484C(CHIPS)':
 'PB21B': CDS_PINID='PB21B';
NODE_NAME     R4056 2
 '@S9S_MB_2U_LIB.S9S_MB_2U(SCH_1):PAGE312_I80@PURE_QUANTA.Q_RES(CHIPS)':
 'B': CDS_PINID='B';
NET_NAME
'HSC_D_OC_R2'
 '@S9S_MB_2U_LIB.S9S_MB_2U(SCH_1):HSC_D_OC_R2':
 C_SIGNAL='@s9s_mb_2u_lib.s9s_mb_2u(sch_1):hsc_d_oc_r2';
NODE_NAME     U344 4
 '@S9S_MB_2U_LIB.S9S_MB_2U(SCH_1):PAGE326_I66@PURE_QUANTA.AP331AWG7(CHIPS)':
 'OUTPUT': CDS_PINID='OUTPUT';
NODE_NAME     R4793 2
 '@S9S_MB_2U_LIB.S9S_MB_2U(SCH_1):PAGE326_I68@PURE_QUANTA.Q_RES(CHIPS)':
 'B': CDS_PINID='B';
NODE_NAME     R4794 1
 '@S9S_MB_2U_LIB.S9S_MB_2U(SCH_1):PAGE326_I72@PURE_QUANTA.Q_RES(CHIPS)':
 'A': CDS_PINID='A';
NET_NAME
'HSC_EN'
 '@S9S_MB_2U_LIB.S9S_MB_2U(SCH_1):HSC_EN':
 C_SIGNAL='@s9s_mb_2u_lib.s9s_mb_2u(sch_1):hsc_en';
NODE_NAME     U290 D
 '@S9S_MB_2U_LIB.S9S_MB_2U(SCH_1):PAGE303_I5@PURE_QUANTA.MOSFET_NCH_GDS_ESD_PROTECTED(CHIPS)':
 'D': CDS_PINID='D';
NODE_NAME     R2585 1
 '@S9S_MB_2U_LIB.S9S_MB_2U(SCH_1):PAGE303_I7@PURE_QUANTA.Q_RES(CHIPS)':
 'A': CDS_PINID='A';
NODE_NAME     PJ42 14
 '@S9S_MB_2U_LIB.S9S_MB_2U(SCH_1):PAGE327_I34@PURE_QUANTA.SCONN21_9193031121LF(CHIPS)':
 '14': CDS_PINID='\14\';
NODE_NAME     R4901 2
 '@S9S_MB_2U_LIB.S9S_MB_2U(SCH_1):PAGE303_I26@PURE_QUANTA.Q_RES(CHIPS)':
 'B': CDS_PINID='B';
NODE_NAME     C2179 1
 '@S9S_MB_2U_LIB.S9S_MB_2U(SCH_1):PAGE303_I29@PURE_QUANTA.Q_CAP(CHIPS)':
 'A': CDS_PINID='A';
NODE_NAME     R2586 1
 '@S9S_MB_2U_LIB.S9S_MB_2U(SCH_1):PAGE303_I44@PURE_QUANTA.Q_RES(CHIPS)':
 'A': CDS_PINID='A';
NET_NAME
'HSC_EN_R'
 '@S9S_MB_2U_LIB.S9S_MB_2U(SCH_1):HSC_EN_R':
 C_SIGNAL='@s9s_mb_2u_lib.s9s_mb_2u(sch_1):hsc_en_r';
NODE_NAME     PU289 26
 '@S9S_MB_2U_LIB.S9S_MB_2U(SCH_1):PAGE303_I56@PURE_QUANTA.MP5990GMA1111Z(CHIPS)':
 'EN': CDS_PINID='EN';
NODE_NAME     R2586 2
 '@S9S_MB_2U_LIB.S9S_MB_2U(SCH_1):PAGE303_I44@PURE_QUANTA.Q_RES(CHIPS)':
 'B': CDS_PINID='B';
NET_NAME
'HSC_FAULT'
 '@S9S_MB_2U_LIB.S9S_MB_2U(SCH_1):HSC_FAULT':
 C_SIGNAL='@s9s_mb_2u_lib.s9s_mb_2u(sch_1):hsc_fault';
NODE_NAME     PU297 5
 '@S9S_MB_2U_LIB.S9S_MB_2U(SCH_1):PAGE325_I17@PURE_QUANTA.MP5991GLUZ(CHIPS)':
 'GOK': CDS_PINID='GOK';
NODE_NAME     PU289 39
 '@S9S_MB_2U_LIB.S9S_MB_2U(SCH_1):PAGE303_I56@PURE_QUANTA.MP5990GMA1111Z(CHIPS)':
 'GOK': CDS_PINID='GOK';
NODE_NAME     PU296 5
 '@S9S_MB_2U_LIB.S9S_MB_2U(SCH_1):PAGE325_I35@PURE_QUANTA.MP5991GLUZ(CHIPS)':
 'GOK': CDS_PINID='GOK';
NODE_NAME     R2588 1
 '@S9S_MB_2U_LIB.S9S_MB_2U(SCH_1):PAGE303_I81@PURE_QUANTA.Q_RES(CHIPS)':
 'A': CDS_PINID='A';
NODE_NAME     PU287 5
 '@S9S_MB_2U_LIB.S9S_MB_2U(SCH_1):PAGE301_I35@PURE_QUANTA.MP5991GLUZ(CHIPS)':
 'GOK': CDS_PINID='GOK';
NODE_NAME     PU288 5
 '@S9S_MB_2U_LIB.S9S_MB_2U(SCH_1):PAGE301_I14@PURE_QUANTA.MP5991GLUZ(CHIPS)':
 'GOK': CDS_PINID='GOK';
NET_NAME
'HSC_FLT_TYPE'
 '@S9S_MB_2U_LIB.S9S_MB_2U(SCH_1):HSC_FLT_TYPE':
 C_SIGNAL='@s9s_mb_2u_lib.s9s_mb_2u(sch_1):hsc_flt_type';
NODE_NAME     PR3995 2
 '@S9S_MB_2U_LIB.S9S_MB_2U(SCH_1):PAGE325_I39@PURE_QUANTA.Q_RES(CHIPS)':
 'B': CDS_PINID='B';
NODE_NAME     PR3993 2
 '@S9S_MB_2U_LIB.S9S_MB_2U(SCH_1):PAGE325_I49@PURE_QUANTA.Q_RES(CHIPS)':
 'B': CDS_PINID='B';
NODE_NAME     PU289 40
 '@S9S_MB_2U_LIB.S9S_MB_2U(SCH_1):PAGE303_I56@PURE_QUANTA.MP5990GMA1111Z(CHIPS)':
 'FLT_TYPE': CDS_PINID='FLT_TYPE';
NODE_NAME     PR3922 2
 '@S9S_MB_2U_LIB.S9S_MB_2U(SCH_1):PAGE301_I40@PURE_QUANTA.Q_RES(CHIPS)':
 'B': CDS_PINID='B';
NODE_NAME     PR3920 2
 '@S9S_MB_2U_LIB.S9S_MB_2U(SCH_1):PAGE301_I50@PURE_QUANTA.Q_RES(CHIPS)':
 'B': CDS_PINID='B';
NET_NAME
'HSC_FLT_TYPE_1'
 '@S9S_MB_2U_LIB.S9S_MB_2U(SCH_1):HSC_FLT_TYPE_1':
 C_SIGNAL='@s9s_mb_2u_lib.s9s_mb_2u(sch_1):hsc_flt_type_1';
NODE_NAME     PU287 6
 '@S9S_MB_2U_LIB.S9S_MB_2U(SCH_1):PAGE301_I35@PURE_QUANTA.MP5991GLUZ(CHIPS)':
 'FLT_TYPE': CDS_PINID='FLT_TYPE';
NODE_NAME     PR3920 1
 '@S9S_MB_2U_LIB.S9S_MB_2U(SCH_1):PAGE301_I50@PURE_QUANTA.Q_RES(CHIPS)':
 'A': CDS_PINID='A';
NET_NAME
'HSC_FLT_TYPE_2'
 '@S9S_MB_2U_LIB.S9S_MB_2U(SCH_1):HSC_FLT_TYPE_2':
 C_SIGNAL='@s9s_mb_2u_lib.s9s_mb_2u(sch_1):hsc_flt_type_2';
NODE_NAME     PR3922 1
 '@S9S_MB_2U_LIB.S9S_MB_2U(SCH_1):PAGE301_I40@PURE_QUANTA.Q_RES(CHIPS)':
 'A': CDS_PINID='A';
NODE_NAME     PU288 6
 '@S9S_MB_2U_LIB.S9S_MB_2U(SCH_1):PAGE301_I14@PURE_QUANTA.MP5991GLUZ(CHIPS)':
 'FLT_TYPE': CDS_PINID='FLT_TYPE';
NET_NAME
'HSC_FLT_TYPE_3'
 '@S9S_MB_2U_LIB.S9S_MB_2U(SCH_1):HSC_FLT_TYPE_3':
 C_SIGNAL='@s9s_mb_2u_lib.s9s_mb_2u(sch_1):hsc_flt_type_3';
NODE_NAME     PR3993 1
 '@S9S_MB_2U_LIB.S9S_MB_2U(SCH_1):PAGE325_I49@PURE_QUANTA.Q_RES(CHIPS)':
 'A': CDS_PINID='A';
NODE_NAME     PU296 6
 '@S9S_MB_2U_LIB.S9S_MB_2U(SCH_1):PAGE325_I35@PURE_QUANTA.MP5991GLUZ(CHIPS)':
 'FLT_TYPE': CDS_PINID='FLT_TYPE';
NET_NAME
'HSC_FLT_TYPE_4'
 '@S9S_MB_2U_LIB.S9S_MB_2U(SCH_1):HSC_FLT_TYPE_4':
 C_SIGNAL='@s9s_mb_2u_lib.s9s_mb_2u(sch_1):hsc_flt_type_4';
NODE_NAME     PR3995 1
 '@S9S_MB_2U_LIB.S9S_MB_2U(SCH_1):PAGE325_I39@PURE_QUANTA.Q_RES(CHIPS)':
 'A': CDS_PINID='A';
NODE_NAME     PU297 6
 '@S9S_MB_2U_LIB.S9S_MB_2U(SCH_1):PAGE325_I17@PURE_QUANTA.MP5991GLUZ(CHIPS)':
 'FLT_TYPE': CDS_PINID='FLT_TYPE';
NET_NAME
'HSC_IMON'
 '@S9S_MB_2U_LIB.S9S_MB_2U(SCH_1):HSC_IMON':
 C_SIGNAL='@s9s_mb_2u_lib.s9s_mb_2u(sch_1):hsc_imon';
NODE_NAME     PR1101 1
 '@S9S_MB_2U_LIB.S9S_MB_2U(SCH_1):PAGE301_I13@PURE_QUANTA.Q_RES(CHIPS)':
 'A': CDS_PINID='A';
NODE_NAME     PR3991 1
 '@S9S_MB_2U_LIB.S9S_MB_2U(SCH_1):PAGE325_I13@PURE_QUANTA.Q_RES(CHIPS)':
 'A': CDS_PINID='A';
NODE_NAME     PR3990 1
 '@S9S_MB_2U_LIB.S9S_MB_2U(SCH_1):PAGE325_I34@PURE_QUANTA.Q_RES(CHIPS)':
 'A': CDS_PINID='A';
NODE_NAME     PR3918 1
 '@S9S_MB_2U_LIB.S9S_MB_2U(SCH_1):PAGE301_I34@PURE_QUANTA.Q_RES(CHIPS)':
 'A': CDS_PINID='A';
NODE_NAME     PU297 22
 '@S9S_MB_2U_LIB.S9S_MB_2U(SCH_1):PAGE325_I17@PURE_QUANTA.MP5991GLUZ(CHIPS)':
 'IMON': CDS_PINID='IMON';
NODE_NAME     PU289 21
 '@S9S_MB_2U_LIB.S9S_MB_2U(SCH_1):PAGE303_I56@PURE_QUANTA.MP5990GMA1111Z(CHIPS)':
 'IMON': CDS_PINID='IMON';
NODE_NAME     PU296 22
 '@S9S_MB_2U_LIB.S9S_MB_2U(SCH_1):PAGE325_I35@PURE_QUANTA.MP5991GLUZ(CHIPS)':
 'IMON': CDS_PINID='IMON';
NODE_NAME     PU287 22
 '@S9S_MB_2U_LIB.S9S_MB_2U(SCH_1):PAGE301_I35@PURE_QUANTA.MP5991GLUZ(CHIPS)':
 'IMON': CDS_PINID='IMON';
NODE_NAME     PU288 22
 '@S9S_MB_2U_LIB.S9S_MB_2U(SCH_1):PAGE301_I14@PURE_QUANTA.MP5991GLUZ(CHIPS)':
 'IMON': CDS_PINID='IMON';
NODE_NAME     PC2193 1
 '@S9S_MB_2U_LIB.S9S_MB_2U(SCH_1):PAGE303_I89@PURE_QUANTA.Q_CAP(CHIPS)':
 'A': CDS_PINID='A';
NODE_NAME     PR1133 1
 '@S9S_MB_2U_LIB.S9S_MB_2U(SCH_1):PAGE303_I91@PURE_QUANTA.Q_RES(CHIPS)':
 'A': CDS_PINID='A';
NET_NAME
'HSC_MODE'
 '@S9S_MB_2U_LIB.S9S_MB_2U(SCH_1):HSC_MODE':
 C_SIGNAL='@s9s_mb_2u_lib.s9s_mb_2u(sch_1):hsc_mode';
NODE_NAME     PU289 41
 '@S9S_MB_2U_LIB.S9S_MB_2U(SCH_1):PAGE303_I56@PURE_QUANTA.MP5990GMA1111Z(CHIPS)':
 'MODE': CDS_PINID='MODE';
NODE_NAME     PR3937 1
 '@S9S_MB_2U_LIB.S9S_MB_2U(SCH_1):PAGE303_I84@PURE_QUANTA.Q_RES(CHIPS)':
 'A': CDS_PINID='A';
NET_NAME
'HSC_MODE_1'
 '@S9S_MB_2U_LIB.S9S_MB_2U(SCH_1):HSC_MODE_1':
 C_SIGNAL='@s9s_mb_2u_lib.s9s_mb_2u(sch_1):hsc_mode_1';
NODE_NAME     PU287 8
 '@S9S_MB_2U_LIB.S9S_MB_2U(SCH_1):PAGE301_I35@PURE_QUANTA.MP5991GLUZ(CHIPS)':
 'MODE': CDS_PINID='MODE';
NODE_NAME     PR1134 2
 '@S9S_MB_2U_LIB.S9S_MB_2U(SCH_1):PAGE301_I32@PURE_QUANTA.Q_RES(CHIPS)':
 'B': CDS_PINID='B';
NET_NAME
'HSC_MODE_2'
 '@S9S_MB_2U_LIB.S9S_MB_2U(SCH_1):HSC_MODE_2':
 C_SIGNAL='@s9s_mb_2u_lib.s9s_mb_2u(sch_1):hsc_mode_2';
NODE_NAME     PR3912 2
 '@S9S_MB_2U_LIB.S9S_MB_2U(SCH_1):PAGE301_I15@PURE_QUANTA.Q_RES(CHIPS)':
 'B': CDS_PINID='B';
NODE_NAME     PU288 8
 '@S9S_MB_2U_LIB.S9S_MB_2U(SCH_1):PAGE301_I14@PURE_QUANTA.MP5991GLUZ(CHIPS)':
 'MODE': CDS_PINID='MODE';
NET_NAME
'HSC_MODE_3'
 '@S9S_MB_2U_LIB.S9S_MB_2U(SCH_1):HSC_MODE_3':
 C_SIGNAL='@s9s_mb_2u_lib.s9s_mb_2u(sch_1):hsc_mode_3';
NODE_NAME     PU296 8
 '@S9S_MB_2U_LIB.S9S_MB_2U(SCH_1):PAGE325_I35@PURE_QUANTA.MP5991GLUZ(CHIPS)':
 'MODE': CDS_PINID='MODE';
NODE_NAME     PR3982 2
 '@S9S_MB_2U_LIB.S9S_MB_2U(SCH_1):PAGE325_I32@PURE_QUANTA.Q_RES(CHIPS)':
 'B': CDS_PINID='B';
NET_NAME
'HSC_MODE_4'
 '@S9S_MB_2U_LIB.S9S_MB_2U(SCH_1):HSC_MODE_4':
 C_SIGNAL='@s9s_mb_2u_lib.s9s_mb_2u(sch_1):hsc_mode_4';
NODE_NAME     PU297 8
 '@S9S_MB_2U_LIB.S9S_MB_2U(SCH_1):PAGE325_I17@PURE_QUANTA.MP5991GLUZ(CHIPS)':
 'MODE': CDS_PINID='MODE';
NODE_NAME     PR3984 2
 '@S9S_MB_2U_LIB.S9S_MB_2U(SCH_1):PAGE325_I14@PURE_QUANTA.Q_RES(CHIPS)':
 'B': CDS_PINID='B';
NET_NAME
'HSC_NC1_1'
 '@S9S_MB_2U_LIB.S9S_MB_2U(SCH_1):HSC_NC1_1':
 C_SIGNAL='@s9s_mb_2u_lib.s9s_mb_2u(sch_1):hsc_nc1_1';
NODE_NAME     PU287 7
 '@S9S_MB_2U_LIB.S9S_MB_2U(SCH_1):PAGE301_I35@PURE_QUANTA.MP5991GLUZ(CHIPS)':
 'NC1': CDS_PINID='NC1';
NET_NAME
'HSC_NC1_2'
 '@S9S_MB_2U_LIB.S9S_MB_2U(SCH_1):HSC_NC1_2':
 C_SIGNAL='@s9s_mb_2u_lib.s9s_mb_2u(sch_1):hsc_nc1_2';
NODE_NAME     PU288 7
 '@S9S_MB_2U_LIB.S9S_MB_2U(SCH_1):PAGE301_I14@PURE_QUANTA.MP5991GLUZ(CHIPS)':
 'NC1': CDS_PINID='NC1';
NET_NAME
'HSC_NC1_3'
 '@S9S_MB_2U_LIB.S9S_MB_2U(SCH_1):HSC_NC1_3':
 C_SIGNAL='@s9s_mb_2u_lib.s9s_mb_2u(sch_1):hsc_nc1_3';
NODE_NAME     PU296 7
 '@S9S_MB_2U_LIB.S9S_MB_2U(SCH_1):PAGE325_I35@PURE_QUANTA.MP5991GLUZ(CHIPS)':
 'NC1': CDS_PINID='NC1';
NET_NAME
'HSC_NC1_4'
 '@S9S_MB_2U_LIB.S9S_MB_2U(SCH_1):HSC_NC1_4':
 C_SIGNAL='@s9s_mb_2u_lib.s9s_mb_2u(sch_1):hsc_nc1_4';
NODE_NAME     PU297 7
 '@S9S_MB_2U_LIB.S9S_MB_2U(SCH_1):PAGE325_I17@PURE_QUANTA.MP5991GLUZ(CHIPS)':
 'NC1': CDS_PINID='NC1';
NET_NAME
'HSC_OCREF'
 '@S9S_MB_2U_LIB.S9S_MB_2U(SCH_1):HSC_OCREF':
 C_SIGNAL='@s9s_mb_2u_lib.s9s_mb_2u(sch_1):hsc_ocref';
NODE_NAME     PC2347 1
 '@S9S_MB_2U_LIB.S9S_MB_2U(SCH_1):PAGE301_I29@PURE_QUANTA.Q_CAP(CHIPS)':
 'A': CDS_PINID='A';
NODE_NAME     PC2349 1
 '@S9S_MB_2U_LIB.S9S_MB_2U(SCH_1):PAGE325_I11@PURE_QUANTA.Q_CAP(CHIPS)':
 'A': CDS_PINID='A';
NODE_NAME     PC2348 1
 '@S9S_MB_2U_LIB.S9S_MB_2U(SCH_1):PAGE301_I11@PURE_QUANTA.Q_CAP(CHIPS)':
 'A': CDS_PINID='A';
NODE_NAME     PU297 24
 '@S9S_MB_2U_LIB.S9S_MB_2U(SCH_1):PAGE325_I17@PURE_QUANTA.MP5991GLUZ(CHIPS)':
 'OCREF': CDS_PINID='OCREF';
NODE_NAME     PU289 22
 '@S9S_MB_2U_LIB.S9S_MB_2U(SCH_1):PAGE303_I56@PURE_QUANTA.MP5990GMA1111Z(CHIPS)':
 'OCREF': CDS_PINID='OCREF';
NODE_NAME     PU296 24
 '@S9S_MB_2U_LIB.S9S_MB_2U(SCH_1):PAGE325_I35@PURE_QUANTA.MP5991GLUZ(CHIPS)':
 'OCREF': CDS_PINID='OCREF';
NODE_NAME     PU287 24
 '@S9S_MB_2U_LIB.S9S_MB_2U(SCH_1):PAGE301_I35@PURE_QUANTA.MP5991GLUZ(CHIPS)':
 'OCREF': CDS_PINID='OCREF';
NODE_NAME     PU288 24
 '@S9S_MB_2U_LIB.S9S_MB_2U(SCH_1):PAGE301_I14@PURE_QUANTA.MP5991GLUZ(CHIPS)':
 'OCREF': CDS_PINID='OCREF';
NODE_NAME     PC2350 1
 '@S9S_MB_2U_LIB.S9S_MB_2U(SCH_1):PAGE325_I29@PURE_QUANTA.Q_CAP(CHIPS)':
 'A': CDS_PINID='A';
NET_NAME
'HSC_OC_VOL'
 '@S9S_MB_2U_LIB.S9S_MB_2U(SCH_1):HSC_OC_VOL':
 C_SIGNAL='@s9s_mb_2u_lib.s9s_mb_2u(sch_1):hsc_oc_vol';
NODE_NAME     U344 3
 '@S9S_MB_2U_LIB.S9S_MB_2U(SCH_1):PAGE326_I66@PURE_QUANTA.AP331AWG7(CHIPS)':
 'IN+': CDS_PINID='\in+\';
NODE_NAME     R4793 1
 '@S9S_MB_2U_LIB.S9S_MB_2U(SCH_1):PAGE326_I68@PURE_QUANTA.Q_RES(CHIPS)':
 'A': CDS_PINID='A';
NODE_NAME     C2389 1
 '@S9S_MB_2U_LIB.S9S_MB_2U(SCH_1):PAGE326_I76@PURE_QUANTA.Q_CAP(CHIPS)':
 'A': CDS_PINID='A';
NODE_NAME     R4796 1
 '@S9S_MB_2U_LIB.S9S_MB_2U(SCH_1):PAGE326_I77@PURE_QUANTA.Q_RES(CHIPS)':
 'A': CDS_PINID='A';
NODE_NAME     R4795 2
 '@S9S_MB_2U_LIB.S9S_MB_2U(SCH_1):PAGE326_I78@PURE_QUANTA.Q_RES(CHIPS)':
 'B': CDS_PINID='B';
NET_NAME
'HSC_ON'
 '@S9S_MB_2U_LIB.S9S_MB_2U(SCH_1):HSC_ON':
 C_SIGNAL='@s9s_mb_2u_lib.s9s_mb_2u(sch_1):hsc_on';
NODE_NAME     PC2183 1
 '@S9S_MB_2U_LIB.S9S_MB_2U(SCH_1):PAGE301_I2@PURE_QUANTA.Q_CAP(CHIPS)':
 'A': CDS_PINID='A';
NODE_NAME     PU297 4
 '@S9S_MB_2U_LIB.S9S_MB_2U(SCH_1):PAGE325_I17@PURE_QUANTA.MP5991GLUZ(CHIPS)':
 'ON': CDS_PINID='\on\';
NODE_NAME     PU296 4
 '@S9S_MB_2U_LIB.S9S_MB_2U(SCH_1):PAGE325_I35@PURE_QUANTA.MP5991GLUZ(CHIPS)':
 'ON': CDS_PINID='\on\';
NODE_NAME     PU287 4
 '@S9S_MB_2U_LIB.S9S_MB_2U(SCH_1):PAGE301_I35@PURE_QUANTA.MP5991GLUZ(CHIPS)':
 'ON': CDS_PINID='\on\';
NODE_NAME     PU288 4
 '@S9S_MB_2U_LIB.S9S_MB_2U(SCH_1):PAGE301_I14@PURE_QUANTA.MP5991GLUZ(CHIPS)':
 'ON': CDS_PINID='\on\';
NODE_NAME     PR3928 1
 '@S9S_MB_2U_LIB.S9S_MB_2U(SCH_1):PAGE303_I41@PURE_QUANTA.Q_RES(CHIPS)':
 'A': CDS_PINID='A';
NODE_NAME     PC2224 1
 '@S9S_MB_2U_LIB.S9S_MB_2U(SCH_1):PAGE325_I23@PURE_QUANTA.Q_CAP(CHIPS)':
 'A': CDS_PINID='A';
NODE_NAME     PC2182 1
 '@S9S_MB_2U_LIB.S9S_MB_2U(SCH_1):PAGE301_I23@PURE_QUANTA.Q_CAP(CHIPS)':
 'A': CDS_PINID='A';
NODE_NAME     PC2225 1
 '@S9S_MB_2U_LIB.S9S_MB_2U(SCH_1):PAGE325_I2@PURE_QUANTA.Q_CAP(CHIPS)':
 'A': CDS_PINID='A';
NET_NAME
'HSC_ON_R'
 '@S9S_MB_2U_LIB.S9S_MB_2U(SCH_1):HSC_ON_R':
 C_SIGNAL='@s9s_mb_2u_lib.s9s_mb_2u(sch_1):hsc_on_r';
NODE_NAME     PU289 38
 '@S9S_MB_2U_LIB.S9S_MB_2U(SCH_1):PAGE303_I56@PURE_QUANTA.MP5990GMA1111Z(CHIPS)':
 'ON': CDS_PINID='\on\';
NODE_NAME     PR3928 2
 '@S9S_MB_2U_LIB.S9S_MB_2U(SCH_1):PAGE303_I41@PURE_QUANTA.Q_RES(CHIPS)':
 'B': CDS_PINID='B';
NET_NAME
'HSC_SCREF'
 '@S9S_MB_2U_LIB.S9S_MB_2U(SCH_1):HSC_SCREF':
 C_SIGNAL='@s9s_mb_2u_lib.s9s_mb_2u(sch_1):hsc_scref';
NODE_NAME     PR3916 1
 '@S9S_MB_2U_LIB.S9S_MB_2U(SCH_1):PAGE301_I33@PURE_QUANTA.Q_RES(CHIPS)':
 'A': CDS_PINID='A';
NODE_NAME     PR3989 1
 '@S9S_MB_2U_LIB.S9S_MB_2U(SCH_1):PAGE325_I16@PURE_QUANTA.Q_RES(CHIPS)':
 'A': CDS_PINID='A';
NODE_NAME     PU289 25
 '@S9S_MB_2U_LIB.S9S_MB_2U(SCH_1):PAGE303_I56@PURE_QUANTA.MP5990GMA1111Z(CHIPS)':
 'SCREF_OCWREF': CDS_PINID='SCREF_OCWREF';
NODE_NAME     PR3917 1
 '@S9S_MB_2U_LIB.S9S_MB_2U(SCH_1):PAGE301_I17@PURE_QUANTA.Q_RES(CHIPS)':
 'A': CDS_PINID='A';
NODE_NAME     PR3988 1
 '@S9S_MB_2U_LIB.S9S_MB_2U(SCH_1):PAGE325_I33@PURE_QUANTA.Q_RES(CHIPS)':
 'A': CDS_PINID='A';
NET_NAME
'HSC_SCREF_1'
 '@S9S_MB_2U_LIB.S9S_MB_2U(SCH_1):HSC_SCREF_1':
 C_SIGNAL='@s9s_mb_2u_lib.s9s_mb_2u(sch_1):hsc_scref_1';
NODE_NAME     PR3916 2
 '@S9S_MB_2U_LIB.S9S_MB_2U(SCH_1):PAGE301_I33@PURE_QUANTA.Q_RES(CHIPS)':
 'B': CDS_PINID='B';
NODE_NAME     PU287 17
 '@S9S_MB_2U_LIB.S9S_MB_2U(SCH_1):PAGE301_I35@PURE_QUANTA.MP5991GLUZ(CHIPS)':
 'SCREF_OCWREF': CDS_PINID='SCREF_OCWREF';
NET_NAME
'HSC_SCREF_2'
 '@S9S_MB_2U_LIB.S9S_MB_2U(SCH_1):HSC_SCREF_2':
 C_SIGNAL='@s9s_mb_2u_lib.s9s_mb_2u(sch_1):hsc_scref_2';
NODE_NAME     PR3917 2
 '@S9S_MB_2U_LIB.S9S_MB_2U(SCH_1):PAGE301_I17@PURE_QUANTA.Q_RES(CHIPS)':
 'B': CDS_PINID='B';
NODE_NAME     PU288 17
 '@S9S_MB_2U_LIB.S9S_MB_2U(SCH_1):PAGE301_I14@PURE_QUANTA.MP5991GLUZ(CHIPS)':
 'SCREF_OCWREF': CDS_PINID='SCREF_OCWREF';
NET_NAME
'HSC_SCREF_3'
 '@S9S_MB_2U_LIB.S9S_MB_2U(SCH_1):HSC_SCREF_3':
 C_SIGNAL='@s9s_mb_2u_lib.s9s_mb_2u(sch_1):hsc_scref_3';
NODE_NAME     PU296 17
 '@S9S_MB_2U_LIB.S9S_MB_2U(SCH_1):PAGE325_I35@PURE_QUANTA.MP5991GLUZ(CHIPS)':
 'SCREF_OCWREF': CDS_PINID='SCREF_OCWREF';
NODE_NAME     PR3988 2
 '@S9S_MB_2U_LIB.S9S_MB_2U(SCH_1):PAGE325_I33@PURE_QUANTA.Q_RES(CHIPS)':
 'B': CDS_PINID='B';
NET_NAME
'HSC_SCREF_4'
 '@S9S_MB_2U_LIB.S9S_MB_2U(SCH_1):HSC_SCREF_4':
 C_SIGNAL='@s9s_mb_2u_lib.s9s_mb_2u(sch_1):hsc_scref_4';
NODE_NAME     PR3989 2
 '@S9S_MB_2U_LIB.S9S_MB_2U(SCH_1):PAGE325_I16@PURE_QUANTA.Q_RES(CHIPS)':
 'B': CDS_PINID='B';
NODE_NAME     PU297 17
 '@S9S_MB_2U_LIB.S9S_MB_2U(SCH_1):PAGE325_I17@PURE_QUANTA.MP5991GLUZ(CHIPS)':
 'SCREF_OCWREF': CDS_PINID='SCREF_OCWREF';
NET_NAME
'HSC_SS'
 '@S9S_MB_2U_LIB.S9S_MB_2U(SCH_1):HSC_SS':
 C_SIGNAL='@s9s_mb_2u_lib.s9s_mb_2u(sch_1):hsc_ss';
NODE_NAME     PU297 19
 '@S9S_MB_2U_LIB.S9S_MB_2U(SCH_1):PAGE325_I17@PURE_QUANTA.MP5991GLUZ(CHIPS)':
 'SS': CDS_PINID='SS';
NODE_NAME     PU289 16
 '@S9S_MB_2U_LIB.S9S_MB_2U(SCH_1):PAGE303_I56@PURE_QUANTA.MP5990GMA1111Z(CHIPS)':
 'SS': CDS_PINID='SS';
NODE_NAME     PU296 19
 '@S9S_MB_2U_LIB.S9S_MB_2U(SCH_1):PAGE325_I35@PURE_QUANTA.MP5991GLUZ(CHIPS)':
 'SS': CDS_PINID='SS';
NODE_NAME     PU287 19
 '@S9S_MB_2U_LIB.S9S_MB_2U(SCH_1):PAGE301_I35@PURE_QUANTA.MP5991GLUZ(CHIPS)':
 'SS': CDS_PINID='SS';
NODE_NAME     PC2227 1
 '@S9S_MB_2U_LIB.S9S_MB_2U(SCH_1):PAGE325_I38@PURE_QUANTA.Q_CAP(CHIPS)':
 'A': CDS_PINID='A';
NODE_NAME     PU288 19
 '@S9S_MB_2U_LIB.S9S_MB_2U(SCH_1):PAGE301_I14@PURE_QUANTA.MP5991GLUZ(CHIPS)':
 'SS': CDS_PINID='SS';
NODE_NAME     PC2191 1
 '@S9S_MB_2U_LIB.S9S_MB_2U(SCH_1):PAGE303_I69@PURE_QUANTA.Q_CAP(CHIPS)':
 'A': CDS_PINID='A';
NODE_NAME     PC2185 1
 '@S9S_MB_2U_LIB.S9S_MB_2U(SCH_1):PAGE301_I37@PURE_QUANTA.Q_CAP(CHIPS)':
 'A': CDS_PINID='A';
NODE_NAME     PC2184 1
 '@S9S_MB_2U_LIB.S9S_MB_2U(SCH_1):PAGE301_I47@PURE_QUANTA.Q_CAP(CHIPS)':
 'A': CDS_PINID='A';
NODE_NAME     PC2226 1
 '@S9S_MB_2U_LIB.S9S_MB_2U(SCH_1):PAGE325_I48@PURE_QUANTA.Q_CAP(CHIPS)':
 'A': CDS_PINID='A';
NET_NAME
'HSC_TYPE_ADC'
 '@S9S_MB_2U_LIB.S9S_MB_2U(SCH_1):HSC_TYPE_ADC':
 C_SIGNAL='@s9s_mb_2u_lib.s9s_mb_2u(sch_1):hsc_type_adc';
NODE_NAME     C2363 1
 '@S9S_MB_2U_LIB.S9S_MB_2U(SCH_1):PAGE240_I15@PURE_QUANTA.Q_CAP(CHIPS)':
 'A': CDS_PINID='A';
NODE_NAME     PJ42 17
 '@S9S_MB_2U_LIB.S9S_MB_2U(SCH_1):PAGE327_I34@PURE_QUANTA.SCONN21_9193031121LF(CHIPS)':
 '17': CDS_PINID='\17\';
NODE_NAME     U331 11
 '@S9S_MB_2U_LIB.S9S_MB_2U(SCH_1):PAGE240_I39@PURE_QUANTA.INA230AIRGTR(CHIPS)':
 'BUS': CDS_PINID='\bus\';
NET_NAME
'HSC_TYPE_ADC_A0'
 '@S9S_MB_2U_LIB.S9S_MB_2U(SCH_1):HSC_TYPE_ADC_A0':
 C_SIGNAL='@s9s_mb_2u_lib.s9s_mb_2u(sch_1):hsc_type_adc_a0';
NODE_NAME     R4691 1
 '@S9S_MB_2U_LIB.S9S_MB_2U(SCH_1):PAGE240_I16@PURE_QUANTA.Q_RES(CHIPS)':
 'A': CDS_PINID='A';
NODE_NAME     R4688 2
 '@S9S_MB_2U_LIB.S9S_MB_2U(SCH_1):PAGE240_I18@PURE_QUANTA.Q_RES(CHIPS)':
 'B': CDS_PINID='B';
NODE_NAME     U331 2
 '@S9S_MB_2U_LIB.S9S_MB_2U(SCH_1):PAGE240_I39@PURE_QUANTA.INA230AIRGTR(CHIPS)':
 'A0': CDS_PINID='A0';
NET_NAME
'HSC_TYPE_ADC_A1'
 '@S9S_MB_2U_LIB.S9S_MB_2U(SCH_1):HSC_TYPE_ADC_A1':
 C_SIGNAL='@s9s_mb_2u_lib.s9s_mb_2u(sch_1):hsc_type_adc_a1';
NODE_NAME     R4687 2
 '@S9S_MB_2U_LIB.S9S_MB_2U(SCH_1):PAGE240_I19@PURE_QUANTA.Q_RES(CHIPS)':
 'B': CDS_PINID='B';
NODE_NAME     U331 1
 '@S9S_MB_2U_LIB.S9S_MB_2U(SCH_1):PAGE240_I39@PURE_QUANTA.INA230AIRGTR(CHIPS)':
 'A1': CDS_PINID='A1';
NET_NAME
'HSC_VDD'
 '@S9S_MB_2U_LIB.S9S_MB_2U(SCH_1):HSC_VDD':
 C_SIGNAL='@s9s_mb_2u_lib.s9s_mb_2u(sch_1):hsc_vdd',
 CDS_GLOBAL_NET='TRUE';
NODE_NAME     PR3980 2
 '@S9S_MB_2U_LIB.S9S_MB_2U(SCH_1):PAGE325_I21@PURE_QUANTA.Q_RES(CHIPS)':
 'B': CDS_PINID='B';
NODE_NAME     PR3911 2
 '@S9S_MB_2U_LIB.S9S_MB_2U(SCH_1):PAGE301_I5@PURE_QUANTA.Q_RES(CHIPS)':
 'B': CDS_PINID='B';
NODE_NAME     PR3910 2
 '@S9S_MB_2U_LIB.S9S_MB_2U(SCH_1):PAGE301_I21@PURE_QUANTA.Q_RES(CHIPS)':
 'B': CDS_PINID='B';
NODE_NAME     R3936 1
 '@S9S_MB_2U_LIB.S9S_MB_2U(SCH_1):PAGE303_I85@PURE_QUANTA.Q_RES(CHIPS)':
 'A': CDS_PINID='A';
NODE_NAME     PR2149 2
 '@S9S_MB_2U_LIB.S9S_MB_2U(SCH_1):PAGE303_I24@PURE_QUANTA.Q_RES(CHIPS)':
 'B': CDS_PINID='B';
NODE_NAME     PR2106 1
 '@S9S_MB_2U_LIB.S9S_MB_2U(SCH_1):PAGE303_I43@PURE_QUANTA.Q_RES(CHIPS)':
 'A': CDS_PINID='A';
NODE_NAME     R2587 1
 '@S9S_MB_2U_LIB.S9S_MB_2U(SCH_1):PAGE303_I93@PURE_QUANTA.Q_RES(CHIPS)':
 'A': CDS_PINID='A';
NODE_NAME     PR3981 2
 '@S9S_MB_2U_LIB.S9S_MB_2U(SCH_1):PAGE325_I5@PURE_QUANTA.Q_RES(CHIPS)':
 'B': CDS_PINID='B';
NET_NAME
'HSC_VDD18'
 '@S9S_MB_2U_LIB.S9S_MB_2U(SCH_1):HSC_VDD18':
 C_SIGNAL='@s9s_mb_2u_lib.s9s_mb_2u(sch_1):hsc_vdd18';
NODE_NAME     PU289 19
 '@S9S_MB_2U_LIB.S9S_MB_2U(SCH_1):PAGE303_I56@PURE_QUANTA.MP5990GMA1111Z(CHIPS)':
 'VDD18': CDS_PINID='VDD18';
NODE_NAME     PC2103 1
 '@S9S_MB_2U_LIB.S9S_MB_2U(SCH_1):PAGE303_I35@PURE_QUANTA.Q_CAP(CHIPS)':
 'A': CDS_PINID='A';
NODE_NAME     PR3929 2
 '@S9S_MB_2U_LIB.S9S_MB_2U(SCH_1):PAGE303_I42@PURE_QUANTA.Q_RES(CHIPS)':
 'B': CDS_PINID='B';
NET_NAME
'HSC_VDD_R'
 '@S9S_MB_2U_LIB.S9S_MB_2U(SCH_1):HSC_VDD_R':
 C_SIGNAL='@s9s_mb_2u_lib.s9s_mb_2u(sch_1):hsc_vdd_r';
NODE_NAME     PU289 17
 '@S9S_MB_2U_LIB.S9S_MB_2U(SCH_1):PAGE303_I56@PURE_QUANTA.MP5990GMA1111Z(CHIPS)':
 'VDD33_1': CDS_PINID='VDD33_1';
NODE_NAME     PU289 45
 '@S9S_MB_2U_LIB.S9S_MB_2U(SCH_1):PAGE303_I56@PURE_QUANTA.MP5990GMA1111Z(CHIPS)':
 'VDD33_2': CDS_PINID='VDD33_2';
NODE_NAME     PR2149 1
 '@S9S_MB_2U_LIB.S9S_MB_2U(SCH_1):PAGE303_I24@PURE_QUANTA.Q_RES(CHIPS)':
 'A': CDS_PINID='A';
NODE_NAME     PC2186 1
 '@S9S_MB_2U_LIB.S9S_MB_2U(SCH_1):PAGE303_I14@PURE_QUANTA.Q_CAP(CHIPS)':
 'A': CDS_PINID='A';
NODE_NAME     PC2187 1
 '@S9S_MB_2U_LIB.S9S_MB_2U(SCH_1):PAGE303_I23@PURE_QUANTA.Q_CAP(CHIPS)':
 'A': CDS_PINID='A';
NET_NAME
'HSC_VDD_R_1'
 '@S9S_MB_2U_LIB.S9S_MB_2U(SCH_1):HSC_VDD_R_1':
 C_SIGNAL='@s9s_mb_2u_lib.s9s_mb_2u(sch_1):hsc_vdd_r_1';
NODE_NAME     PC1525 1
 '@S9S_MB_2U_LIB.S9S_MB_2U(SCH_1):PAGE301_I20@PURE_QUANTA.Q_CAP(CHIPS)':
 'A': CDS_PINID='A';
NODE_NAME     PR3910 1
 '@S9S_MB_2U_LIB.S9S_MB_2U(SCH_1):PAGE301_I21@PURE_QUANTA.Q_RES(CHIPS)':
 'A': CDS_PINID='A';
NODE_NAME     PU287 21
 '@S9S_MB_2U_LIB.S9S_MB_2U(SCH_1):PAGE301_I35@PURE_QUANTA.MP5991GLUZ(CHIPS)':
 'VDD33': CDS_PINID='VDD33';
NET_NAME
'HSC_VDD_R_2'
 '@S9S_MB_2U_LIB.S9S_MB_2U(SCH_1):HSC_VDD_R_2':
 C_SIGNAL='@s9s_mb_2u_lib.s9s_mb_2u(sch_1):hsc_vdd_r_2';
NODE_NAME     PC2181 1
 '@S9S_MB_2U_LIB.S9S_MB_2U(SCH_1):PAGE301_I4@PURE_QUANTA.Q_CAP(CHIPS)':
 'A': CDS_PINID='A';
NODE_NAME     PR3911 1
 '@S9S_MB_2U_LIB.S9S_MB_2U(SCH_1):PAGE301_I5@PURE_QUANTA.Q_RES(CHIPS)':
 'A': CDS_PINID='A';
NODE_NAME     PU288 21
 '@S9S_MB_2U_LIB.S9S_MB_2U(SCH_1):PAGE301_I14@PURE_QUANTA.MP5991GLUZ(CHIPS)':
 'VDD33': CDS_PINID='VDD33';
NET_NAME
'HSC_VDD_R_3'
 '@S9S_MB_2U_LIB.S9S_MB_2U(SCH_1):HSC_VDD_R_3':
 C_SIGNAL='@s9s_mb_2u_lib.s9s_mb_2u(sch_1):hsc_vdd_r_3';
NODE_NAME     PR3980 1
 '@S9S_MB_2U_LIB.S9S_MB_2U(SCH_1):PAGE325_I21@PURE_QUANTA.Q_RES(CHIPS)':
 'A': CDS_PINID='A';
NODE_NAME     PU296 21
 '@S9S_MB_2U_LIB.S9S_MB_2U(SCH_1):PAGE325_I35@PURE_QUANTA.MP5991GLUZ(CHIPS)':
 'VDD33': CDS_PINID='VDD33';
NODE_NAME     PC3272 1
 '@S9S_MB_2U_LIB.S9S_MB_2U(SCH_1):PAGE325_I19@PURE_QUANTA.Q_CAP(CHIPS)':
 'A': CDS_PINID='A';
NET_NAME
'HSC_VDD_R_4'
 '@S9S_MB_2U_LIB.S9S_MB_2U(SCH_1):HSC_VDD_R_4':
 C_SIGNAL='@s9s_mb_2u_lib.s9s_mb_2u(sch_1):hsc_vdd_r_4';
NODE_NAME     PU297 21
 '@S9S_MB_2U_LIB.S9S_MB_2U(SCH_1):PAGE325_I17@PURE_QUANTA.MP5991GLUZ(CHIPS)':
 'VDD33': CDS_PINID='VDD33';
NODE_NAME     PC2223 1
 '@S9S_MB_2U_LIB.S9S_MB_2U(SCH_1):PAGE325_I4@PURE_QUANTA.Q_CAP(CHIPS)':
 'A': CDS_PINID='A';
NODE_NAME     PR3981 1
 '@S9S_MB_2U_LIB.S9S_MB_2U(SCH_1):PAGE325_I5@PURE_QUANTA.Q_RES(CHIPS)':
 'A': CDS_PINID='A';
NET_NAME
'HSC_VIN_UVW_N'
 '@S9S_MB_2U_LIB.S9S_MB_2U(SCH_1):HSC_VIN_UVW_N':
 C_SIGNAL='@s9s_mb_2u_lib.s9s_mb_2u(sch_1):hsc_vin_uvw_n';
NODE_NAME     PU289 14
 '@S9S_MB_2U_LIB.S9S_MB_2U(SCH_1):PAGE303_I56@PURE_QUANTA.MP5990GMA1111Z(CHIPS)':
 'VIN_UVW#': CDS_PINID='\vin_uvw#\';
NODE_NAME     PR2106 2
 '@S9S_MB_2U_LIB.S9S_MB_2U(SCH_1):PAGE303_I43@PURE_QUANTA.Q_RES(CHIPS)':
 'B': CDS_PINID='B';
NET_NAME
'HSC_VOSEN'
 '@S9S_MB_2U_LIB.S9S_MB_2U(SCH_1):HSC_VOSEN':
 C_SIGNAL='@s9s_mb_2u_lib.s9s_mb_2u(sch_1):hsc_vosen';
NODE_NAME     PU289 24
 '@S9S_MB_2U_LIB.S9S_MB_2U(SCH_1):PAGE303_I56@PURE_QUANTA.MP5990GMA1111Z(CHIPS)':
 'VOSEN': CDS_PINID='VOSEN';
NODE_NAME     PR3932 1
 '@S9S_MB_2U_LIB.S9S_MB_2U(SCH_1):PAGE303_I59@PURE_QUANTA.Q_RES(CHIPS)':
 'A': CDS_PINID='A';
NODE_NAME     PR3931 2
 '@S9S_MB_2U_LIB.S9S_MB_2U(SCH_1):PAGE303_I86@PURE_QUANTA.Q_RES(CHIPS)':
 'B': CDS_PINID='B';
NODE_NAME     PC2190 1
 '@S9S_MB_2U_LIB.S9S_MB_2U(SCH_1):PAGE303_I75@PURE_QUANTA.Q_CAP(CHIPS)':
 'A': CDS_PINID='A';
NET_NAME
'HSC_VSENSE'
 '@S9S_MB_2U_LIB.S9S_MB_2U(SCH_1):HSC_VSENSE':
 C_SIGNAL='@s9s_mb_2u_lib.s9s_mb_2u(sch_1):hsc_vsense';
NODE_NAME     PR3926 2
 '@S9S_MB_2U_LIB.S9S_MB_2U(SCH_1):PAGE303_I52@PURE_QUANTA.Q_RES(CHIPS)':
 'B': CDS_PINID='B';
NODE_NAME     PU289 9
 '@S9S_MB_2U_LIB.S9S_MB_2U(SCH_1):PAGE303_I56@PURE_QUANTA.MP5990GMA1111Z(CHIPS)':
 'VINSEN': CDS_PINID='VINSEN';
NODE_NAME     PR3927 1
 '@S9S_MB_2U_LIB.S9S_MB_2U(SCH_1):PAGE303_I40@PURE_QUANTA.Q_RES(CHIPS)':
 'A': CDS_PINID='A';
NODE_NAME     PC2189 1
 '@S9S_MB_2U_LIB.S9S_MB_2U(SCH_1):PAGE303_I45@PURE_QUANTA.Q_CAP(CHIPS)':
 'A': CDS_PINID='A';
NET_NAME
'HSC_VTEMP'
 '@S9S_MB_2U_LIB.S9S_MB_2U(SCH_1):HSC_VTEMP':
 C_SIGNAL='@s9s_mb_2u_lib.s9s_mb_2u(sch_1):hsc_vtemp';
NODE_NAME     PU297 18
 '@S9S_MB_2U_LIB.S9S_MB_2U(SCH_1):PAGE325_I17@PURE_QUANTA.MP5991GLUZ(CHIPS)':
 'VTEMP': CDS_PINID='VTEMP';
NODE_NAME     PU289 15
 '@S9S_MB_2U_LIB.S9S_MB_2U(SCH_1):PAGE303_I56@PURE_QUANTA.MP5990GMA1111Z(CHIPS)':
 'VTEMP': CDS_PINID='VTEMP';
NODE_NAME     PU296 18
 '@S9S_MB_2U_LIB.S9S_MB_2U(SCH_1):PAGE325_I35@PURE_QUANTA.MP5991GLUZ(CHIPS)':
 'VTEMP': CDS_PINID='VTEMP';
NODE_NAME     PU287 18
 '@S9S_MB_2U_LIB.S9S_MB_2U(SCH_1):PAGE301_I35@PURE_QUANTA.MP5991GLUZ(CHIPS)':
 'VTEMP': CDS_PINID='VTEMP';
NODE_NAME     PU288 18
 '@S9S_MB_2U_LIB.S9S_MB_2U(SCH_1):PAGE301_I14@PURE_QUANTA.MP5991GLUZ(CHIPS)':
 'VTEMP': CDS_PINID='VTEMP';
NODE_NAME     PC2192 1
 '@S9S_MB_2U_LIB.S9S_MB_2U(SCH_1):PAGE303_I77@PURE_QUANTA.Q_CAP(CHIPS)':
 'A': CDS_PINID='A';
NODE_NAME     PR3935 1
 '@S9S_MB_2U_LIB.S9S_MB_2U(SCH_1):PAGE303_I79@PURE_QUANTA.Q_RES(CHIPS)':
 'A': CDS_PINID='A';
NET_NAME
'H_CPU0_BMCINIT_LVC1'
 '@S9S_MB_2U_LIB.S9S_MB_2U(SCH_1):H_CPU0_BMCINIT_LVC1':
 C_SIGNAL='@s9s_mb_2u_lib.s9s_mb_2u(sch_1):h_cpu0_bmcinit_lvc1';
NODE_NAME     U2 BN23
 '@S9S_MB_2U_LIB.S9S_MB_2U(SCH_1):PAGE13_I57@PURE_QUANTA.SOCKET4677_AZIF0045P001C01CS(CHIPS)':
 'BMCINIT': CDS_PINID='BMCINIT';
NODE_NAME     R278 2
 '@S9S_MB_2U_LIB.S9S_MB_2U(SCH_1):PAGE119_I61@PURE_QUANTA.Q_RES(CHIPS)':
 'B': CDS_PINID='B';
NET_NAME
'H_CPU0_CATERR_LVC1_R_N'
 '@S9S_MB_2U_LIB.S9S_MB_2U(SCH_1):H_CPU0_CATERR_LVC1_R_N':
 C_SIGNAL='@s9s_mb_2u_lib.s9s_mb_2u(sch_1):h_cpu0_caterr_lvc1_r_n';
NODE_NAME     U2 BP24
 '@S9S_MB_2U_LIB.S9S_MB_2U(SCH_1):PAGE14_I1@PURE_QUANTA.SOCKET4677_AZIF0045P001C01CS(CHIPS)':
 'CATERR_N': CDS_PINID='CATERR_N';
NODE_NAME     R297 1
 '@S9S_MB_2U_LIB.S9S_MB_2U(SCH_1):PAGE118_I23@PURE_QUANTA.Q_RES(CHIPS)':
 'A': CDS_PINID='A';
NET_NAME
'H_CPU0_ERR0_LVC1_R_N'
 '@S9S_MB_2U_LIB.S9S_MB_2U(SCH_1):H_CPU0_ERR0_LVC1_R_N':
 C_SIGNAL='@s9s_mb_2u_lib.s9s_mb_2u(sch_1):h_cpu0_err0_lvc1_r_n';
NODE_NAME     U2 BF22
 '@S9S_MB_2U_LIB.S9S_MB_2U(SCH_1):PAGE14_I1@PURE_QUANTA.SOCKET4677_AZIF0045P001C01CS(CHIPS)':
 'ERROR_N0': CDS_PINID='ERROR_N0';
NODE_NAME     R336 1
 '@S9S_MB_2U_LIB.S9S_MB_2U(SCH_1):PAGE322_I159@PURE_QUANTA.Q_RES(CHIPS)':
 'A': CDS_PINID='A';
NET_NAME
'H_CPU0_ERR1_LVC1_R_N'
 '@S9S_MB_2U_LIB.S9S_MB_2U(SCH_1):H_CPU0_ERR1_LVC1_R_N':
 C_SIGNAL='@s9s_mb_2u_lib.s9s_mb_2u(sch_1):h_cpu0_err1_lvc1_r_n';
NODE_NAME     U2 AY22
 '@S9S_MB_2U_LIB.S9S_MB_2U(SCH_1):PAGE14_I1@PURE_QUANTA.SOCKET4677_AZIF0045P001C01CS(CHIPS)':
 'ERROR_N1': CDS_PINID='ERROR_N1';
NODE_NAME     R340 1
 '@S9S_MB_2U_LIB.S9S_MB_2U(SCH_1):PAGE322_I164@PURE_QUANTA.Q_RES(CHIPS)':
 'A': CDS_PINID='A';
NET_NAME
'H_CPU0_ERR2_LVC1_R_N'
 '@S9S_MB_2U_LIB.S9S_MB_2U(SCH_1):H_CPU0_ERR2_LVC1_R_N':
 C_SIGNAL='@s9s_mb_2u_lib.s9s_mb_2u(sch_1):h_cpu0_err2_lvc1_r_n';
NODE_NAME     U2 BD22
 '@S9S_MB_2U_LIB.S9S_MB_2U(SCH_1):PAGE14_I1@PURE_QUANTA.SOCKET4677_AZIF0045P001C01CS(CHIPS)':
 'ERROR_N2': CDS_PINID='ERROR_N2';
NODE_NAME     R344 1
 '@S9S_MB_2U_LIB.S9S_MB_2U(SCH_1):PAGE322_I157@PURE_QUANTA.Q_RES(CHIPS)':
 'A': CDS_PINID='A';
NET_NAME
'H_CPU0_MEMHOT_IN_LVC1_N'
 '@S9S_MB_2U_LIB.S9S_MB_2U(SCH_1):H_CPU0_MEMHOT_IN_LVC1_N':
 C_SIGNAL='@s9s_mb_2u_lib.s9s_mb_2u(sch_1):h_cpu0_memhot_in_lvc1_n';
NODE_NAME     U2 AU21
 '@S9S_MB_2U_LIB.S9S_MB_2U(SCH_1):PAGE14_I1@PURE_QUANTA.SOCKET4677_AZIF0045P001C01CS(CHIPS)':
 'MEMHOT_IN_N': CDS_PINID='MEMHOT_IN_N';
NODE_NAME     R4293 2
 '@S9S_MB_2U_LIB.S9S_MB_2U(SCH_1):PAGE122_I34@PURE_QUANTA.Q_RES(CHIPS)':
 'B': CDS_PINID='B';
NET_NAME
'H_CPU0_MEMHOT_IN_LVC1_R1_N'
 '@S9S_MB_2U_LIB.S9S_MB_2U(SCH_1):H_CPU0_MEMHOT_IN_LVC1_R1_N':
 C_SIGNAL='@s9s_mb_2u_lib.s9s_mb_2u(sch_1):h_cpu0_memhot_in_lvc1_r1_n';
NODE_NAME     R208 2
 '@S9S_MB_2U_LIB.S9S_MB_2U(SCH_1):PAGE122_I16@PURE_QUANTA.Q_RES(CHIPS)':
 'B': CDS_PINID='B';
NODE_NAME     R4293 1
 '@S9S_MB_2U_LIB.S9S_MB_2U(SCH_1):PAGE122_I34@PURE_QUANTA.Q_RES(CHIPS)':
 'A': CDS_PINID='A';
NODE_NAME     R219 2
 '@S9S_MB_2U_LIB.S9S_MB_2U(SCH_1):PAGE122_I37@PURE_QUANTA.Q_RES(CHIPS)':
 'B': CDS_PINID='B';
NET_NAME
'H_CPU0_MEMHOT_IN_LVC1_R_N'
 '@S9S_MB_2U_LIB.S9S_MB_2U(SCH_1):H_CPU0_MEMHOT_IN_LVC1_R_N':
 C_SIGNAL='@s9s_mb_2u_lib.s9s_mb_2u(sch_1):h_cpu0_memhot_in_lvc1_r_n';
NODE_NAME     U249 T7
 '@S9S_MB_2U_LIB.S9S_MB_2U(SCH_1):PAGE311_I33@PURE_QUANTA.LCMXO3LF9400C5BG484C(CHIPS)':
 'PL30D': CDS_PINID='PL30D';
NODE_NAME     R208 1
 '@S9S_MB_2U_LIB.S9S_MB_2U(SCH_1):PAGE122_I16@PURE_QUANTA.Q_RES(CHIPS)':
 'A': CDS_PINID='A';
NET_NAME
'H_CPU0_MEMHOT_OUT'
 '@S9S_MB_2U_LIB.S9S_MB_2U(SCH_1):H_CPU0_MEMHOT_OUT':
 C_SIGNAL='@s9s_mb_2u_lib.s9s_mb_2u(sch_1):h_cpu0_memhot_out';
NODE_NAME     Q143 3
 '@S9S_MB_2U_LIB.S9S_MB_2U(SCH_1):PAGE122_I12@PURE_QUANTA.BC847BPN(CHIPS)':
 'C2': CDS_PINID='C2';
NODE_NAME     R4403 1
 '@S9S_MB_2U_LIB.S9S_MB_2U(SCH_1):PAGE122_I21@PURE_QUANTA.Q_RES(CHIPS)':
 'A': CDS_PINID='A';
NET_NAME
'H_CPU0_MEMHOT_OUT_LVC1_N'
 '@S9S_MB_2U_LIB.S9S_MB_2U(SCH_1):H_CPU0_MEMHOT_OUT_LVC1_N':
 C_SIGNAL='@s9s_mb_2u_lib.s9s_mb_2u(sch_1):h_cpu0_memhot_out_lvc1_n';
NODE_NAME     U249 T3
 '@S9S_MB_2U_LIB.S9S_MB_2U(SCH_1):PAGE311_I33@PURE_QUANTA.LCMXO3LF9400C5BG484C(CHIPS)':
 'PL26A': CDS_PINID='PL26A';
NODE_NAME     R4407 2
 '@S9S_MB_2U_LIB.S9S_MB_2U(SCH_1):PAGE122_I31@PURE_QUANTA.Q_RES(CHIPS)':
 'B': CDS_PINID='B';
NET_NAME
'H_CPU0_MEMHOT_OUT_LVC1_R_N'
 '@S9S_MB_2U_LIB.S9S_MB_2U(SCH_1):H_CPU0_MEMHOT_OUT_LVC1_R_N':
 C_SIGNAL='@s9s_mb_2u_lib.s9s_mb_2u(sch_1):h_cpu0_memhot_out_lvc1_r_n';
NODE_NAME     U2 CF26
 '@S9S_MB_2U_LIB.S9S_MB_2U(SCH_1):PAGE14_I1@PURE_QUANTA.SOCKET4677_AZIF0045P001C01CS(CHIPS)':
 'MEMHOT_OUT_N': CDS_PINID='MEMHOT_OUT_N';
NODE_NAME     R4401 2
 '@S9S_MB_2U_LIB.S9S_MB_2U(SCH_1):PAGE122_I8@PURE_QUANTA.Q_RES(CHIPS)':
 'B': CDS_PINID='B';
NODE_NAME     R203 1
 '@S9S_MB_2U_LIB.S9S_MB_2U(SCH_1):PAGE122_I9@PURE_QUANTA.Q_RES(CHIPS)':
 'A': CDS_PINID='A';
NET_NAME
'H_CPU0_MEMHOT_OUT_R'
 '@S9S_MB_2U_LIB.S9S_MB_2U(SCH_1):H_CPU0_MEMHOT_OUT_R':
 C_SIGNAL='@s9s_mb_2u_lib.s9s_mb_2u(sch_1):h_cpu0_memhot_out_r';
NODE_NAME     R4403 2
 '@S9S_MB_2U_LIB.S9S_MB_2U(SCH_1):PAGE122_I21@PURE_QUANTA.Q_RES(CHIPS)':
 'B': CDS_PINID='B';
NODE_NAME     Q143 2
 '@S9S_MB_2U_LIB.S9S_MB_2U(SCH_1):PAGE122_I22@PURE_QUANTA.BC847BPN(CHIPS)':
 'B1': CDS_PINID='B1';
NET_NAME
'H_CPU0_MEMHOT_OUT_VT_N'
 '@S9S_MB_2U_LIB.S9S_MB_2U(SCH_1):H_CPU0_MEMHOT_OUT_VT_N':
 C_SIGNAL='@s9s_mb_2u_lib.s9s_mb_2u(sch_1):h_cpu0_memhot_out_vt_n';
NODE_NAME     Q143 6
 '@S9S_MB_2U_LIB.S9S_MB_2U(SCH_1):PAGE122_I22@PURE_QUANTA.BC847BPN(CHIPS)':
 'C1': CDS_PINID='C1';
NODE_NAME     R4405 2
 '@S9S_MB_2U_LIB.S9S_MB_2U(SCH_1):PAGE122_I27@PURE_QUANTA.Q_RES(CHIPS)':
 'B': CDS_PINID='B';
NODE_NAME     R4407 1
 '@S9S_MB_2U_LIB.S9S_MB_2U(SCH_1):PAGE122_I31@PURE_QUANTA.Q_RES(CHIPS)':
 'A': CDS_PINID='A';
NET_NAME
'H_CPU0_MEMHOT_OUT_VT_R_N'
 '@S9S_MB_2U_LIB.S9S_MB_2U(SCH_1):H_CPU0_MEMHOT_OUT_VT_R_N':
 C_SIGNAL='@s9s_mb_2u_lib.s9s_mb_2u(sch_1):h_cpu0_memhot_out_vt_r_n';
NODE_NAME     R203 2
 '@S9S_MB_2U_LIB.S9S_MB_2U(SCH_1):PAGE122_I9@PURE_QUANTA.Q_RES(CHIPS)':
 'B': CDS_PINID='B';
NODE_NAME     Q143 5
 '@S9S_MB_2U_LIB.S9S_MB_2U(SCH_1):PAGE122_I12@PURE_QUANTA.BC847BPN(CHIPS)':
 'B2': CDS_PINID='B2';
NET_NAME
'H_CPU0_MEMTRIP'
 '@S9S_MB_2U_LIB.S9S_MB_2U(SCH_1):H_CPU0_MEMTRIP':
 C_SIGNAL='@s9s_mb_2u_lib.s9s_mb_2u(sch_1):h_cpu0_memtrip';
NODE_NAME     Q141 3
 '@S9S_MB_2U_LIB.S9S_MB_2U(SCH_1):PAGE123_I12@PURE_QUANTA.BC847BPN(CHIPS)':
 'C2': CDS_PINID='C2';
NODE_NAME     R4409 1
 '@S9S_MB_2U_LIB.S9S_MB_2U(SCH_1):PAGE123_I15@PURE_QUANTA.Q_RES(CHIPS)':
 'A': CDS_PINID='A';
NET_NAME
'H_CPU0_MEMTRIP_LVC1_N'
 '@S9S_MB_2U_LIB.S9S_MB_2U(SCH_1):H_CPU0_MEMTRIP_LVC1_N':
 C_SIGNAL='@s9s_mb_2u_lib.s9s_mb_2u(sch_1):h_cpu0_memtrip_lvc1_n';
NODE_NAME     U249 R6
 '@S9S_MB_2U_LIB.S9S_MB_2U(SCH_1):PAGE311_I33@PURE_QUANTA.LCMXO3LF9400C5BG484C(CHIPS)':
 'PL25C': CDS_PINID='PL25C';
NODE_NAME     R4413 2
 '@S9S_MB_2U_LIB.S9S_MB_2U(SCH_1):PAGE123_I33@PURE_QUANTA.Q_RES(CHIPS)':
 'B': CDS_PINID='B';
NET_NAME
'H_CPU0_MEMTRIP_LVC1_R_N'
 '@S9S_MB_2U_LIB.S9S_MB_2U(SCH_1):H_CPU0_MEMTRIP_LVC1_R_N':
 C_SIGNAL='@s9s_mb_2u_lib.s9s_mb_2u(sch_1):h_cpu0_memtrip_lvc1_r_n';
NODE_NAME     U2 AV24
 '@S9S_MB_2U_LIB.S9S_MB_2U(SCH_1):PAGE14_I1@PURE_QUANTA.SOCKET4677_AZIF0045P001C01CS(CHIPS)':
 'MEMTRIP_N': CDS_PINID='MEMTRIP_N';
NODE_NAME     R205 1
 '@S9S_MB_2U_LIB.S9S_MB_2U(SCH_1):PAGE123_I10@PURE_QUANTA.Q_RES(CHIPS)':
 'A': CDS_PINID='A';
NODE_NAME     R200 2
 '@S9S_MB_2U_LIB.S9S_MB_2U(SCH_1):PAGE123_I19@PURE_QUANTA.Q_RES(CHIPS)':
 'B': CDS_PINID='B';
NET_NAME
'H_CPU0_MEMTRIP_OUT_VT_R_N'
 '@S9S_MB_2U_LIB.S9S_MB_2U(SCH_1):H_CPU0_MEMTRIP_OUT_VT_R_N':
 C_SIGNAL='@s9s_mb_2u_lib.s9s_mb_2u(sch_1):h_cpu0_memtrip_out_vt_r_n';
NODE_NAME     R205 2
 '@S9S_MB_2U_LIB.S9S_MB_2U(SCH_1):PAGE123_I10@PURE_QUANTA.Q_RES(CHIPS)':
 'B': CDS_PINID='B';
NODE_NAME     Q141 5
 '@S9S_MB_2U_LIB.S9S_MB_2U(SCH_1):PAGE123_I12@PURE_QUANTA.BC847BPN(CHIPS)':
 'B2': CDS_PINID='B2';
NET_NAME
'H_CPU0_MEMTRIP_R'
 '@S9S_MB_2U_LIB.S9S_MB_2U(SCH_1):H_CPU0_MEMTRIP_R':
 C_SIGNAL='@s9s_mb_2u_lib.s9s_mb_2u(sch_1):h_cpu0_memtrip_r';
NODE_NAME     R4409 2
 '@S9S_MB_2U_LIB.S9S_MB_2U(SCH_1):PAGE123_I15@PURE_QUANTA.Q_RES(CHIPS)':
 'B': CDS_PINID='B';
NODE_NAME     Q141 2
 '@S9S_MB_2U_LIB.S9S_MB_2U(SCH_1):PAGE123_I18@PURE_QUANTA.BC847BPN(CHIPS)':
 'B1': CDS_PINID='B1';
NET_NAME
'H_CPU0_MEMTRIP_VT_N'
 '@S9S_MB_2U_LIB.S9S_MB_2U(SCH_1):H_CPU0_MEMTRIP_VT_N':
 C_SIGNAL='@s9s_mb_2u_lib.s9s_mb_2u(sch_1):h_cpu0_memtrip_vt_n';
NODE_NAME     Q141 6
 '@S9S_MB_2U_LIB.S9S_MB_2U(SCH_1):PAGE123_I18@PURE_QUANTA.BC847BPN(CHIPS)':
 'C1': CDS_PINID='C1';
NODE_NAME     R4411 2
 '@S9S_MB_2U_LIB.S9S_MB_2U(SCH_1):PAGE123_I32@PURE_QUANTA.Q_RES(CHIPS)':
 'B': CDS_PINID='B';
NODE_NAME     R4413 1
 '@S9S_MB_2U_LIB.S9S_MB_2U(SCH_1):PAGE123_I33@PURE_QUANTA.Q_RES(CHIPS)':
 'A': CDS_PINID='A';
NET_NAME
'H_CPU0_NMI_LVC1_N'
 '@S9S_MB_2U_LIB.S9S_MB_2U(SCH_1):H_CPU0_NMI_LVC1_N':
 C_SIGNAL='@s9s_mb_2u_lib.s9s_mb_2u(sch_1):h_cpu0_nmi_lvc1_n';
NODE_NAME     U2 AV18
 '@S9S_MB_2U_LIB.S9S_MB_2U(SCH_1):PAGE14_I1@PURE_QUANTA.SOCKET4677_AZIF0045P001C01CS(CHIPS)':
 'NMI': CDS_PINID='NMI';
NODE_NAME     R195 2
 '@S9S_MB_2U_LIB.S9S_MB_2U(SCH_1):PAGE123_I6@PURE_QUANTA.Q_RES(CHIPS)':
 'B': CDS_PINID='B';
NODE_NAME     R197 2
 '@S9S_MB_2U_LIB.S9S_MB_2U(SCH_1):PAGE123_I27@PURE_QUANTA.Q_RES(CHIPS)':
 'B': CDS_PINID='B';
NET_NAME
'H_CPU0_PMDOWN_CPU1'
 '@S9S_MB_2U_LIB.S9S_MB_2U(SCH_1):H_CPU0_PMDOWN_CPU1':
 C_SIGNAL='@s9s_mb_2u_lib.s9s_mb_2u(sch_1):h_cpu0_pmdown_cpu1';
NODE_NAME     R11 2
 '@S9S_MB_2U_LIB.S9S_MB_2U(SCH_1):PAGE14_I79@PURE_QUANTA.Q_RES(CHIPS)':
 'B': CDS_PINID='B';
NODE_NAME     U1 CN25
 '@S9S_MB_2U_LIB.S9S_MB_2U(SCH_1):PAGE45_I29@PURE_QUANTA.SOCKET4677_AZIF0045P001C01CS(CHIPS)':
 'PMSYNC0': CDS_PINID='PMSYNC0';
NET_NAME
'H_CPU0_PMDOWN_CPU1_R'
 '@S9S_MB_2U_LIB.S9S_MB_2U(SCH_1):H_CPU0_PMDOWN_CPU1_R':
 C_SIGNAL='@s9s_mb_2u_lib.s9s_mb_2u(sch_1):h_cpu0_pmdown_cpu1_r';
NODE_NAME     U2 CW39
 '@S9S_MB_2U_LIB.S9S_MB_2U(SCH_1):PAGE14_I1@PURE_QUANTA.SOCKET4677_AZIF0045P001C01CS(CHIPS)':
 'PMDOWN0': CDS_PINID='PMDOWN0';
NODE_NAME     R2362 1
 '@S9S_MB_2U_LIB.S9S_MB_2U(SCH_1):PAGE14_I122@PURE_QUANTA.Q_RES(CHIPS)':
 'A': CDS_PINID='A';
NET_NAME
'H_CPU0_PMDOWN_CPU1_R1'
 '@S9S_MB_2U_LIB.S9S_MB_2U(SCH_1):H_CPU0_PMDOWN_CPU1_R1':
 C_SIGNAL='@s9s_mb_2u_lib.s9s_mb_2u(sch_1):h_cpu0_pmdown_cpu1_r1';
NODE_NAME     R11 1
 '@S9S_MB_2U_LIB.S9S_MB_2U(SCH_1):PAGE14_I79@PURE_QUANTA.Q_RES(CHIPS)':
 'A': CDS_PINID='A';
NODE_NAME     R2362 2
 '@S9S_MB_2U_LIB.S9S_MB_2U(SCH_1):PAGE14_I122@PURE_QUANTA.Q_RES(CHIPS)':
 'B': CDS_PINID='B';
NET_NAME
'H_CPU0_PMDOWN_PCH'
 '@S9S_MB_2U_LIB.S9S_MB_2U(SCH_1):H_CPU0_PMDOWN_PCH':
 C_SIGNAL='@s9s_mb_2u_lib.s9s_mb_2u(sch_1):h_cpu0_pmdown_pch';
NODE_NAME     R7 2
 '@S9S_MB_2U_LIB.S9S_MB_2U(SCH_1):PAGE14_I66@PURE_QUANTA.Q_RES(CHIPS)':
 'B': CDS_PINID='B';
NODE_NAME     U4 AE7
 '@S9S_MB_2U_LIB.S9S_MB_2U(SCH_1):PAGE176_I22@PURE_QUANTA.EMMITSBURG_REV0P9(CHIPS)':
 'GPP_L_1_PM_DOWN_0': CDS_PINID='GPP_L_1_PM_DOWN_0';
NET_NAME
'H_CPU0_PMDOWN_PCH_R'
 '@S9S_MB_2U_LIB.S9S_MB_2U(SCH_1):H_CPU0_PMDOWN_PCH_R':
 C_SIGNAL='@s9s_mb_2u_lib.s9s_mb_2u(sch_1):h_cpu0_pmdown_pch_r';
NODE_NAME     R7 1
 '@S9S_MB_2U_LIB.S9S_MB_2U(SCH_1):PAGE14_I66@PURE_QUANTA.Q_RES(CHIPS)':
 'A': CDS_PINID='A';
NODE_NAME     R1959 2
 '@S9S_MB_2U_LIB.S9S_MB_2U(SCH_1):PAGE14_I115@PURE_QUANTA.Q_RES(CHIPS)':
 'B': CDS_PINID='B';
NET_NAME
'H_CPU0_PMDOWN_PCH_R2'
 '@S9S_MB_2U_LIB.S9S_MB_2U(SCH_1):H_CPU0_PMDOWN_PCH_R2':
 C_SIGNAL='@s9s_mb_2u_lib.s9s_mb_2u(sch_1):h_cpu0_pmdown_pch_r2';
NODE_NAME     U2 CY40
 '@S9S_MB_2U_LIB.S9S_MB_2U(SCH_1):PAGE14_I1@PURE_QUANTA.SOCKET4677_AZIF0045P001C01CS(CHIPS)':
 'PMDOWN_PCH': CDS_PINID='PMDOWN_PCH';
NODE_NAME     R1959 1
 '@S9S_MB_2U_LIB.S9S_MB_2U(SCH_1):PAGE14_I115@PURE_QUANTA.Q_RES(CHIPS)':
 'A': CDS_PINID='A';
NET_NAME
'H_CPU0_PMSYNC_CPU1'
 '@S9S_MB_2U_LIB.S9S_MB_2U(SCH_1):H_CPU0_PMSYNC_CPU1':
 C_SIGNAL='@s9s_mb_2u_lib.s9s_mb_2u(sch_1):h_cpu0_pmsync_cpu1';
NODE_NAME     U1 CW39
 '@S9S_MB_2U_LIB.S9S_MB_2U(SCH_1):PAGE45_I29@PURE_QUANTA.SOCKET4677_AZIF0045P001C01CS(CHIPS)':
 'PMDOWN0': CDS_PINID='PMDOWN0';
NODE_NAME     R4089 2
 '@S9S_MB_2U_LIB.S9S_MB_2U(SCH_1):PAGE14_I128@PURE_QUANTA.Q_RES(CHIPS)':
 'B': CDS_PINID='B';
NET_NAME
'H_CPU0_PMSYNC_CPU1_R'
 '@S9S_MB_2U_LIB.S9S_MB_2U(SCH_1):H_CPU0_PMSYNC_CPU1_R':
 C_SIGNAL='@s9s_mb_2u_lib.s9s_mb_2u(sch_1):h_cpu0_pmsync_cpu1_r';
NODE_NAME     U2 CN25
 '@S9S_MB_2U_LIB.S9S_MB_2U(SCH_1):PAGE14_I1@PURE_QUANTA.SOCKET4677_AZIF0045P001C01CS(CHIPS)':
 'PMSYNC0': CDS_PINID='PMSYNC0';
NODE_NAME     R322 1
 '@S9S_MB_2U_LIB.S9S_MB_2U(SCH_1):PAGE14_I90@PURE_QUANTA.Q_RES(CHIPS)':
 'A': CDS_PINID='A';
NET_NAME
'H_CPU0_PMSYNC_CPU1_R1'
 '@S9S_MB_2U_LIB.S9S_MB_2U(SCH_1):H_CPU0_PMSYNC_CPU1_R1':
 C_SIGNAL='@s9s_mb_2u_lib.s9s_mb_2u(sch_1):h_cpu0_pmsync_cpu1_r1';
NODE_NAME     R322 2
 '@S9S_MB_2U_LIB.S9S_MB_2U(SCH_1):PAGE14_I90@PURE_QUANTA.Q_RES(CHIPS)':
 'B': CDS_PINID='B';
NODE_NAME     R4089 1
 '@S9S_MB_2U_LIB.S9S_MB_2U(SCH_1):PAGE14_I128@PURE_QUANTA.Q_RES(CHIPS)':
 'A': CDS_PINID='A';
NET_NAME
'H_CPU0_PMSYNC_PCH'
 '@S9S_MB_2U_LIB.S9S_MB_2U(SCH_1):H_CPU0_PMSYNC_PCH':
 C_SIGNAL='@s9s_mb_2u_lib.s9s_mb_2u(sch_1):h_cpu0_pmsync_pch';
NODE_NAME     U2 DA39
 '@S9S_MB_2U_LIB.S9S_MB_2U(SCH_1):PAGE14_I1@PURE_QUANTA.SOCKET4677_AZIF0045P001C01CS(CHIPS)':
 'PMSYNC_PCH': CDS_PINID='PMSYNC_PCH';
NODE_NAME     R10 2
 '@S9S_MB_2U_LIB.S9S_MB_2U(SCH_1):PAGE14_I78@PURE_QUANTA.Q_RES(CHIPS)':
 'B': CDS_PINID='B';
NET_NAME
'H_CPU0_PMSYNC_PCH_R'
 '@S9S_MB_2U_LIB.S9S_MB_2U(SCH_1):H_CPU0_PMSYNC_PCH_R':
 C_SIGNAL='@s9s_mb_2u_lib.s9s_mb_2u(sch_1):h_cpu0_pmsync_pch_r';
NODE_NAME     R10 1
 '@S9S_MB_2U_LIB.S9S_MB_2U(SCH_1):PAGE14_I78@PURE_QUANTA.Q_RES(CHIPS)':
 'A': CDS_PINID='A';
NODE_NAME     R1960 2
 '@S9S_MB_2U_LIB.S9S_MB_2U(SCH_1):PAGE14_I117@PURE_QUANTA.Q_RES(CHIPS)':
 'B': CDS_PINID='B';
NET_NAME
'H_CPU0_PMSYNC_PCH_R2'
 '@S9S_MB_2U_LIB.S9S_MB_2U(SCH_1):H_CPU0_PMSYNC_PCH_R2':
 C_SIGNAL='@s9s_mb_2u_lib.s9s_mb_2u(sch_1):h_cpu0_pmsync_pch_r2';
NODE_NAME     R1960 1
 '@S9S_MB_2U_LIB.S9S_MB_2U(SCH_1):PAGE14_I117@PURE_QUANTA.Q_RES(CHIPS)':
 'A': CDS_PINID='A';
NODE_NAME     U4 AF8
 '@S9S_MB_2U_LIB.S9S_MB_2U(SCH_1):PAGE176_I22@PURE_QUANTA.EMMITSBURG_REV0P9(CHIPS)':
 'GPP_L_0_PM_SYNC_0': CDS_PINID='GPP_L_0_PM_SYNC_0';
NET_NAME
'H_CPU0_PM_FAST_WAKE_N'
 '@S9S_MB_2U_LIB.S9S_MB_2U(SCH_1):H_CPU0_PM_FAST_WAKE_N':
 C_SIGNAL='@s9s_mb_2u_lib.s9s_mb_2u(sch_1):h_cpu0_pm_fast_wake_n';
NODE_NAME     U2 CP20
 '@S9S_MB_2U_LIB.S9S_MB_2U(SCH_1):PAGE14_I1@PURE_QUANTA.SOCKET4677_AZIF0045P001C01CS(CHIPS)':
 'PMFAST_WAKE_N': CDS_PINID='PMFAST_WAKE_N';
NODE_NAME     R1240 1
 '@S9S_MB_2U_LIB.S9S_MB_2U(SCH_1):PAGE117_I9@PURE_QUANTA.Q_RES(CHIPS)':
 'A': CDS_PINID='A';
NET_NAME
'H_CPU0_PRDY_QS_GTL_R_N'
 '@S9S_MB_2U_LIB.S9S_MB_2U(SCH_1):H_CPU0_PRDY_QS_GTL_R_N':
 C_SIGNAL='@s9s_mb_2u_lib.s9s_mb_2u(sch_1):h_cpu0_prdy_qs_gtl_r_n';
NODE_NAME     R1 2
 '@S9S_MB_2U_LIB.S9S_MB_2U(SCH_1):PAGE13_I18@PURE_QUANTA.Q_RES(CHIPS)':
 'B': CDS_PINID='B';
NODE_NAME     U2 BP26
 '@S9S_MB_2U_LIB.S9S_MB_2U(SCH_1):PAGE13_I57@PURE_QUANTA.SOCKET4677_AZIF0045P001C01CS(CHIPS)':
 'PRDY_N': CDS_PINID='PRDY_N';
NET_NAME
'H_CPU0_PREQ_QS_GTL_R_N'
 '@S9S_MB_2U_LIB.S9S_MB_2U(SCH_1):H_CPU0_PREQ_QS_GTL_R_N':
 C_SIGNAL='@s9s_mb_2u_lib.s9s_mb_2u(sch_1):h_cpu0_preq_qs_gtl_r_n';
NODE_NAME     R2 2
 '@S9S_MB_2U_LIB.S9S_MB_2U(SCH_1):PAGE13_I16@PURE_QUANTA.Q_RES(CHIPS)':
 'B': CDS_PINID='B';
NODE_NAME     U2 AV22
 '@S9S_MB_2U_LIB.S9S_MB_2U(SCH_1):PAGE13_I57@PURE_QUANTA.SOCKET4677_AZIF0045P001C01CS(CHIPS)':
 'PREQ_N': CDS_PINID='PREQ_N';
NET_NAME
'H_CPU0_PROCHOT_LVC1_N'
 '@S9S_MB_2U_LIB.S9S_MB_2U(SCH_1):H_CPU0_PROCHOT_LVC1_N':
 C_SIGNAL='@s9s_mb_2u_lib.s9s_mb_2u(sch_1):h_cpu0_prochot_lvc1_n';
NODE_NAME     U2 AU19
 '@S9S_MB_2U_LIB.S9S_MB_2U(SCH_1):PAGE14_I1@PURE_QUANTA.SOCKET4677_AZIF0045P001C01CS(CHIPS)':
 'PROCHOT_N': CDS_PINID='PROCHOT_N';
NODE_NAME     R239 2
 '@S9S_MB_2U_LIB.S9S_MB_2U(SCH_1):PAGE121_I7@PURE_QUANTA.Q_RES(CHIPS)':
 'B': CDS_PINID='B';
NODE_NAME     R243 2
 '@S9S_MB_2U_LIB.S9S_MB_2U(SCH_1):PAGE121_I23@PURE_QUANTA.Q_RES(CHIPS)':
 'B': CDS_PINID='B';
NET_NAME
'H_CPU0_PROCHOT_LVC1_R_N'
 '@S9S_MB_2U_LIB.S9S_MB_2U(SCH_1):H_CPU0_PROCHOT_LVC1_R_N':
 C_SIGNAL='@s9s_mb_2u_lib.s9s_mb_2u(sch_1):h_cpu0_prochot_lvc1_r_n';
NODE_NAME     U249 W4
 '@S9S_MB_2U_LIB.S9S_MB_2U(SCH_1):PAGE311_I33@PURE_QUANTA.LCMXO3LF9400C5BG484C(CHIPS)':
 'PL30B': CDS_PINID='PL30B';
NODE_NAME     R239 1
 '@S9S_MB_2U_LIB.S9S_MB_2U(SCH_1):PAGE121_I7@PURE_QUANTA.Q_RES(CHIPS)':
 'A': CDS_PINID='A';
NET_NAME
'H_CPU0_RMCA_LVC1_R_N'
 '@S9S_MB_2U_LIB.S9S_MB_2U(SCH_1):H_CPU0_RMCA_LVC1_R_N':
 C_SIGNAL='@s9s_mb_2u_lib.s9s_mb_2u(sch_1):h_cpu0_rmca_lvc1_r_n';
NODE_NAME     U2 BH22
 '@S9S_MB_2U_LIB.S9S_MB_2U(SCH_1):PAGE16_I1@PURE_QUANTA.SOCKET4677_AZIF0045P001C01CS(CHIPS)':
 'RMCA_N': CDS_PINID='RMCA_N';
NODE_NAME     R302 1
 '@S9S_MB_2U_LIB.S9S_MB_2U(SCH_1):PAGE118_I101@PURE_QUANTA.Q_RES(CHIPS)':
 'A': CDS_PINID='A';
NET_NAME
'H_CPU0_THERMTRIP_LVC1_N'
 '@S9S_MB_2U_LIB.S9S_MB_2U(SCH_1):H_CPU0_THERMTRIP_LVC1_N':
 C_SIGNAL='@s9s_mb_2u_lib.s9s_mb_2u(sch_1):h_cpu0_thermtrip_lvc1_n';
NODE_NAME     U249 T2
 '@S9S_MB_2U_LIB.S9S_MB_2U(SCH_1):PAGE311_I33@PURE_QUANTA.LCMXO3LF9400C5BG484C(CHIPS)':
 'PL25A': CDS_PINID='PL25A';
NODE_NAME     R4399 2
 '@S9S_MB_2U_LIB.S9S_MB_2U(SCH_1):PAGE121_I35@PURE_QUANTA.Q_RES(CHIPS)':
 'B': CDS_PINID='B';
NET_NAME
'H_CPU0_THERMTRIP_LVC1_R_N'
 '@S9S_MB_2U_LIB.S9S_MB_2U(SCH_1):H_CPU0_THERMTRIP_LVC1_R_N':
 C_SIGNAL='@s9s_mb_2u_lib.s9s_mb_2u(sch_1):h_cpu0_thermtrip_lvc1_r_n';
NODE_NAME     U2 BL62
 '@S9S_MB_2U_LIB.S9S_MB_2U(SCH_1):PAGE14_I1@PURE_QUANTA.SOCKET4677_AZIF0045P001C01CS(CHIPS)':
 'THERMTRIP_N': CDS_PINID='THERMTRIP_N';
NODE_NAME     R4395 2
 '@S9S_MB_2U_LIB.S9S_MB_2U(SCH_1):PAGE121_I13@PURE_QUANTA.Q_RES(CHIPS)':
 'B': CDS_PINID='B';
NODE_NAME     R237 1
 '@S9S_MB_2U_LIB.S9S_MB_2U(SCH_1):PAGE121_I15@PURE_QUANTA.Q_RES(CHIPS)':
 'A': CDS_PINID='A';
NET_NAME
'H_CPU0_THERMTRIP_N'
 '@S9S_MB_2U_LIB.S9S_MB_2U(SCH_1):H_CPU0_THERMTRIP_N':
 C_SIGNAL='@s9s_mb_2u_lib.s9s_mb_2u(sch_1):h_cpu0_thermtrip_n';
NODE_NAME     R4397 1
 '@S9S_MB_2U_LIB.S9S_MB_2U(SCH_1):PAGE121_I16@PURE_QUANTA.Q_RES(CHIPS)':
 'A': CDS_PINID='A';
NODE_NAME     Q138 3
 '@S9S_MB_2U_LIB.S9S_MB_2U(SCH_1):PAGE121_I17@PURE_QUANTA.BC847BPN(CHIPS)':
 'C2': CDS_PINID='C2';
NET_NAME
'H_CPU0_THERMTRIP_R_N'
 '@S9S_MB_2U_LIB.S9S_MB_2U(SCH_1):H_CPU0_THERMTRIP_R_N':
 C_SIGNAL='@s9s_mb_2u_lib.s9s_mb_2u(sch_1):h_cpu0_thermtrip_r_n';
NODE_NAME     R4397 2
 '@S9S_MB_2U_LIB.S9S_MB_2U(SCH_1):PAGE121_I16@PURE_QUANTA.Q_RES(CHIPS)':
 'B': CDS_PINID='B';
NODE_NAME     Q138 2
 '@S9S_MB_2U_LIB.S9S_MB_2U(SCH_1):PAGE121_I31@PURE_QUANTA.BC847BPN(CHIPS)':
 'B1': CDS_PINID='B1';
NET_NAME
'H_CPU0_THERMTRIP_VT_N'
 '@S9S_MB_2U_LIB.S9S_MB_2U(SCH_1):H_CPU0_THERMTRIP_VT_N':
 C_SIGNAL='@s9s_mb_2u_lib.s9s_mb_2u(sch_1):h_cpu0_thermtrip_vt_n';
NODE_NAME     Q138 6
 '@S9S_MB_2U_LIB.S9S_MB_2U(SCH_1):PAGE121_I31@PURE_QUANTA.BC847BPN(CHIPS)':
 'C1': CDS_PINID='C1';
NODE_NAME     R241 2
 '@S9S_MB_2U_LIB.S9S_MB_2U(SCH_1):PAGE121_I33@PURE_QUANTA.Q_RES(CHIPS)':
 'B': CDS_PINID='B';
NODE_NAME     R4399 1
 '@S9S_MB_2U_LIB.S9S_MB_2U(SCH_1):PAGE121_I35@PURE_QUANTA.Q_RES(CHIPS)':
 'A': CDS_PINID='A';
NET_NAME
'H_CPU0_THERMTRIP_VT_R_N'
 '@S9S_MB_2U_LIB.S9S_MB_2U(SCH_1):H_CPU0_THERMTRIP_VT_R_N':
 C_SIGNAL='@s9s_mb_2u_lib.s9s_mb_2u(sch_1):h_cpu0_thermtrip_vt_r_n';
NODE_NAME     R237 2
 '@S9S_MB_2U_LIB.S9S_MB_2U(SCH_1):PAGE121_I15@PURE_QUANTA.Q_RES(CHIPS)':
 'B': CDS_PINID='B';
NODE_NAME     Q138 5
 '@S9S_MB_2U_LIB.S9S_MB_2U(SCH_1):PAGE121_I17@PURE_QUANTA.BC847BPN(CHIPS)':
 'B2': CDS_PINID='B2';
NET_NAME
'H_CPU1_BMCINIT_LVC1'
 '@S9S_MB_2U_LIB.S9S_MB_2U(SCH_1):H_CPU1_BMCINIT_LVC1':
 C_SIGNAL='@s9s_mb_2u_lib.s9s_mb_2u(sch_1):h_cpu1_bmcinit_lvc1';
NODE_NAME     U1 BN23
 '@S9S_MB_2U_LIB.S9S_MB_2U(SCH_1):PAGE44_I51@PURE_QUANTA.SOCKET4677_AZIF0045P001C01CS(CHIPS)':
 'BMCINIT': CDS_PINID='BMCINIT';
NODE_NAME     R264 2
 '@S9S_MB_2U_LIB.S9S_MB_2U(SCH_1):PAGE119_I98@PURE_QUANTA.Q_RES(CHIPS)':
 'B': CDS_PINID='B';
NET_NAME
'H_CPU1_CATERR_LVC1_R_N'
 '@S9S_MB_2U_LIB.S9S_MB_2U(SCH_1):H_CPU1_CATERR_LVC1_R_N':
 C_SIGNAL='@s9s_mb_2u_lib.s9s_mb_2u(sch_1):h_cpu1_caterr_lvc1_r_n';
NODE_NAME     U1 BP24
 '@S9S_MB_2U_LIB.S9S_MB_2U(SCH_1):PAGE45_I29@PURE_QUANTA.SOCKET4677_AZIF0045P001C01CS(CHIPS)':
 'CATERR_N': CDS_PINID='CATERR_N';
NODE_NAME     R299 1
 '@S9S_MB_2U_LIB.S9S_MB_2U(SCH_1):PAGE118_I63@PURE_QUANTA.Q_RES(CHIPS)':
 'A': CDS_PINID='A';
NET_NAME
'H_CPU1_ERR0_LVC1_R_N'
 '@S9S_MB_2U_LIB.S9S_MB_2U(SCH_1):H_CPU1_ERR0_LVC1_R_N':
 C_SIGNAL='@s9s_mb_2u_lib.s9s_mb_2u(sch_1):h_cpu1_err0_lvc1_r_n';
NODE_NAME     U1 BF22
 '@S9S_MB_2U_LIB.S9S_MB_2U(SCH_1):PAGE45_I29@PURE_QUANTA.SOCKET4677_AZIF0045P001C01CS(CHIPS)':
 'ERROR_N0': CDS_PINID='ERROR_N0';
NODE_NAME     R337 1
 '@S9S_MB_2U_LIB.S9S_MB_2U(SCH_1):PAGE322_I160@PURE_QUANTA.Q_RES(CHIPS)':
 'A': CDS_PINID='A';
NET_NAME
'H_CPU1_ERR1_LVC1_R_N'
 '@S9S_MB_2U_LIB.S9S_MB_2U(SCH_1):H_CPU1_ERR1_LVC1_R_N':
 C_SIGNAL='@s9s_mb_2u_lib.s9s_mb_2u(sch_1):h_cpu1_err1_lvc1_r_n';
NODE_NAME     U1 AY22
 '@S9S_MB_2U_LIB.S9S_MB_2U(SCH_1):PAGE45_I29@PURE_QUANTA.SOCKET4677_AZIF0045P001C01CS(CHIPS)':
 'ERROR_N1': CDS_PINID='ERROR_N1';
NODE_NAME     R341 1
 '@S9S_MB_2U_LIB.S9S_MB_2U(SCH_1):PAGE322_I163@PURE_QUANTA.Q_RES(CHIPS)':
 'A': CDS_PINID='A';
NET_NAME
'H_CPU1_ERR2_LVC1_R_N'
 '@S9S_MB_2U_LIB.S9S_MB_2U(SCH_1):H_CPU1_ERR2_LVC1_R_N':
 C_SIGNAL='@s9s_mb_2u_lib.s9s_mb_2u(sch_1):h_cpu1_err2_lvc1_r_n';
NODE_NAME     U1 BD22
 '@S9S_MB_2U_LIB.S9S_MB_2U(SCH_1):PAGE45_I29@PURE_QUANTA.SOCKET4677_AZIF0045P001C01CS(CHIPS)':
 'ERROR_N2': CDS_PINID='ERROR_N2';
NODE_NAME     R345 1
 '@S9S_MB_2U_LIB.S9S_MB_2U(SCH_1):PAGE322_I158@PURE_QUANTA.Q_RES(CHIPS)':
 'A': CDS_PINID='A';
NET_NAME
'H_CPU1_MEMHOT_IN_LVC1_N'
 '@S9S_MB_2U_LIB.S9S_MB_2U(SCH_1):H_CPU1_MEMHOT_IN_LVC1_N':
 C_SIGNAL='@s9s_mb_2u_lib.s9s_mb_2u(sch_1):h_cpu1_memhot_in_lvc1_n';
NODE_NAME     U1 AU21
 '@S9S_MB_2U_LIB.S9S_MB_2U(SCH_1):PAGE45_I29@PURE_QUANTA.SOCKET4677_AZIF0045P001C01CS(CHIPS)':
 'MEMHOT_IN_N': CDS_PINID='MEMHOT_IN_N';
NODE_NAME     R4294 2
 '@S9S_MB_2U_LIB.S9S_MB_2U(SCH_1):PAGE122_I33@PURE_QUANTA.Q_RES(CHIPS)':
 'B': CDS_PINID='B';
NET_NAME
'H_CPU1_MEMHOT_IN_LVC1_R1_N'
 '@S9S_MB_2U_LIB.S9S_MB_2U(SCH_1):H_CPU1_MEMHOT_IN_LVC1_R1_N':
 C_SIGNAL='@s9s_mb_2u_lib.s9s_mb_2u(sch_1):h_cpu1_memhot_in_lvc1_r1_n';
NODE_NAME     R210 2
 '@S9S_MB_2U_LIB.S9S_MB_2U(SCH_1):PAGE122_I15@PURE_QUANTA.Q_RES(CHIPS)':
 'B': CDS_PINID='B';
NODE_NAME     R220 2
 '@S9S_MB_2U_LIB.S9S_MB_2U(SCH_1):PAGE122_I29@PURE_QUANTA.Q_RES(CHIPS)':
 'B': CDS_PINID='B';
NODE_NAME     R4294 1
 '@S9S_MB_2U_LIB.S9S_MB_2U(SCH_1):PAGE122_I33@PURE_QUANTA.Q_RES(CHIPS)':
 'A': CDS_PINID='A';
NET_NAME
'H_CPU1_MEMHOT_IN_LVC1_R_N'
 '@S9S_MB_2U_LIB.S9S_MB_2U(SCH_1):H_CPU1_MEMHOT_IN_LVC1_R_N':
 C_SIGNAL='@s9s_mb_2u_lib.s9s_mb_2u(sch_1):h_cpu1_memhot_in_lvc1_r_n';
NODE_NAME     U249 V5
 '@S9S_MB_2U_LIB.S9S_MB_2U(SCH_1):PAGE311_I33@PURE_QUANTA.LCMXO3LF9400C5BG484C(CHIPS)':
 'PL30C': CDS_PINID='PL30C';
NODE_NAME     R210 1
 '@S9S_MB_2U_LIB.S9S_MB_2U(SCH_1):PAGE122_I15@PURE_QUANTA.Q_RES(CHIPS)':
 'A': CDS_PINID='A';
NET_NAME
'H_CPU1_MEMHOT_OUT'
 '@S9S_MB_2U_LIB.S9S_MB_2U(SCH_1):H_CPU1_MEMHOT_OUT':
 C_SIGNAL='@s9s_mb_2u_lib.s9s_mb_2u(sch_1):h_cpu1_memhot_out';
NODE_NAME     Q142 3
 '@S9S_MB_2U_LIB.S9S_MB_2U(SCH_1):PAGE122_I10@PURE_QUANTA.BC847BPN(CHIPS)':
 'C2': CDS_PINID='C2';
NODE_NAME     R4404 1
 '@S9S_MB_2U_LIB.S9S_MB_2U(SCH_1):PAGE122_I20@PURE_QUANTA.Q_RES(CHIPS)':
 'A': CDS_PINID='A';
NET_NAME
'H_CPU1_MEMHOT_OUT_LVC1_N'
 '@S9S_MB_2U_LIB.S9S_MB_2U(SCH_1):H_CPU1_MEMHOT_OUT_LVC1_N':
 C_SIGNAL='@s9s_mb_2u_lib.s9s_mb_2u(sch_1):h_cpu1_memhot_out_lvc1_n';
NODE_NAME     U249 R7
 '@S9S_MB_2U_LIB.S9S_MB_2U(SCH_1):PAGE311_I33@PURE_QUANTA.LCMXO3LF9400C5BG484C(CHIPS)':
 'PL25D': CDS_PINID='PL25D';
NODE_NAME     R4408 2
 '@S9S_MB_2U_LIB.S9S_MB_2U(SCH_1):PAGE122_I18@PURE_QUANTA.Q_RES(CHIPS)':
 'B': CDS_PINID='B';
NET_NAME
'H_CPU1_MEMHOT_OUT_LVC1_R_N'
 '@S9S_MB_2U_LIB.S9S_MB_2U(SCH_1):H_CPU1_MEMHOT_OUT_LVC1_R_N':
 C_SIGNAL='@s9s_mb_2u_lib.s9s_mb_2u(sch_1):h_cpu1_memhot_out_lvc1_r_n';
NODE_NAME     U1 CF26
 '@S9S_MB_2U_LIB.S9S_MB_2U(SCH_1):PAGE45_I29@PURE_QUANTA.SOCKET4677_AZIF0045P001C01CS(CHIPS)':
 'MEMHOT_OUT_N': CDS_PINID='MEMHOT_OUT_N';
NODE_NAME     R4402 2
 '@S9S_MB_2U_LIB.S9S_MB_2U(SCH_1):PAGE122_I5@PURE_QUANTA.Q_RES(CHIPS)':
 'B': CDS_PINID='B';
NODE_NAME     R204 1
 '@S9S_MB_2U_LIB.S9S_MB_2U(SCH_1):PAGE122_I6@PURE_QUANTA.Q_RES(CHIPS)':
 'A': CDS_PINID='A';
NET_NAME
'H_CPU1_MEMHOT_OUT_R'
 '@S9S_MB_2U_LIB.S9S_MB_2U(SCH_1):H_CPU1_MEMHOT_OUT_R':
 C_SIGNAL='@s9s_mb_2u_lib.s9s_mb_2u(sch_1):h_cpu1_memhot_out_r';
NODE_NAME     Q142 2
 '@S9S_MB_2U_LIB.S9S_MB_2U(SCH_1):PAGE122_I17@PURE_QUANTA.BC847BPN(CHIPS)':
 'B1': CDS_PINID='B1';
NODE_NAME     R4404 2
 '@S9S_MB_2U_LIB.S9S_MB_2U(SCH_1):PAGE122_I20@PURE_QUANTA.Q_RES(CHIPS)':
 'B': CDS_PINID='B';
NET_NAME
'H_CPU1_MEMHOT_OUT_VT_N'
 '@S9S_MB_2U_LIB.S9S_MB_2U(SCH_1):H_CPU1_MEMHOT_OUT_VT_N':
 C_SIGNAL='@s9s_mb_2u_lib.s9s_mb_2u(sch_1):h_cpu1_memhot_out_vt_n';
NODE_NAME     Q142 6
 '@S9S_MB_2U_LIB.S9S_MB_2U(SCH_1):PAGE122_I17@PURE_QUANTA.BC847BPN(CHIPS)':
 'C1': CDS_PINID='C1';
NODE_NAME     R4408 1
 '@S9S_MB_2U_LIB.S9S_MB_2U(SCH_1):PAGE122_I18@PURE_QUANTA.Q_RES(CHIPS)':
 'A': CDS_PINID='A';
NODE_NAME     R4406 2
 '@S9S_MB_2U_LIB.S9S_MB_2U(SCH_1):PAGE122_I24@PURE_QUANTA.Q_RES(CHIPS)':
 'B': CDS_PINID='B';
NET_NAME
'H_CPU1_MEMHOT_OUT_VT_R_N'
 '@S9S_MB_2U_LIB.S9S_MB_2U(SCH_1):H_CPU1_MEMHOT_OUT_VT_R_N':
 C_SIGNAL='@s9s_mb_2u_lib.s9s_mb_2u(sch_1):h_cpu1_memhot_out_vt_r_n';
NODE_NAME     R204 2
 '@S9S_MB_2U_LIB.S9S_MB_2U(SCH_1):PAGE122_I6@PURE_QUANTA.Q_RES(CHIPS)':
 'B': CDS_PINID='B';
NODE_NAME     Q142 5
 '@S9S_MB_2U_LIB.S9S_MB_2U(SCH_1):PAGE122_I10@PURE_QUANTA.BC847BPN(CHIPS)':
 'B2': CDS_PINID='B2';
NET_NAME
'H_CPU1_MEMTRIP'
 '@S9S_MB_2U_LIB.S9S_MB_2U(SCH_1):H_CPU1_MEMTRIP':
 C_SIGNAL='@s9s_mb_2u_lib.s9s_mb_2u(sch_1):h_cpu1_memtrip';
NODE_NAME     Q140 3
 '@S9S_MB_2U_LIB.S9S_MB_2U(SCH_1):PAGE123_I11@PURE_QUANTA.BC847BPN(CHIPS)':
 'C2': CDS_PINID='C2';
NODE_NAME     R4410 1
 '@S9S_MB_2U_LIB.S9S_MB_2U(SCH_1):PAGE123_I14@PURE_QUANTA.Q_RES(CHIPS)':
 'A': CDS_PINID='A';
NET_NAME
'H_CPU1_MEMTRIP_LVC1_N'
 '@S9S_MB_2U_LIB.S9S_MB_2U(SCH_1):H_CPU1_MEMTRIP_LVC1_N':
 C_SIGNAL='@s9s_mb_2u_lib.s9s_mb_2u(sch_1):h_cpu1_memtrip_lvc1_n';
NODE_NAME     U249 U1
 '@S9S_MB_2U_LIB.S9S_MB_2U(SCH_1):PAGE311_I33@PURE_QUANTA.LCMXO3LF9400C5BG484C(CHIPS)':
 'PL25B': CDS_PINID='PL25B';
NODE_NAME     R4414 2
 '@S9S_MB_2U_LIB.S9S_MB_2U(SCH_1):PAGE123_I31@PURE_QUANTA.Q_RES(CHIPS)':
 'B': CDS_PINID='B';
NET_NAME
'H_CPU1_MEMTRIP_LVC1_R_N'
 '@S9S_MB_2U_LIB.S9S_MB_2U(SCH_1):H_CPU1_MEMTRIP_LVC1_R_N':
 C_SIGNAL='@s9s_mb_2u_lib.s9s_mb_2u(sch_1):h_cpu1_memtrip_lvc1_r_n';
NODE_NAME     U1 AV24
 '@S9S_MB_2U_LIB.S9S_MB_2U(SCH_1):PAGE45_I29@PURE_QUANTA.SOCKET4677_AZIF0045P001C01CS(CHIPS)':
 'MEMTRIP_N': CDS_PINID='MEMTRIP_N';
NODE_NAME     R206 1
 '@S9S_MB_2U_LIB.S9S_MB_2U(SCH_1):PAGE123_I8@PURE_QUANTA.Q_RES(CHIPS)':
 'A': CDS_PINID='A';
NODE_NAME     R202 2
 '@S9S_MB_2U_LIB.S9S_MB_2U(SCH_1):PAGE123_I7@PURE_QUANTA.Q_RES(CHIPS)':
 'B': CDS_PINID='B';
NET_NAME
'H_CPU1_MEMTRIP_OUT_VT_R_N'
 '@S9S_MB_2U_LIB.S9S_MB_2U(SCH_1):H_CPU1_MEMTRIP_OUT_VT_R_N':
 C_SIGNAL='@s9s_mb_2u_lib.s9s_mb_2u(sch_1):h_cpu1_memtrip_out_vt_r_n';
NODE_NAME     R206 2
 '@S9S_MB_2U_LIB.S9S_MB_2U(SCH_1):PAGE123_I8@PURE_QUANTA.Q_RES(CHIPS)':
 'B': CDS_PINID='B';
NODE_NAME     Q140 5
 '@S9S_MB_2U_LIB.S9S_MB_2U(SCH_1):PAGE123_I11@PURE_QUANTA.BC847BPN(CHIPS)':
 'B2': CDS_PINID='B2';
NET_NAME
'H_CPU1_MEMTRIP_R'
 '@S9S_MB_2U_LIB.S9S_MB_2U(SCH_1):H_CPU1_MEMTRIP_R':
 C_SIGNAL='@s9s_mb_2u_lib.s9s_mb_2u(sch_1):h_cpu1_memtrip_r';
NODE_NAME     R4410 2
 '@S9S_MB_2U_LIB.S9S_MB_2U(SCH_1):PAGE123_I14@PURE_QUANTA.Q_RES(CHIPS)':
 'B': CDS_PINID='B';
NODE_NAME     Q140 2
 '@S9S_MB_2U_LIB.S9S_MB_2U(SCH_1):PAGE123_I16@PURE_QUANTA.BC847BPN(CHIPS)':
 'B1': CDS_PINID='B1';
NET_NAME
'H_CPU1_MEMTRIP_VT_N'
 '@S9S_MB_2U_LIB.S9S_MB_2U(SCH_1):H_CPU1_MEMTRIP_VT_N':
 C_SIGNAL='@s9s_mb_2u_lib.s9s_mb_2u(sch_1):h_cpu1_memtrip_vt_n';
NODE_NAME     Q140 6
 '@S9S_MB_2U_LIB.S9S_MB_2U(SCH_1):PAGE123_I16@PURE_QUANTA.BC847BPN(CHIPS)':
 'C1': CDS_PINID='C1';
NODE_NAME     R4412 2
 '@S9S_MB_2U_LIB.S9S_MB_2U(SCH_1):PAGE123_I29@PURE_QUANTA.Q_RES(CHIPS)':
 'B': CDS_PINID='B';
NODE_NAME     R4414 1
 '@S9S_MB_2U_LIB.S9S_MB_2U(SCH_1):PAGE123_I31@PURE_QUANTA.Q_RES(CHIPS)':
 'A': CDS_PINID='A';
NET_NAME
'H_CPU1_NMI_LVC1_N'
 '@S9S_MB_2U_LIB.S9S_MB_2U(SCH_1):H_CPU1_NMI_LVC1_N':
 C_SIGNAL='@s9s_mb_2u_lib.s9s_mb_2u(sch_1):h_cpu1_nmi_lvc1_n';
NODE_NAME     U1 AV18
 '@S9S_MB_2U_LIB.S9S_MB_2U(SCH_1):PAGE45_I29@PURE_QUANTA.SOCKET4677_AZIF0045P001C01CS(CHIPS)':
 'NMI': CDS_PINID='NMI';
NODE_NAME     R196 2
 '@S9S_MB_2U_LIB.S9S_MB_2U(SCH_1):PAGE123_I5@PURE_QUANTA.Q_RES(CHIPS)':
 'B': CDS_PINID='B';
NODE_NAME     R198 2
 '@S9S_MB_2U_LIB.S9S_MB_2U(SCH_1):PAGE123_I23@PURE_QUANTA.Q_RES(CHIPS)':
 'B': CDS_PINID='B';
NET_NAME
'H_CPU1_PM_FAST_WAKE_N'
 '@S9S_MB_2U_LIB.S9S_MB_2U(SCH_1):H_CPU1_PM_FAST_WAKE_N':
 C_SIGNAL='@s9s_mb_2u_lib.s9s_mb_2u(sch_1):h_cpu1_pm_fast_wake_n';
NODE_NAME     U1 CP20
 '@S9S_MB_2U_LIB.S9S_MB_2U(SCH_1):PAGE45_I29@PURE_QUANTA.SOCKET4677_AZIF0045P001C01CS(CHIPS)':
 'PMFAST_WAKE_N': CDS_PINID='PMFAST_WAKE_N';
NODE_NAME     R3023 2
 '@S9S_MB_2U_LIB.S9S_MB_2U(SCH_1):PAGE117_I10@PURE_QUANTA.Q_RES(CHIPS)':
 'B': CDS_PINID='B';
NET_NAME
'H_CPU1_PRDY_QS_GTL_R_N'
 '@S9S_MB_2U_LIB.S9S_MB_2U(SCH_1):H_CPU1_PRDY_QS_GTL_R_N':
 C_SIGNAL='@s9s_mb_2u_lib.s9s_mb_2u(sch_1):h_cpu1_prdy_qs_gtl_r_n';
NODE_NAME     R61 2
 '@S9S_MB_2U_LIB.S9S_MB_2U(SCH_1):PAGE44_I16@PURE_QUANTA.Q_RES(CHIPS)':
 'B': CDS_PINID='B';
NODE_NAME     U1 BP26
 '@S9S_MB_2U_LIB.S9S_MB_2U(SCH_1):PAGE44_I51@PURE_QUANTA.SOCKET4677_AZIF0045P001C01CS(CHIPS)':
 'PRDY_N': CDS_PINID='PRDY_N';
NET_NAME
'H_CPU1_PREQ_QS_GTL_R_N'
 '@S9S_MB_2U_LIB.S9S_MB_2U(SCH_1):H_CPU1_PREQ_QS_GTL_R_N':
 C_SIGNAL='@s9s_mb_2u_lib.s9s_mb_2u(sch_1):h_cpu1_preq_qs_gtl_r_n';
NODE_NAME     R62 2
 '@S9S_MB_2U_LIB.S9S_MB_2U(SCH_1):PAGE44_I11@PURE_QUANTA.Q_RES(CHIPS)':
 'B': CDS_PINID='B';
NODE_NAME     U1 AV22
 '@S9S_MB_2U_LIB.S9S_MB_2U(SCH_1):PAGE44_I51@PURE_QUANTA.SOCKET4677_AZIF0045P001C01CS(CHIPS)':
 'PREQ_N': CDS_PINID='PREQ_N';
NET_NAME
'H_CPU1_PROCHOT_LVC1_N'
 '@S9S_MB_2U_LIB.S9S_MB_2U(SCH_1):H_CPU1_PROCHOT_LVC1_N':
 C_SIGNAL='@s9s_mb_2u_lib.s9s_mb_2u(sch_1):h_cpu1_prochot_lvc1_n';
NODE_NAME     U1 AU19
 '@S9S_MB_2U_LIB.S9S_MB_2U(SCH_1):PAGE45_I29@PURE_QUANTA.SOCKET4677_AZIF0045P001C01CS(CHIPS)':
 'PROCHOT_N': CDS_PINID='PROCHOT_N';
NODE_NAME     R240 2
 '@S9S_MB_2U_LIB.S9S_MB_2U(SCH_1):PAGE121_I5@PURE_QUANTA.Q_RES(CHIPS)':
 'B': CDS_PINID='B';
NODE_NAME     R244 2
 '@S9S_MB_2U_LIB.S9S_MB_2U(SCH_1):PAGE121_I19@PURE_QUANTA.Q_RES(CHIPS)':
 'B': CDS_PINID='B';
NET_NAME
'H_CPU1_PROCHOT_LVC1_R_N'
 '@S9S_MB_2U_LIB.S9S_MB_2U(SCH_1):H_CPU1_PROCHOT_LVC1_R_N':
 C_SIGNAL='@s9s_mb_2u_lib.s9s_mb_2u(sch_1):h_cpu1_prochot_lvc1_r_n';
NODE_NAME     U249 Y3
 '@S9S_MB_2U_LIB.S9S_MB_2U(SCH_1):PAGE311_I33@PURE_QUANTA.LCMXO3LF9400C5BG484C(CHIPS)':
 'PL30A': CDS_PINID='PL30A';
NODE_NAME     R240 1
 '@S9S_MB_2U_LIB.S9S_MB_2U(SCH_1):PAGE121_I5@PURE_QUANTA.Q_RES(CHIPS)':
 'A': CDS_PINID='A';
NET_NAME
'H_CPU1_RMCA_LVC1_R_N'
 '@S9S_MB_2U_LIB.S9S_MB_2U(SCH_1):H_CPU1_RMCA_LVC1_R_N':
 C_SIGNAL='@s9s_mb_2u_lib.s9s_mb_2u(sch_1):h_cpu1_rmca_lvc1_r_n';
NODE_NAME     U1 BH22
 '@S9S_MB_2U_LIB.S9S_MB_2U(SCH_1):PAGE47_I16@PURE_QUANTA.SOCKET4677_AZIF0045P001C01CS(CHIPS)':
 'RMCA_N': CDS_PINID='RMCA_N';
NODE_NAME     R304 1
 '@S9S_MB_2U_LIB.S9S_MB_2U(SCH_1):PAGE118_I102@PURE_QUANTA.Q_RES(CHIPS)':
 'A': CDS_PINID='A';
NET_NAME
'H_CPU1_THERMTRIP_LVC1_N'
 '@S9S_MB_2U_LIB.S9S_MB_2U(SCH_1):H_CPU1_THERMTRIP_LVC1_N':
 C_SIGNAL='@s9s_mb_2u_lib.s9s_mb_2u(sch_1):h_cpu1_thermtrip_lvc1_n';
NODE_NAME     U249 P7
 '@S9S_MB_2U_LIB.S9S_MB_2U(SCH_1):PAGE311_I33@PURE_QUANTA.LCMXO3LF9400C5BG484C(CHIPS)':
 'PL24D': CDS_PINID='PL24D';
NODE_NAME     R4400 2
 '@S9S_MB_2U_LIB.S9S_MB_2U(SCH_1):PAGE121_I29@PURE_QUANTA.Q_RES(CHIPS)':
 'B': CDS_PINID='B';
NET_NAME
'H_CPU1_THERMTRIP_LVC1_R_N'
 '@S9S_MB_2U_LIB.S9S_MB_2U(SCH_1):H_CPU1_THERMTRIP_LVC1_R_N':
 C_SIGNAL='@s9s_mb_2u_lib.s9s_mb_2u(sch_1):h_cpu1_thermtrip_lvc1_r_n';
NODE_NAME     U1 BL62
 '@S9S_MB_2U_LIB.S9S_MB_2U(SCH_1):PAGE45_I29@PURE_QUANTA.SOCKET4677_AZIF0045P001C01CS(CHIPS)':
 'THERMTRIP_N': CDS_PINID='THERMTRIP_N';
NODE_NAME     R4396 2
 '@S9S_MB_2U_LIB.S9S_MB_2U(SCH_1):PAGE121_I4@PURE_QUANTA.Q_RES(CHIPS)':
 'B': CDS_PINID='B';
NODE_NAME     R238 1
 '@S9S_MB_2U_LIB.S9S_MB_2U(SCH_1):PAGE121_I6@PURE_QUANTA.Q_RES(CHIPS)':
 'A': CDS_PINID='A';
NET_NAME
'H_CPU1_THERMTRIP_N'
 '@S9S_MB_2U_LIB.S9S_MB_2U(SCH_1):H_CPU1_THERMTRIP_N':
 C_SIGNAL='@s9s_mb_2u_lib.s9s_mb_2u(sch_1):h_cpu1_thermtrip_n';
NODE_NAME     Q139 3
 '@S9S_MB_2U_LIB.S9S_MB_2U(SCH_1):PAGE121_I8@PURE_QUANTA.BC847BPN(CHIPS)':
 'C2': CDS_PINID='C2';
NODE_NAME     R4398 1
 '@S9S_MB_2U_LIB.S9S_MB_2U(SCH_1):PAGE121_I10@PURE_QUANTA.Q_RES(CHIPS)':
 'A': CDS_PINID='A';
NET_NAME
'H_CPU1_THERMTRIP_R_N'
 '@S9S_MB_2U_LIB.S9S_MB_2U(SCH_1):H_CPU1_THERMTRIP_R_N':
 C_SIGNAL='@s9s_mb_2u_lib.s9s_mb_2u(sch_1):h_cpu1_thermtrip_r_n';
NODE_NAME     R4398 2
 '@S9S_MB_2U_LIB.S9S_MB_2U(SCH_1):PAGE121_I10@PURE_QUANTA.Q_RES(CHIPS)':
 'B': CDS_PINID='B';
NODE_NAME     Q139 2
 '@S9S_MB_2U_LIB.S9S_MB_2U(SCH_1):PAGE121_I21@PURE_QUANTA.BC847BPN(CHIPS)':
 'B1': CDS_PINID='B1';
NET_NAME
'H_CPU1_THERMTRIP_VT_N'
 '@S9S_MB_2U_LIB.S9S_MB_2U(SCH_1):H_CPU1_THERMTRIP_VT_N':
 C_SIGNAL='@s9s_mb_2u_lib.s9s_mb_2u(sch_1):h_cpu1_thermtrip_vt_n';
NODE_NAME     Q139 6
 '@S9S_MB_2U_LIB.S9S_MB_2U(SCH_1):PAGE121_I21@PURE_QUANTA.BC847BPN(CHIPS)':
 'C1': CDS_PINID='C1';
NODE_NAME     R242 2
 '@S9S_MB_2U_LIB.S9S_MB_2U(SCH_1):PAGE121_I26@PURE_QUANTA.Q_RES(CHIPS)':
 'B': CDS_PINID='B';
NODE_NAME     R4400 1
 '@S9S_MB_2U_LIB.S9S_MB_2U(SCH_1):PAGE121_I29@PURE_QUANTA.Q_RES(CHIPS)':
 'A': CDS_PINID='A';
NET_NAME
'H_CPU1_THERMTRIP_VT_R_N'
 '@S9S_MB_2U_LIB.S9S_MB_2U(SCH_1):H_CPU1_THERMTRIP_VT_R_N':
 C_SIGNAL='@s9s_mb_2u_lib.s9s_mb_2u(sch_1):h_cpu1_thermtrip_vt_r_n';
NODE_NAME     R238 2
 '@S9S_MB_2U_LIB.S9S_MB_2U(SCH_1):PAGE121_I6@PURE_QUANTA.Q_RES(CHIPS)':
 'B': CDS_PINID='B';
NODE_NAME     Q139 5
 '@S9S_MB_2U_LIB.S9S_MB_2U(SCH_1):PAGE121_I8@PURE_QUANTA.BC847BPN(CHIPS)':
 'B2': CDS_PINID='B2';
NET_NAME
'H_CPU_CATERR_LVC1_R_N'
 '@S9S_MB_2U_LIB.S9S_MB_2U(SCH_1):H_CPU_CATERR_LVC1_R_N':
 C_SIGNAL='@s9s_mb_2u_lib.s9s_mb_2u(sch_1):h_cpu_caterr_lvc1_r_n';
NODE_NAME     R297 2
 '@S9S_MB_2U_LIB.S9S_MB_2U(SCH_1):PAGE118_I23@PURE_QUANTA.Q_RES(CHIPS)':
 'B': CDS_PINID='B';
NODE_NAME     R299 2
 '@S9S_MB_2U_LIB.S9S_MB_2U(SCH_1):PAGE118_I63@PURE_QUANTA.Q_RES(CHIPS)':
 'B': CDS_PINID='B';
NODE_NAME     R296 2
 '@S9S_MB_2U_LIB.S9S_MB_2U(SCH_1):PAGE118_I65@PURE_QUANTA.Q_RES(CHIPS)':
 'B': CDS_PINID='B';
NODE_NAME     R298 2
 '@S9S_MB_2U_LIB.S9S_MB_2U(SCH_1):PAGE118_I67@PURE_QUANTA.Q_RES(CHIPS)':
 'B': CDS_PINID='B';
NODE_NAME     U301 2
 '@S9S_MB_2U_LIB.S9S_MB_2U(SCH_1):PAGE321_I91@PURE_QUANTA.GTL2014PW(CHIPS)':
 'B0': CDS_PINID='B0';
NODE_NAME     U301 3
 '@S9S_MB_2U_LIB.S9S_MB_2U(SCH_1):PAGE321_I91@PURE_QUANTA.GTL2014PW(CHIPS)':
 'B1': CDS_PINID='B1';
NET_NAME
'H_CPU_CATERR_LVC2_BMC_N'
 '@S9S_MB_2U_LIB.S9S_MB_2U(SCH_1):H_CPU_CATERR_LVC2_BMC_N':
 C_SIGNAL='@s9s_mb_2u_lib.s9s_mb_2u(sch_1):h_cpu_caterr_lvc2_bmc_n';
NODE_NAME     R4621 2
 '@S9S_MB_2U_LIB.S9S_MB_2U(SCH_1):PAGE321_I101@PURE_QUANTA.Q_RES(CHIPS)':
 'B': CDS_PINID='B';
NODE_NAME     J41 OB13
 '@S9S_MB_2U_LIB.S9S_MB_2U(SCH_1):PAGE227_I173@PURE_QUANTA.SCONN168_ME1016810202011(CHIPS)':
 'GND_OB13': CDS_PINID='GND_OB13';
NET_NAME
'H_CPU_CATERR_LVC2_BMC_R_N'
 '@S9S_MB_2U_LIB.S9S_MB_2U(SCH_1):H_CPU_CATERR_LVC2_BMC_R_N':
 C_SIGNAL='@s9s_mb_2u_lib.s9s_mb_2u(sch_1):h_cpu_caterr_lvc2_bmc_r_n';
NODE_NAME     U301 13
 '@S9S_MB_2U_LIB.S9S_MB_2U(SCH_1):PAGE321_I91@PURE_QUANTA.GTL2014PW(CHIPS)':
 'A0': CDS_PINID='A0';
NODE_NAME     R4621 1
 '@S9S_MB_2U_LIB.S9S_MB_2U(SCH_1):PAGE321_I101@PURE_QUANTA.Q_RES(CHIPS)':
 'A': CDS_PINID='A';
NET_NAME
'H_CPU_CATERR_LVC2_R1_N'
 '@S9S_MB_2U_LIB.S9S_MB_2U(SCH_1):H_CPU_CATERR_LVC2_R1_N':
 C_SIGNAL='@s9s_mb_2u_lib.s9s_mb_2u(sch_1):h_cpu_caterr_lvc2_r1_n';
NODE_NAME     R4023 1
 '@S9S_MB_2U_LIB.S9S_MB_2U(SCH_1):PAGE321_I80@PURE_QUANTA.Q_RES(CHIPS)':
 'A': CDS_PINID='A';
NODE_NAME     U301 12
 '@S9S_MB_2U_LIB.S9S_MB_2U(SCH_1):PAGE321_I91@PURE_QUANTA.GTL2014PW(CHIPS)':
 'A1': CDS_PINID='A1';
NET_NAME
'H_CPU_CATERR_LVC2_R2_N'
 '@S9S_MB_2U_LIB.S9S_MB_2U(SCH_1):H_CPU_CATERR_LVC2_R2_N':
 C_SIGNAL='@s9s_mb_2u_lib.s9s_mb_2u(sch_1):h_cpu_caterr_lvc2_r2_n';
NODE_NAME     U249 Y2
 '@S9S_MB_2U_LIB.S9S_MB_2U(SCH_1):PAGE311_I33@PURE_QUANTA.LCMXO3LF9400C5BG484C(CHIPS)':
 'PL29D': CDS_PINID='PL29D';
NODE_NAME     R4023 2
 '@S9S_MB_2U_LIB.S9S_MB_2U(SCH_1):PAGE321_I80@PURE_QUANTA.Q_RES(CHIPS)':
 'B': CDS_PINID='B';
NET_NAME
'H_CPU_ERR0_LVC1_N'
 '@S9S_MB_2U_LIB.S9S_MB_2U(SCH_1):H_CPU_ERR0_LVC1_N':
 C_SIGNAL='@s9s_mb_2u_lib.s9s_mb_2u(sch_1):h_cpu_err0_lvc1_n';
NODE_NAME     U306 6
 '@S9S_MB_2U_LIB.S9S_MB_2U(SCH_1):PAGE322_I80@PURE_QUANTA.GTL2014PW(CHIPS)':
 'B3': CDS_PINID='B3';
NODE_NAME     R338 2
 '@S9S_MB_2U_LIB.S9S_MB_2U(SCH_1):PAGE322_I173@PURE_QUANTA.Q_RES(CHIPS)':
 'B': CDS_PINID='B';
NET_NAME
'H_CPU_ERR0_LVC1_R_N'
 '@S9S_MB_2U_LIB.S9S_MB_2U(SCH_1):H_CPU_ERR0_LVC1_R_N':
 C_SIGNAL='@s9s_mb_2u_lib.s9s_mb_2u(sch_1):h_cpu_err0_lvc1_r_n';
NODE_NAME     R336 2
 '@S9S_MB_2U_LIB.S9S_MB_2U(SCH_1):PAGE322_I159@PURE_QUANTA.Q_RES(CHIPS)':
 'B': CDS_PINID='B';
NODE_NAME     R337 2
 '@S9S_MB_2U_LIB.S9S_MB_2U(SCH_1):PAGE322_I160@PURE_QUANTA.Q_RES(CHIPS)':
 'B': CDS_PINID='B';
NODE_NAME     R4390 2
 '@S9S_MB_2U_LIB.S9S_MB_2U(SCH_1):PAGE322_I169@PURE_QUANTA.Q_RES(CHIPS)':
 'B': CDS_PINID='B';
NODE_NAME     R338 1
 '@S9S_MB_2U_LIB.S9S_MB_2U(SCH_1):PAGE322_I173@PURE_QUANTA.Q_RES(CHIPS)':
 'A': CDS_PINID='A';
NET_NAME
'H_CPU_ERR0_LVC2_N'
 '@S9S_MB_2U_LIB.S9S_MB_2U(SCH_1):H_CPU_ERR0_LVC2_N':
 C_SIGNAL='@s9s_mb_2u_lib.s9s_mb_2u(sch_1):h_cpu_err0_lvc2_n';
NODE_NAME     U249 T6
 '@S9S_MB_2U_LIB.S9S_MB_2U(SCH_1):PAGE311_I33@PURE_QUANTA.LCMXO3LF9400C5BG484C(CHIPS)':
 'PL26D': CDS_PINID='PL26D';
NODE_NAME     R4050 2
 '@S9S_MB_2U_LIB.S9S_MB_2U(SCH_1):PAGE322_I184@PURE_QUANTA.Q_RES(CHIPS)':
 'B': CDS_PINID='B';
NET_NAME
'H_CPU_ERR0_LVC2_R_N'
 '@S9S_MB_2U_LIB.S9S_MB_2U(SCH_1):H_CPU_ERR0_LVC2_R_N':
 C_SIGNAL='@s9s_mb_2u_lib.s9s_mb_2u(sch_1):h_cpu_err0_lvc2_r_n';
NODE_NAME     U306 9
 '@S9S_MB_2U_LIB.S9S_MB_2U(SCH_1):PAGE322_I80@PURE_QUANTA.GTL2014PW(CHIPS)':
 'A3': CDS_PINID='A3';
NODE_NAME     R4392 1
 '@S9S_MB_2U_LIB.S9S_MB_2U(SCH_1):PAGE322_I183@PURE_QUANTA.Q_RES(CHIPS)':
 'A': CDS_PINID='A';
NODE_NAME     R4050 1
 '@S9S_MB_2U_LIB.S9S_MB_2U(SCH_1):PAGE322_I184@PURE_QUANTA.Q_RES(CHIPS)':
 'A': CDS_PINID='A';
NET_NAME
'H_CPU_ERR0_PCH_R_N'
 '@S9S_MB_2U_LIB.S9S_MB_2U(SCH_1):H_CPU_ERR0_PCH_R_N':
 C_SIGNAL='@s9s_mb_2u_lib.s9s_mb_2u(sch_1):h_cpu_err0_pch_r_n';
NODE_NAME     U4 J7
 '@S9S_MB_2U_LIB.S9S_MB_2U(SCH_1):PAGE174_I36@PURE_QUANTA.EMMITSBURG_REV0P9(CHIPS)':
 'CPU_ERR0_N': CDS_PINID='CPU_ERR0_N';
NODE_NAME     R1260 2
 '@S9S_MB_2U_LIB.S9S_MB_2U(SCH_1):PAGE192_I17@PURE_QUANTA.Q_RES(CHIPS)':
 'B': CDS_PINID='B';
NODE_NAME     R4392 2
 '@S9S_MB_2U_LIB.S9S_MB_2U(SCH_1):PAGE322_I183@PURE_QUANTA.Q_RES(CHIPS)':
 'B': CDS_PINID='B';
NET_NAME
'H_CPU_ERR1_LVC1_N'
 '@S9S_MB_2U_LIB.S9S_MB_2U(SCH_1):H_CPU_ERR1_LVC1_N':
 C_SIGNAL='@s9s_mb_2u_lib.s9s_mb_2u(sch_1):h_cpu_err1_lvc1_n';
NODE_NAME     U306 5
 '@S9S_MB_2U_LIB.S9S_MB_2U(SCH_1):PAGE322_I80@PURE_QUANTA.GTL2014PW(CHIPS)':
 'B2': CDS_PINID='B2';
NODE_NAME     R342 2
 '@S9S_MB_2U_LIB.S9S_MB_2U(SCH_1):PAGE322_I172@PURE_QUANTA.Q_RES(CHIPS)':
 'B': CDS_PINID='B';
NET_NAME
'H_CPU_ERR1_LVC1_R_N'
 '@S9S_MB_2U_LIB.S9S_MB_2U(SCH_1):H_CPU_ERR1_LVC1_R_N':
 C_SIGNAL='@s9s_mb_2u_lib.s9s_mb_2u(sch_1):h_cpu_err1_lvc1_r_n';
NODE_NAME     R341 2
 '@S9S_MB_2U_LIB.S9S_MB_2U(SCH_1):PAGE322_I163@PURE_QUANTA.Q_RES(CHIPS)':
 'B': CDS_PINID='B';
NODE_NAME     R340 2
 '@S9S_MB_2U_LIB.S9S_MB_2U(SCH_1):PAGE322_I164@PURE_QUANTA.Q_RES(CHIPS)':
 'B': CDS_PINID='B';
NODE_NAME     R342 1
 '@S9S_MB_2U_LIB.S9S_MB_2U(SCH_1):PAGE322_I172@PURE_QUANTA.Q_RES(CHIPS)':
 'A': CDS_PINID='A';
NODE_NAME     R4388 2
 '@S9S_MB_2U_LIB.S9S_MB_2U(SCH_1):PAGE322_I174@PURE_QUANTA.Q_RES(CHIPS)':
 'B': CDS_PINID='B';
NET_NAME
'H_CPU_ERR1_LVC2_N'
 '@S9S_MB_2U_LIB.S9S_MB_2U(SCH_1):H_CPU_ERR1_LVC2_N':
 C_SIGNAL='@s9s_mb_2u_lib.s9s_mb_2u(sch_1):h_cpu_err1_lvc2_n';
NODE_NAME     U249 T5
 '@S9S_MB_2U_LIB.S9S_MB_2U(SCH_1):PAGE311_I33@PURE_QUANTA.LCMXO3LF9400C5BG484C(CHIPS)':
 'PL26C': CDS_PINID='PL26C';
NODE_NAME     R4051 2
 '@S9S_MB_2U_LIB.S9S_MB_2U(SCH_1):PAGE322_I94@PURE_QUANTA.Q_RES(CHIPS)':
 'B': CDS_PINID='B';
NET_NAME
'H_CPU_ERR1_LVC2_R_N'
 '@S9S_MB_2U_LIB.S9S_MB_2U(SCH_1):H_CPU_ERR1_LVC2_R_N':
 C_SIGNAL='@s9s_mb_2u_lib.s9s_mb_2u(sch_1):h_cpu_err1_lvc2_r_n';
NODE_NAME     U306 10
 '@S9S_MB_2U_LIB.S9S_MB_2U(SCH_1):PAGE322_I80@PURE_QUANTA.GTL2014PW(CHIPS)':
 'A2': CDS_PINID='A2';
NODE_NAME     R4051 1
 '@S9S_MB_2U_LIB.S9S_MB_2U(SCH_1):PAGE322_I94@PURE_QUANTA.Q_RES(CHIPS)':
 'A': CDS_PINID='A';
NODE_NAME     R4393 1
 '@S9S_MB_2U_LIB.S9S_MB_2U(SCH_1):PAGE322_I188@PURE_QUANTA.Q_RES(CHIPS)':
 'A': CDS_PINID='A';
NET_NAME
'H_CPU_ERR1_PCH_R_N'
 '@S9S_MB_2U_LIB.S9S_MB_2U(SCH_1):H_CPU_ERR1_PCH_R_N':
 C_SIGNAL='@s9s_mb_2u_lib.s9s_mb_2u(sch_1):h_cpu_err1_pch_r_n';
NODE_NAME     U4 G7
 '@S9S_MB_2U_LIB.S9S_MB_2U(SCH_1):PAGE174_I36@PURE_QUANTA.EMMITSBURG_REV0P9(CHIPS)':
 'CPU_ERR1_N': CDS_PINID='CPU_ERR1_N';
NODE_NAME     R3042 2
 '@S9S_MB_2U_LIB.S9S_MB_2U(SCH_1):PAGE192_I18@PURE_QUANTA.Q_RES(CHIPS)':
 'B': CDS_PINID='B';
NODE_NAME     R4393 2
 '@S9S_MB_2U_LIB.S9S_MB_2U(SCH_1):PAGE322_I188@PURE_QUANTA.Q_RES(CHIPS)':
 'B': CDS_PINID='B';
NET_NAME
'H_CPU_ERR2_LVC1_N'
 '@S9S_MB_2U_LIB.S9S_MB_2U(SCH_1):H_CPU_ERR2_LVC1_N':
 C_SIGNAL='@s9s_mb_2u_lib.s9s_mb_2u(sch_1):h_cpu_err2_lvc1_n';
NODE_NAME     U306 3
 '@S9S_MB_2U_LIB.S9S_MB_2U(SCH_1):PAGE322_I80@PURE_QUANTA.GTL2014PW(CHIPS)':
 'B1': CDS_PINID='B1';
NODE_NAME     R346 2
 '@S9S_MB_2U_LIB.S9S_MB_2U(SCH_1):PAGE322_I171@PURE_QUANTA.Q_RES(CHIPS)':
 'B': CDS_PINID='B';
NET_NAME
'H_CPU_ERR2_LVC1_R_N'
 '@S9S_MB_2U_LIB.S9S_MB_2U(SCH_1):H_CPU_ERR2_LVC1_R_N':
 C_SIGNAL='@s9s_mb_2u_lib.s9s_mb_2u(sch_1):h_cpu_err2_lvc1_r_n';
NODE_NAME     R344 2
 '@S9S_MB_2U_LIB.S9S_MB_2U(SCH_1):PAGE322_I157@PURE_QUANTA.Q_RES(CHIPS)':
 'B': CDS_PINID='B';
NODE_NAME     R345 2
 '@S9S_MB_2U_LIB.S9S_MB_2U(SCH_1):PAGE322_I158@PURE_QUANTA.Q_RES(CHIPS)':
 'B': CDS_PINID='B';
NODE_NAME     R346 1
 '@S9S_MB_2U_LIB.S9S_MB_2U(SCH_1):PAGE322_I171@PURE_QUANTA.Q_RES(CHIPS)':
 'A': CDS_PINID='A';
NODE_NAME     R4389 2
 '@S9S_MB_2U_LIB.S9S_MB_2U(SCH_1):PAGE322_I177@PURE_QUANTA.Q_RES(CHIPS)':
 'B': CDS_PINID='B';
NET_NAME
'H_CPU_ERR2_LVC2_N'
 '@S9S_MB_2U_LIB.S9S_MB_2U(SCH_1):H_CPU_ERR2_LVC2_N':
 C_SIGNAL='@s9s_mb_2u_lib.s9s_mb_2u(sch_1):h_cpu_err2_lvc2_n';
NODE_NAME     U249 T4
 '@S9S_MB_2U_LIB.S9S_MB_2U(SCH_1):PAGE311_I33@PURE_QUANTA.LCMXO3LF9400C5BG484C(CHIPS)':
 'PL26B': CDS_PINID='PL26B';
NODE_NAME     R4052 2
 '@S9S_MB_2U_LIB.S9S_MB_2U(SCH_1):PAGE322_I187@PURE_QUANTA.Q_RES(CHIPS)':
 'B': CDS_PINID='B';
NET_NAME
'H_CPU_ERR2_LVC2_R_N'
 '@S9S_MB_2U_LIB.S9S_MB_2U(SCH_1):H_CPU_ERR2_LVC2_R_N':
 C_SIGNAL='@s9s_mb_2u_lib.s9s_mb_2u(sch_1):h_cpu_err2_lvc2_r_n';
NODE_NAME     U306 12
 '@S9S_MB_2U_LIB.S9S_MB_2U(SCH_1):PAGE322_I80@PURE_QUANTA.GTL2014PW(CHIPS)':
 'A1': CDS_PINID='A1';
NODE_NAME     R4052 1
 '@S9S_MB_2U_LIB.S9S_MB_2U(SCH_1):PAGE322_I187@PURE_QUANTA.Q_RES(CHIPS)':
 'A': CDS_PINID='A';
NODE_NAME     R4394 1
 '@S9S_MB_2U_LIB.S9S_MB_2U(SCH_1):PAGE322_I189@PURE_QUANTA.Q_RES(CHIPS)':
 'A': CDS_PINID='A';
NET_NAME
'H_CPU_ERR2_PCH_R_N'
 '@S9S_MB_2U_LIB.S9S_MB_2U(SCH_1):H_CPU_ERR2_PCH_R_N':
 C_SIGNAL='@s9s_mb_2u_lib.s9s_mb_2u(sch_1):h_cpu_err2_pch_r_n';
NODE_NAME     U4 L7
 '@S9S_MB_2U_LIB.S9S_MB_2U(SCH_1):PAGE174_I36@PURE_QUANTA.EMMITSBURG_REV0P9(CHIPS)':
 'CPU_ERR2_N': CDS_PINID='CPU_ERR2_N';
NODE_NAME     R1262 2
 '@S9S_MB_2U_LIB.S9S_MB_2U(SCH_1):PAGE192_I11@PURE_QUANTA.Q_RES(CHIPS)':
 'B': CDS_PINID='B';
NODE_NAME     R4394 2
 '@S9S_MB_2U_LIB.S9S_MB_2U(SCH_1):PAGE322_I189@PURE_QUANTA.Q_RES(CHIPS)':
 'B': CDS_PINID='B';
NET_NAME
'H_CPU_NMI_LVC1_N'
 '@S9S_MB_2U_LIB.S9S_MB_2U(SCH_1):H_CPU_NMI_LVC1_N':
 C_SIGNAL='@s9s_mb_2u_lib.s9s_mb_2u(sch_1):h_cpu_nmi_lvc1_n';
NODE_NAME     R188 2
 '@S9S_MB_2U_LIB.S9S_MB_2U(SCH_1):PAGE123_I4@PURE_QUANTA.Q_RES(CHIPS)':
 'B': CDS_PINID='B';
NODE_NAME     R196 1
 '@S9S_MB_2U_LIB.S9S_MB_2U(SCH_1):PAGE123_I5@PURE_QUANTA.Q_RES(CHIPS)':
 'A': CDS_PINID='A';
NODE_NAME     R195 1
 '@S9S_MB_2U_LIB.S9S_MB_2U(SCH_1):PAGE123_I6@PURE_QUANTA.Q_RES(CHIPS)':
 'A': CDS_PINID='A';
NET_NAME
'H_CPU_NMI_LVC1_R_N'
 '@S9S_MB_2U_LIB.S9S_MB_2U(SCH_1):H_CPU_NMI_LVC1_R_N':
 C_SIGNAL='@s9s_mb_2u_lib.s9s_mb_2u(sch_1):h_cpu_nmi_lvc1_r_n';
NODE_NAME     U249 AA1
 '@S9S_MB_2U_LIB.S9S_MB_2U(SCH_1):PAGE311_I33@PURE_QUANTA.LCMXO3LF9400C5BG484C(CHIPS)':
 'PL29B': CDS_PINID='PL29B';
NODE_NAME     R188 1
 '@S9S_MB_2U_LIB.S9S_MB_2U(SCH_1):PAGE123_I4@PURE_QUANTA.Q_RES(CHIPS)':
 'A': CDS_PINID='A';
NET_NAME
'H_CPU_PM_FAST_WAKE_N'
 '@S9S_MB_2U_LIB.S9S_MB_2U(SCH_1):H_CPU_PM_FAST_WAKE_N':
 C_SIGNAL='@s9s_mb_2u_lib.s9s_mb_2u(sch_1):h_cpu_pm_fast_wake_n';
NODE_NAME     R1240 2
 '@S9S_MB_2U_LIB.S9S_MB_2U(SCH_1):PAGE117_I9@PURE_QUANTA.Q_RES(CHIPS)':
 'B': CDS_PINID='B';
NODE_NAME     R3023 1
 '@S9S_MB_2U_LIB.S9S_MB_2U(SCH_1):PAGE117_I10@PURE_QUANTA.Q_RES(CHIPS)':
 'A': CDS_PINID='A';
NODE_NAME     R1242 2
 '@S9S_MB_2U_LIB.S9S_MB_2U(SCH_1):PAGE117_I13@PURE_QUANTA.Q_RES(CHIPS)':
 'B': CDS_PINID='B';
NODE_NAME     R1244 2
 '@S9S_MB_2U_LIB.S9S_MB_2U(SCH_1):PAGE117_I16@PURE_QUANTA.Q_RES(CHIPS)':
 'B': CDS_PINID='B';
NET_NAME
'H_CPU_PRDY_QS_GTL_N'
 '@S9S_MB_2U_LIB.S9S_MB_2U(SCH_1):H_CPU_PRDY_QS_GTL_N':
 C_SIGNAL='@s9s_mb_2u_lib.s9s_mb_2u(sch_1):h_cpu_prdy_qs_gtl_n';
NODE_NAME     R1 1
 '@S9S_MB_2U_LIB.S9S_MB_2U(SCH_1):PAGE13_I18@PURE_QUANTA.Q_RES(CHIPS)':
 'A': CDS_PINID='A';
NODE_NAME     R61 1
 '@S9S_MB_2U_LIB.S9S_MB_2U(SCH_1):PAGE44_I16@PURE_QUANTA.Q_RES(CHIPS)':
 'A': CDS_PINID='A';
NODE_NAME     U18 8
 '@S9S_MB_2U_LIB.S9S_MB_2U(SCH_1):PAGE134_I129@PURE_QUANTA.74CBTLV3126PW(CHIPS)':
 '3B': CDS_PINID='\3b\';
NODE_NAME     R759 2
 '@S9S_MB_2U_LIB.S9S_MB_2U(SCH_1):PAGE134_I169@PURE_QUANTA.Q_RES(CHIPS)':
 'B': CDS_PINID='B';
NET_NAME
'H_CPU_PREQ_QS_GTL_N'
 '@S9S_MB_2U_LIB.S9S_MB_2U(SCH_1):H_CPU_PREQ_QS_GTL_N':
 C_SIGNAL='@s9s_mb_2u_lib.s9s_mb_2u(sch_1):h_cpu_preq_qs_gtl_n';
NODE_NAME     R2 1
 '@S9S_MB_2U_LIB.S9S_MB_2U(SCH_1):PAGE13_I16@PURE_QUANTA.Q_RES(CHIPS)':
 'A': CDS_PINID='A';
NODE_NAME     R62 1
 '@S9S_MB_2U_LIB.S9S_MB_2U(SCH_1):PAGE44_I11@PURE_QUANTA.Q_RES(CHIPS)':
 'A': CDS_PINID='A';
NODE_NAME     U18 11
 '@S9S_MB_2U_LIB.S9S_MB_2U(SCH_1):PAGE134_I129@PURE_QUANTA.74CBTLV3126PW(CHIPS)':
 '4B': CDS_PINID='\4b\';
NODE_NAME     R758 2
 '@S9S_MB_2U_LIB.S9S_MB_2U(SCH_1):PAGE134_I168@PURE_QUANTA.Q_RES(CHIPS)':
 'B': CDS_PINID='B';
NET_NAME
'H_CPU_RMCA_LVC1_R_N'
 '@S9S_MB_2U_LIB.S9S_MB_2U(SCH_1):H_CPU_RMCA_LVC1_R_N':
 C_SIGNAL='@s9s_mb_2u_lib.s9s_mb_2u(sch_1):h_cpu_rmca_lvc1_r_n';
NODE_NAME     R301 2
 '@S9S_MB_2U_LIB.S9S_MB_2U(SCH_1):PAGE118_I73@PURE_QUANTA.Q_RES(CHIPS)':
 'B': CDS_PINID='B';
NODE_NAME     R303 2
 '@S9S_MB_2U_LIB.S9S_MB_2U(SCH_1):PAGE118_I76@PURE_QUANTA.Q_RES(CHIPS)':
 'B': CDS_PINID='B';
NODE_NAME     U301 5
 '@S9S_MB_2U_LIB.S9S_MB_2U(SCH_1):PAGE321_I91@PURE_QUANTA.GTL2014PW(CHIPS)':
 'B2': CDS_PINID='B2';
NODE_NAME     R302 2
 '@S9S_MB_2U_LIB.S9S_MB_2U(SCH_1):PAGE118_I101@PURE_QUANTA.Q_RES(CHIPS)':
 'B': CDS_PINID='B';
NODE_NAME     R304 2
 '@S9S_MB_2U_LIB.S9S_MB_2U(SCH_1):PAGE118_I102@PURE_QUANTA.Q_RES(CHIPS)':
 'B': CDS_PINID='B';
NET_NAME
'H_CPU_RMCA_LVC2_R1_N'
 '@S9S_MB_2U_LIB.S9S_MB_2U(SCH_1):H_CPU_RMCA_LVC2_R1_N':
 C_SIGNAL='@s9s_mb_2u_lib.s9s_mb_2u(sch_1):h_cpu_rmca_lvc2_r1_n';
NODE_NAME     R4022 1
 '@S9S_MB_2U_LIB.S9S_MB_2U(SCH_1):PAGE321_I79@PURE_QUANTA.Q_RES(CHIPS)':
 'A': CDS_PINID='A';
NODE_NAME     U301 10
 '@S9S_MB_2U_LIB.S9S_MB_2U(SCH_1):PAGE321_I91@PURE_QUANTA.GTL2014PW(CHIPS)':
 'A2': CDS_PINID='A2';
NET_NAME
'H_CPU_RMCA_LVC2_R2_N'
 '@S9S_MB_2U_LIB.S9S_MB_2U(SCH_1):H_CPU_RMCA_LVC2_R2_N':
 C_SIGNAL='@s9s_mb_2u_lib.s9s_mb_2u(sch_1):h_cpu_rmca_lvc2_r2_n';
NODE_NAME     U249 Y1
 '@S9S_MB_2U_LIB.S9S_MB_2U(SCH_1):PAGE311_I33@PURE_QUANTA.LCMXO3LF9400C5BG484C(CHIPS)':
 'PL29A': CDS_PINID='PL29A';
NODE_NAME     R4022 2
 '@S9S_MB_2U_LIB.S9S_MB_2U(SCH_1):PAGE321_I79@PURE_QUANTA.Q_RES(CHIPS)':
 'B': CDS_PINID='B';
NET_NAME
'H_DBP_PRDY_N_PCH'
 '@S9S_MB_2U_LIB.S9S_MB_2U(SCH_1):H_DBP_PRDY_N_PCH':
 C_SIGNAL='@s9s_mb_2u_lib.s9s_mb_2u(sch_1):h_dbp_prdy_n_pch';
NODE_NAME     R756 2
 '@S9S_MB_2U_LIB.S9S_MB_2U(SCH_1):PAGE134_I148@PURE_QUANTA.Q_RES(CHIPS)':
 'B': CDS_PINID='B';
NODE_NAME     R751 2
 '@S9S_MB_2U_LIB.S9S_MB_2U(SCH_1):PAGE134_I177@PURE_QUANTA.Q_RES(CHIPS)':
 'B': CDS_PINID='B';
NODE_NAME     U4 BB37
 '@S9S_MB_2U_LIB.S9S_MB_2U(SCH_1):PAGE174_I36@PURE_QUANTA.EMMITSBURG_REV0P9(CHIPS)':
 'PRDY_N': CDS_PINID='PRDY_N';
NET_NAME
'H_DBP_PREQ_N_PCH'
 '@S9S_MB_2U_LIB.S9S_MB_2U(SCH_1):H_DBP_PREQ_N_PCH':
 C_SIGNAL='@s9s_mb_2u_lib.s9s_mb_2u(sch_1):h_dbp_preq_n_pch';
NODE_NAME     R755 2
 '@S9S_MB_2U_LIB.S9S_MB_2U(SCH_1):PAGE134_I147@PURE_QUANTA.Q_RES(CHIPS)':
 'B': CDS_PINID='B';
NODE_NAME     R750 2
 '@S9S_MB_2U_LIB.S9S_MB_2U(SCH_1):PAGE134_I178@PURE_QUANTA.Q_RES(CHIPS)':
 'B': CDS_PINID='B';
NODE_NAME     U4 BF37
 '@S9S_MB_2U_LIB.S9S_MB_2U(SCH_1):PAGE174_I36@PURE_QUANTA.EMMITSBURG_REV0P9(CHIPS)':
 'PREQ_N': CDS_PINID='PREQ_N';
NET_NAME
'H_PMAX_TRIGGER_IO_CPU0'
 '@S9S_MB_2U_LIB.S9S_MB_2U(SCH_1):H_PMAX_TRIGGER_IO_CPU0':
 C_SIGNAL='@s9s_mb_2u_lib.s9s_mb_2u(sch_1):h_pmax_trigger_io_cpu0';
NODE_NAME     U2 BD24
 '@S9S_MB_2U_LIB.S9S_MB_2U(SCH_1):PAGE16_I1@PURE_QUANTA.SOCKET4677_AZIF0045P001C01CS(CHIPS)':
 'PMAX_TRIGGER_IO': CDS_PINID='PMAX_TRIGGER_IO';
NODE_NAME     R1241 1
 '@S9S_MB_2U_LIB.S9S_MB_2U(SCH_1):PAGE117_I17@PURE_QUANTA.Q_RES(CHIPS)':
 'A': CDS_PINID='A';
NET_NAME
'H_PMAX_TRIGGER_IO_CPU1'
 '@S9S_MB_2U_LIB.S9S_MB_2U(SCH_1):H_PMAX_TRIGGER_IO_CPU1':
 C_SIGNAL='@s9s_mb_2u_lib.s9s_mb_2u(sch_1):h_pmax_trigger_io_cpu1';
NODE_NAME     U1 BD24
 '@S9S_MB_2U_LIB.S9S_MB_2U(SCH_1):PAGE47_I16@PURE_QUANTA.SOCKET4677_AZIF0045P001C01CS(CHIPS)':
 'PMAX_TRIGGER_IO': CDS_PINID='PMAX_TRIGGER_IO';
NODE_NAME     R1243 1
 '@S9S_MB_2U_LIB.S9S_MB_2U(SCH_1):PAGE117_I19@PURE_QUANTA.Q_RES(CHIPS)':
 'A': CDS_PINID='A';
NET_NAME
'H_THERMTRIP_LVC1_N'
 '@S9S_MB_2U_LIB.S9S_MB_2U(SCH_1):H_THERMTRIP_LVC1_N':
 C_SIGNAL='@s9s_mb_2u_lib.s9s_mb_2u(sch_1):h_thermtrip_lvc1_n';
NODE_NAME     U4 F3
 '@S9S_MB_2U_LIB.S9S_MB_2U(SCH_1):PAGE174_I36@PURE_QUANTA.EMMITSBURG_REV0P9(CHIPS)':
 'CPU_THRMTRIP_N': CDS_PINID='CPU_THRMTRIP_N';
NODE_NAME     R1249 2
 '@S9S_MB_2U_LIB.S9S_MB_2U(SCH_1):PAGE191_I2@PURE_QUANTA.Q_RES(CHIPS)':
 'B': CDS_PINID='B';
NODE_NAME     R1266 2
 '@S9S_MB_2U_LIB.S9S_MB_2U(SCH_1):PAGE191_I38@PURE_QUANTA.Q_RES(CHIPS)':
 'B': CDS_PINID='B';
NET_NAME
'I3C_BMC_SWB_BUF_R_SCL'
 '@S9S_MB_2U_LIB.S9S_MB_2U(SCH_1):I3C_BMC_SWB_BUF_R_SCL':
 C_SIGNAL='@s9s_mb_2u_lib.s9s_mb_2u(sch_1):i3c_bmc_swb_buf_r_scl';
NODE_NAME     R2675 1
 '@S9S_MB_2U_LIB.S9S_MB_2U(SCH_1):PAGE222_I72@PURE_QUANTA.Q_RES(CHIPS)':
 'A': CDS_PINID='A';
NODE_NAME     R2725 2
 '@S9S_MB_2U_LIB.S9S_MB_2U(SCH_1):PAGE222_I29@PURE_QUANTA.Q_RES(CHIPS)':
 'B': CDS_PINID='B';
NODE_NAME     U176 2
 '@S9S_MB_2U_LIB.S9S_MB_2U(SCH_1):PAGE222_I31@PURE_QUANTA.LTC4307CMS8(CHIPS)':
 'SCL_OUT': CDS_PINID='SCL_OUT';
NODE_NAME     R2670 2
 '@S9S_MB_2U_LIB.S9S_MB_2U(SCH_1):PAGE222_I77@PURE_QUANTA.Q_RES(CHIPS)':
 'B': CDS_PINID='B';
NET_NAME
'I3C_BMC_SWB_BUF_R_SDA'
 '@S9S_MB_2U_LIB.S9S_MB_2U(SCH_1):I3C_BMC_SWB_BUF_R_SDA':
 C_SIGNAL='@s9s_mb_2u_lib.s9s_mb_2u(sch_1):i3c_bmc_swb_buf_r_sda';
NODE_NAME     R2706 2
 '@S9S_MB_2U_LIB.S9S_MB_2U(SCH_1):PAGE222_I30@PURE_QUANTA.Q_RES(CHIPS)':
 'B': CDS_PINID='B';
NODE_NAME     U176 7
 '@S9S_MB_2U_LIB.S9S_MB_2U(SCH_1):PAGE222_I31@PURE_QUANTA.LTC4307CMS8(CHIPS)':
 'SDA_OUT': CDS_PINID='SDA_OUT';
NODE_NAME     R2674 1
 '@S9S_MB_2U_LIB.S9S_MB_2U(SCH_1):PAGE222_I71@PURE_QUANTA.Q_RES(CHIPS)':
 'A': CDS_PINID='A';
NODE_NAME     R2668 2
 '@S9S_MB_2U_LIB.S9S_MB_2U(SCH_1):PAGE222_I75@PURE_QUANTA.Q_RES(CHIPS)':
 'B': CDS_PINID='B';
NET_NAME
'I3C_BMC_SWB_BUF_SCL'
 '@S9S_MB_2U_LIB.S9S_MB_2U(SCH_1):I3C_BMC_SWB_BUF_SCL':
 C_SIGNAL='@s9s_mb_2u_lib.s9s_mb_2u(sch_1):i3c_bmc_swb_buf_scl';
NODE_NAME     J106 N4
 '@S9S_MB_2U_LIB.S9S_MB_2U(SCH_1):PAGE144_I65@PURE_QUANTA.CONN112_10137002101LF(CHIPS)':
 'N4': CDS_PINID='N4';
NODE_NAME     R2675 2
 '@S9S_MB_2U_LIB.S9S_MB_2U(SCH_1):PAGE222_I72@PURE_QUANTA.Q_RES(CHIPS)':
 'B': CDS_PINID='B';
NET_NAME
'I3C_BMC_SWB_BUF_SDA'
 '@S9S_MB_2U_LIB.S9S_MB_2U(SCH_1):I3C_BMC_SWB_BUF_SDA':
 C_SIGNAL='@s9s_mb_2u_lib.s9s_mb_2u(sch_1):i3c_bmc_swb_buf_sda';
NODE_NAME     J106 N2
 '@S9S_MB_2U_LIB.S9S_MB_2U(SCH_1):PAGE144_I65@PURE_QUANTA.CONN112_10137002101LF(CHIPS)':
 'N2': CDS_PINID='N2';
NODE_NAME     R2674 2
 '@S9S_MB_2U_LIB.S9S_MB_2U(SCH_1):PAGE222_I71@PURE_QUANTA.Q_RES(CHIPS)':
 'B': CDS_PINID='B';
NET_NAME
'I3C_BMC_SWB_R_SCL'
 '@S9S_MB_2U_LIB.S9S_MB_2U(SCH_1):I3C_BMC_SWB_R_SCL':
 C_SIGNAL='@s9s_mb_2u_lib.s9s_mb_2u(sch_1):i3c_bmc_swb_r_scl';
NODE_NAME     R3112 2
 '@S9S_MB_2U_LIB.S9S_MB_2U(SCH_1):PAGE222_I18@PURE_QUANTA.Q_RES(CHIPS)':
 'B': CDS_PINID='B';
NODE_NAME     R2725 1
 '@S9S_MB_2U_LIB.S9S_MB_2U(SCH_1):PAGE222_I29@PURE_QUANTA.Q_RES(CHIPS)':
 'A': CDS_PINID='A';
NODE_NAME     U176 3
 '@S9S_MB_2U_LIB.S9S_MB_2U(SCH_1):PAGE222_I31@PURE_QUANTA.LTC4307CMS8(CHIPS)':
 'SCL_IN': CDS_PINID='SCL_IN';
NET_NAME
'I3C_BMC_SWB_R_SDA'
 '@S9S_MB_2U_LIB.S9S_MB_2U(SCH_1):I3C_BMC_SWB_R_SDA':
 C_SIGNAL='@s9s_mb_2u_lib.s9s_mb_2u(sch_1):i3c_bmc_swb_r_sda';
NODE_NAME     R3111 2
 '@S9S_MB_2U_LIB.S9S_MB_2U(SCH_1):PAGE222_I17@PURE_QUANTA.Q_RES(CHIPS)':
 'B': CDS_PINID='B';
NODE_NAME     R2706 1
 '@S9S_MB_2U_LIB.S9S_MB_2U(SCH_1):PAGE222_I30@PURE_QUANTA.Q_RES(CHIPS)':
 'A': CDS_PINID='A';
NODE_NAME     U176 6
 '@S9S_MB_2U_LIB.S9S_MB_2U(SCH_1):PAGE222_I31@PURE_QUANTA.LTC4307CMS8(CHIPS)':
 'SDA_IN': CDS_PINID='SDA_IN';
NET_NAME
'I3C_BMC_SWB_SCL'
 '@S9S_MB_2U_LIB.S9S_MB_2U(SCH_1):I3C_BMC_SWB_SCL':
 C_SIGNAL='@s9s_mb_2u_lib.s9s_mb_2u(sch_1):i3c_bmc_swb_scl';
NODE_NAME     R1336 1
 '@S9S_MB_2U_LIB.S9S_MB_2U(SCH_1):PAGE228_I177@PURE_QUANTA.Q_RES(CHIPS)':
 'A': CDS_PINID='A';
NODE_NAME     R3112 1
 '@S9S_MB_2U_LIB.S9S_MB_2U(SCH_1):PAGE222_I18@PURE_QUANTA.Q_RES(CHIPS)':
 'A': CDS_PINID='A';
NODE_NAME     J41 A9
 '@S9S_MB_2U_LIB.S9S_MB_2U(SCH_1):PAGE227_I173@PURE_QUANTA.SCONN168_ME1016810202011(CHIPS)':
 'SMRST#': CDS_PINID='\smrst#\';
NET_NAME
'I3C_BMC_SWB_SDA'
 '@S9S_MB_2U_LIB.S9S_MB_2U(SCH_1):I3C_BMC_SWB_SDA':
 C_SIGNAL='@s9s_mb_2u_lib.s9s_mb_2u(sch_1):i3c_bmc_swb_sda';
NODE_NAME     R1460 1
 '@S9S_MB_2U_LIB.S9S_MB_2U(SCH_1):PAGE228_I176@PURE_QUANTA.Q_RES(CHIPS)':
 'A': CDS_PINID='A';
NODE_NAME     R3111 1
 '@S9S_MB_2U_LIB.S9S_MB_2U(SCH_1):PAGE222_I17@PURE_QUANTA.Q_RES(CHIPS)':
 'A': CDS_PINID='A';
NODE_NAME     J41 A10
 '@S9S_MB_2U_LIB.S9S_MB_2U(SCH_1):PAGE227_I173@PURE_QUANTA.SCONN168_ME1016810202011(CHIPS)':
 'PRSNTA#': CDS_PINID='\prsnta#\';
NET_NAME
'I3C_SPD_DDRABCD_CPU0_BMC_R_SCL'
 '@S9S_MB_2U_LIB.S9S_MB_2U(SCH_1):I3C_SPD_DDRABCD_CPU0_BMC_R_SCL':
 C_SIGNAL='@s9s_mb_2u_lib.s9s_mb_2u(sch_1):i3c_spd_ddrabcd_cpu0_bmc_r_scl';
NODE_NAME     R593 1
 '@S9S_MB_2U_LIB.S9S_MB_2U(SCH_1):PAGE228_I311@PURE_QUANTA.Q_RES(CHIPS)':
 'A': CDS_PINID='A';
NODE_NAME     J41 OA5
 '@S9S_MB_2U_LIB.S9S_MB_2U(SCH_1):PAGE227_I173@PURE_QUANTA.SCONN168_ME1016810202011(CHIPS)':
 'RBT_ARB_OUT': CDS_PINID='RBT_ARB_OUT';
NET_NAME
'I3C_SPD_DDRABCD_CPU0_BMC_R_SDA'
 '@S9S_MB_2U_LIB.S9S_MB_2U(SCH_1):I3C_SPD_DDRABCD_CPU0_BMC_R_SDA':
 C_SIGNAL='@s9s_mb_2u_lib.s9s_mb_2u(sch_1):i3c_spd_ddrabcd_cpu0_bmc_r_sda';
NODE_NAME     R594 1
 '@S9S_MB_2U_LIB.S9S_MB_2U(SCH_1):PAGE228_I312@PURE_QUANTA.Q_RES(CHIPS)':
 'A': CDS_PINID='A';
NODE_NAME     J41 OA6
 '@S9S_MB_2U_LIB.S9S_MB_2U(SCH_1):PAGE227_I173@PURE_QUANTA.SCONN168_ME1016810202011(CHIPS)':
 'SLOT_ID1': CDS_PINID='SLOT_ID1';
NET_NAME
'I3C_SPD_DDRABCD_CPU0_BMC_SCL'
 '@S9S_MB_2U_LIB.S9S_MB_2U(SCH_1):I3C_SPD_DDRABCD_CPU0_BMC_SCL':
 C_SIGNAL='@s9s_mb_2u_lib.s9s_mb_2u(sch_1):i3c_spd_ddrabcd_cpu0_bmc_scl';
NODE_NAME     R593 2
 '@S9S_MB_2U_LIB.S9S_MB_2U(SCH_1):PAGE228_I311@PURE_QUANTA.Q_RES(CHIPS)':
 'B': CDS_PINID='B';
NODE_NAME     U15 3
 '@S9S_MB_2U_LIB.S9S_MB_2U(SCH_1):PAGE217_I19@PURE_QUANTA.QS3VH257QG8(CHIPS)':
 'I1A': CDS_PINID='I1A';
NET_NAME
'I3C_SPD_DDRABCD_CPU0_BMC_SDA'
 '@S9S_MB_2U_LIB.S9S_MB_2U(SCH_1):I3C_SPD_DDRABCD_CPU0_BMC_SDA':
 C_SIGNAL='@s9s_mb_2u_lib.s9s_mb_2u(sch_1):i3c_spd_ddrabcd_cpu0_bmc_sda';
NODE_NAME     R594 2
 '@S9S_MB_2U_LIB.S9S_MB_2U(SCH_1):PAGE228_I312@PURE_QUANTA.Q_RES(CHIPS)':
 'B': CDS_PINID='B';
NODE_NAME     U15 6
 '@S9S_MB_2U_LIB.S9S_MB_2U(SCH_1):PAGE217_I19@PURE_QUANTA.QS3VH257QG8(CHIPS)':
 'I1B': CDS_PINID='I1B';
NET_NAME
'I3C_SPD_DDRABCD_CPU0_LVC1_R_SCL'
 '@S9S_MB_2U_LIB.S9S_MB_2U(SCH_1):I3C_SPD_DDRABCD_CPU0_LVC1_R_SCL':
 C_SIGNAL='@s9s_mb_2u_lib.s9s_mb_2u(sch_1):i3c_spd_ddrabcd_cpu0_lvc1_r_scl';
NODE_NAME     U15 4
 '@S9S_MB_2U_LIB.S9S_MB_2U(SCH_1):PAGE217_I19@PURE_QUANTA.QS3VH257QG8(CHIPS)':
 'YA': CDS_PINID='YA';
NODE_NAME     R682 2
 '@S9S_MB_2U_LIB.S9S_MB_2U(SCH_1):PAGE217_I20@PURE_QUANTA.Q_RES(CHIPS)':
 'B': CDS_PINID='B';
NODE_NAME     R691 1
 '@S9S_MB_2U_LIB.S9S_MB_2U(SCH_1):PAGE217_I39@PURE_QUANTA.Q_RES(CHIPS)':
 'A': CDS_PINID='A';
NET_NAME
'I3C_SPD_DDRABCD_CPU0_LVC1_R_SDA'
 '@S9S_MB_2U_LIB.S9S_MB_2U(SCH_1):I3C_SPD_DDRABCD_CPU0_LVC1_R_SDA':
 C_SIGNAL='@s9s_mb_2u_lib.s9s_mb_2u(sch_1):i3c_spd_ddrabcd_cpu0_lvc1_r_sda';
NODE_NAME     R683 2
 '@S9S_MB_2U_LIB.S9S_MB_2U(SCH_1):PAGE217_I18@PURE_QUANTA.Q_RES(CHIPS)':
 'B': CDS_PINID='B';
NODE_NAME     U15 7
 '@S9S_MB_2U_LIB.S9S_MB_2U(SCH_1):PAGE217_I19@PURE_QUANTA.QS3VH257QG8(CHIPS)':
 'YB': CDS_PINID='YB';
NODE_NAME     R692 1
 '@S9S_MB_2U_LIB.S9S_MB_2U(SCH_1):PAGE217_I40@PURE_QUANTA.Q_RES(CHIPS)':
 'A': CDS_PINID='A';
NET_NAME
'I3C_SPD_DDRABCD_CPU0_LVC1_SCL'
 '@S9S_MB_2U_LIB.S9S_MB_2U(SCH_1):I3C_SPD_DDRABCD_CPU0_LVC1_SCL':
 C_SIGNAL='@s9s_mb_2u_lib.s9s_mb_2u(sch_1):i3c_spd_ddrabcd_cpu0_lvc1_scl';
NODE_NAME     R3875 2
 '@S9S_MB_2U_LIB.S9S_MB_2U(SCH_1):PAGE82_I204@PURE_QUANTA.Q_RES(CHIPS)':
 'B': CDS_PINID='B';
NODE_NAME     R3876 2
 '@S9S_MB_2U_LIB.S9S_MB_2U(SCH_1):PAGE83_I182@PURE_QUANTA.Q_RES(CHIPS)':
 'B': CDS_PINID='B';
NODE_NAME     R3877 2
 '@S9S_MB_2U_LIB.S9S_MB_2U(SCH_1):PAGE84_I182@PURE_QUANTA.Q_RES(CHIPS)':
 'B': CDS_PINID='B';
NODE_NAME     R3878 2
 '@S9S_MB_2U_LIB.S9S_MB_2U(SCH_1):PAGE85_I180@PURE_QUANTA.Q_RES(CHIPS)':
 'B': CDS_PINID='B';
NODE_NAME     R3879 2
 '@S9S_MB_2U_LIB.S9S_MB_2U(SCH_1):PAGE86_I180@PURE_QUANTA.Q_RES(CHIPS)':
 'B': CDS_PINID='B';
NODE_NAME     R3880 2
 '@S9S_MB_2U_LIB.S9S_MB_2U(SCH_1):PAGE87_I180@PURE_QUANTA.Q_RES(CHIPS)':
 'B': CDS_PINID='B';
NODE_NAME     R3881 2
 '@S9S_MB_2U_LIB.S9S_MB_2U(SCH_1):PAGE88_I180@PURE_QUANTA.Q_RES(CHIPS)':
 'B': CDS_PINID='B';
NODE_NAME     R3882 2
 '@S9S_MB_2U_LIB.S9S_MB_2U(SCH_1):PAGE89_I180@PURE_QUANTA.Q_RES(CHIPS)':
 'B': CDS_PINID='B';
NODE_NAME     R691 2
 '@S9S_MB_2U_LIB.S9S_MB_2U(SCH_1):PAGE217_I39@PURE_QUANTA.Q_RES(CHIPS)':
 'B': CDS_PINID='B';
NET_NAME
'I3C_SPD_DDRABCD_CPU0_LVC1_SCL_1'
 '@S9S_MB_2U_LIB.S9S_MB_2U(SCH_1):I3C_SPD_DDRABCD_CPU0_LVC1_SCL_R2':
 C_SIGNAL='@s9s_mb_2u_lib.s9s_mb_2u(sch_1):i3c_spd_ddrabcd_cpu0_lvc1_scl_r2';
NODE_NAME     J2 4
 '@S9S_MB_2U_LIB.S9S_MB_2U(SCH_1):PAGE83_I177@PURE_QUANTA.SCONN288_ADR50017P087CC(CHIPS)':
 'HSCL': CDS_PINID='HSCL';
NODE_NAME     R3876 1
 '@S9S_MB_2U_LIB.S9S_MB_2U(SCH_1):PAGE83_I182@PURE_QUANTA.Q_RES(CHIPS)':
 'A': CDS_PINID='A';
NET_NAME
'I3C_SPD_DDRABCD_CPU0_LVC1_SCL_2'
 '@S9S_MB_2U_LIB.S9S_MB_2U(SCH_1):I3C_SPD_DDRABCD_CPU0_LVC1_SCL_R3':
 C_SIGNAL='@s9s_mb_2u_lib.s9s_mb_2u(sch_1):i3c_spd_ddrabcd_cpu0_lvc1_scl_r3';
NODE_NAME     J3 4
 '@S9S_MB_2U_LIB.S9S_MB_2U(SCH_1):PAGE84_I180@PURE_QUANTA.SCONN288_ADR50017P130CC(CHIPS)':
 'HSCL': CDS_PINID='HSCL';
NODE_NAME     R3877 1
 '@S9S_MB_2U_LIB.S9S_MB_2U(SCH_1):PAGE84_I182@PURE_QUANTA.Q_RES(CHIPS)':
 'A': CDS_PINID='A';
NET_NAME
'I3C_SPD_DDRABCD_CPU0_LVC1_SCL_3'
 '@S9S_MB_2U_LIB.S9S_MB_2U(SCH_1):I3C_SPD_DDRABCD_CPU0_LVC1_SCL_R4':
 C_SIGNAL='@s9s_mb_2u_lib.s9s_mb_2u(sch_1):i3c_spd_ddrabcd_cpu0_lvc1_scl_r4';
NODE_NAME     J4 4
 '@S9S_MB_2U_LIB.S9S_MB_2U(SCH_1):PAGE85_I23@PURE_QUANTA.SCONN288_ADR50017P087CC(CHIPS)':
 'HSCL': CDS_PINID='HSCL';
NODE_NAME     R3878 1
 '@S9S_MB_2U_LIB.S9S_MB_2U(SCH_1):PAGE85_I180@PURE_QUANTA.Q_RES(CHIPS)':
 'A': CDS_PINID='A';
NET_NAME
'I3C_SPD_DDRABCD_CPU0_LVC1_SCL_4'
 '@S9S_MB_2U_LIB.S9S_MB_2U(SCH_1):I3C_SPD_DDRABCD_CPU0_LVC1_SCL_R5':
 C_SIGNAL='@s9s_mb_2u_lib.s9s_mb_2u(sch_1):i3c_spd_ddrabcd_cpu0_lvc1_scl_r5';
NODE_NAME     J5 4
 '@S9S_MB_2U_LIB.S9S_MB_2U(SCH_1):PAGE86_I24@PURE_QUANTA.SCONN288_ADR50017P130CC(CHIPS)':
 'HSCL': CDS_PINID='HSCL';
NODE_NAME     R3879 1
 '@S9S_MB_2U_LIB.S9S_MB_2U(SCH_1):PAGE86_I180@PURE_QUANTA.Q_RES(CHIPS)':
 'A': CDS_PINID='A';
NET_NAME
'I3C_SPD_DDRABCD_CPU0_LVC1_SCL_5'
 '@S9S_MB_2U_LIB.S9S_MB_2U(SCH_1):I3C_SPD_DDRABCD_CPU0_LVC1_SCL_R6':
 C_SIGNAL='@s9s_mb_2u_lib.s9s_mb_2u(sch_1):i3c_spd_ddrabcd_cpu0_lvc1_scl_r6';
NODE_NAME     J6 4
 '@S9S_MB_2U_LIB.S9S_MB_2U(SCH_1):PAGE87_I46@PURE_QUANTA.SCONN288_ADR50017P087CC(CHIPS)':
 'HSCL': CDS_PINID='HSCL';
NODE_NAME     R3880 1
 '@S9S_MB_2U_LIB.S9S_MB_2U(SCH_1):PAGE87_I180@PURE_QUANTA.Q_RES(CHIPS)':
 'A': CDS_PINID='A';
NET_NAME
'I3C_SPD_DDRABCD_CPU0_LVC1_SCL_6'
 '@S9S_MB_2U_LIB.S9S_MB_2U(SCH_1):I3C_SPD_DDRABCD_CPU0_LVC1_SCL_R7':
 C_SIGNAL='@s9s_mb_2u_lib.s9s_mb_2u(sch_1):i3c_spd_ddrabcd_cpu0_lvc1_scl_r7';
NODE_NAME     J7 4
 '@S9S_MB_2U_LIB.S9S_MB_2U(SCH_1):PAGE88_I12@PURE_QUANTA.SCONN288_ADR50017P130CC(CHIPS)':
 'HSCL': CDS_PINID='HSCL';
NODE_NAME     R3881 1
 '@S9S_MB_2U_LIB.S9S_MB_2U(SCH_1):PAGE88_I180@PURE_QUANTA.Q_RES(CHIPS)':
 'A': CDS_PINID='A';
NET_NAME
'I3C_SPD_DDRABCD_CPU0_LVC1_SCL_7'
 '@S9S_MB_2U_LIB.S9S_MB_2U(SCH_1):I3C_SPD_DDRABCD_CPU0_LVC1_SCL_R8':
 C_SIGNAL='@s9s_mb_2u_lib.s9s_mb_2u(sch_1):i3c_spd_ddrabcd_cpu0_lvc1_scl_r8';
NODE_NAME     J8 4
 '@S9S_MB_2U_LIB.S9S_MB_2U(SCH_1):PAGE89_I50@PURE_QUANTA.SCONN288_ADR50017P087CC(CHIPS)':
 'HSCL': CDS_PINID='HSCL';
NODE_NAME     R3882 1
 '@S9S_MB_2U_LIB.S9S_MB_2U(SCH_1):PAGE89_I180@PURE_QUANTA.Q_RES(CHIPS)':
 'A': CDS_PINID='A';
NET_NAME
'I3C_SPD_DDRABCD_CPU0_LVC1_SCL_R'
 '@S9S_MB_2U_LIB.S9S_MB_2U(SCH_1):I3C_SPD_DDRABCD_CPU0_LVC1_SCL_R1':
 C_SIGNAL='@s9s_mb_2u_lib.s9s_mb_2u(sch_1):i3c_spd_ddrabcd_cpu0_lvc1_scl_r1';
NODE_NAME     J1 4
 '@S9S_MB_2U_LIB.S9S_MB_2U(SCH_1):PAGE82_I198@PURE_QUANTA.SCONN288_ADR50017P130CC(CHIPS)':
 'HSCL': CDS_PINID='HSCL';
NODE_NAME     R3875 1
 '@S9S_MB_2U_LIB.S9S_MB_2U(SCH_1):PAGE82_I204@PURE_QUANTA.Q_RES(CHIPS)':
 'A': CDS_PINID='A';
NET_NAME
'I3C_SPD_DDRABCD_CPU0_LVC1_SDA'
 '@S9S_MB_2U_LIB.S9S_MB_2U(SCH_1):I3C_SPD_DDRABCD_CPU0_LVC1_SDA':
 C_SIGNAL='@s9s_mb_2u_lib.s9s_mb_2u(sch_1):i3c_spd_ddrabcd_cpu0_lvc1_sda';
NODE_NAME     J1 5
 '@S9S_MB_2U_LIB.S9S_MB_2U(SCH_1):PAGE82_I198@PURE_QUANTA.SCONN288_ADR50017P130CC(CHIPS)':
 'HSDA': CDS_PINID='HSDA';
NODE_NAME     J2 5
 '@S9S_MB_2U_LIB.S9S_MB_2U(SCH_1):PAGE83_I177@PURE_QUANTA.SCONN288_ADR50017P087CC(CHIPS)':
 'HSDA': CDS_PINID='HSDA';
NODE_NAME     J4 5
 '@S9S_MB_2U_LIB.S9S_MB_2U(SCH_1):PAGE85_I23@PURE_QUANTA.SCONN288_ADR50017P087CC(CHIPS)':
 'HSDA': CDS_PINID='HSDA';
NODE_NAME     J5 5
 '@S9S_MB_2U_LIB.S9S_MB_2U(SCH_1):PAGE86_I24@PURE_QUANTA.SCONN288_ADR50017P130CC(CHIPS)':
 'HSDA': CDS_PINID='HSDA';
NODE_NAME     J6 5
 '@S9S_MB_2U_LIB.S9S_MB_2U(SCH_1):PAGE87_I46@PURE_QUANTA.SCONN288_ADR50017P087CC(CHIPS)':
 'HSDA': CDS_PINID='HSDA';
NODE_NAME     J7 5
 '@S9S_MB_2U_LIB.S9S_MB_2U(SCH_1):PAGE88_I12@PURE_QUANTA.SCONN288_ADR50017P130CC(CHIPS)':
 'HSDA': CDS_PINID='HSDA';
NODE_NAME     J8 5
 '@S9S_MB_2U_LIB.S9S_MB_2U(SCH_1):PAGE89_I50@PURE_QUANTA.SCONN288_ADR50017P087CC(CHIPS)':
 'HSDA': CDS_PINID='HSDA';
NODE_NAME     J3 5
 '@S9S_MB_2U_LIB.S9S_MB_2U(SCH_1):PAGE84_I180@PURE_QUANTA.SCONN288_ADR50017P130CC(CHIPS)':
 'HSDA': CDS_PINID='HSDA';
NODE_NAME     R692 2
 '@S9S_MB_2U_LIB.S9S_MB_2U(SCH_1):PAGE217_I40@PURE_QUANTA.Q_RES(CHIPS)':
 'B': CDS_PINID='B';
NET_NAME
'I3C_SPD_DDRABCD_CPU0_R_SCL'
 '@S9S_MB_2U_LIB.S9S_MB_2U(SCH_1):I3C_SPD_DDRABCD_CPU0_R_SCL':
 C_SIGNAL='@s9s_mb_2u_lib.s9s_mb_2u(sch_1):i3c_spd_ddrabcd_cpu0_r_scl';
NODE_NAME     U15 2
 '@S9S_MB_2U_LIB.S9S_MB_2U(SCH_1):PAGE217_I19@PURE_QUANTA.QS3VH257QG8(CHIPS)':
 'I0A': CDS_PINID='I0A';
NODE_NAME     R682 1
 '@S9S_MB_2U_LIB.S9S_MB_2U(SCH_1):PAGE217_I20@PURE_QUANTA.Q_RES(CHIPS)':
 'A': CDS_PINID='A';
NODE_NAME     R687 2
 '@S9S_MB_2U_LIB.S9S_MB_2U(SCH_1):PAGE217_I34@PURE_QUANTA.Q_RES(CHIPS)':
 'B': CDS_PINID='B';
NET_NAME
'I3C_SPD_DDRABCD_CPU0_R_SDA'
 '@S9S_MB_2U_LIB.S9S_MB_2U(SCH_1):I3C_SPD_DDRABCD_CPU0_R_SDA':
 C_SIGNAL='@s9s_mb_2u_lib.s9s_mb_2u(sch_1):i3c_spd_ddrabcd_cpu0_r_sda';
NODE_NAME     R683 1
 '@S9S_MB_2U_LIB.S9S_MB_2U(SCH_1):PAGE217_I18@PURE_QUANTA.Q_RES(CHIPS)':
 'A': CDS_PINID='A';
NODE_NAME     U15 5
 '@S9S_MB_2U_LIB.S9S_MB_2U(SCH_1):PAGE217_I19@PURE_QUANTA.QS3VH257QG8(CHIPS)':
 'I0B': CDS_PINID='I0B';
NODE_NAME     R688 2
 '@S9S_MB_2U_LIB.S9S_MB_2U(SCH_1):PAGE217_I35@PURE_QUANTA.Q_RES(CHIPS)':
 'B': CDS_PINID='B';
NET_NAME
'I3C_SPD_DDRABCD_CPU0_SCL'
 '@S9S_MB_2U_LIB.S9S_MB_2U(SCH_1):I3C_SPD_DDRABCD_CPU0_SCL':
 C_SIGNAL='@s9s_mb_2u_lib.s9s_mb_2u(sch_1):i3c_spd_ddrabcd_cpu0_scl';
NODE_NAME     U2 BT22
 '@S9S_MB_2U_LIB.S9S_MB_2U(SCH_1):PAGE13_I57@PURE_QUANTA.SOCKET4677_AZIF0045P001C01CS(CHIPS)':
 'DDR0123_SPDSCL': CDS_PINID='DDR0123_SPDSCL';
NODE_NAME     R679 2
 '@S9S_MB_2U_LIB.S9S_MB_2U(SCH_1):PAGE217_I29@PURE_QUANTA.Q_RES(CHIPS)':
 'B': CDS_PINID='B';
NODE_NAME     R687 1
 '@S9S_MB_2U_LIB.S9S_MB_2U(SCH_1):PAGE217_I34@PURE_QUANTA.Q_RES(CHIPS)':
 'A': CDS_PINID='A';
NET_NAME
'I3C_SPD_DDRABCD_CPU0_SDA'
 '@S9S_MB_2U_LIB.S9S_MB_2U(SCH_1):I3C_SPD_DDRABCD_CPU0_SDA':
 C_SIGNAL='@s9s_mb_2u_lib.s9s_mb_2u(sch_1):i3c_spd_ddrabcd_cpu0_sda';
NODE_NAME     U2 BY22
 '@S9S_MB_2U_LIB.S9S_MB_2U(SCH_1):PAGE13_I57@PURE_QUANTA.SOCKET4677_AZIF0045P001C01CS(CHIPS)':
 'DDR0123_SPDSDA': CDS_PINID='DDR0123_SPDSDA';
NODE_NAME     R680 2
 '@S9S_MB_2U_LIB.S9S_MB_2U(SCH_1):PAGE217_I30@PURE_QUANTA.Q_RES(CHIPS)':
 'B': CDS_PINID='B';
NODE_NAME     R688 1
 '@S9S_MB_2U_LIB.S9S_MB_2U(SCH_1):PAGE217_I35@PURE_QUANTA.Q_RES(CHIPS)':
 'A': CDS_PINID='A';
NET_NAME
'I3C_SPD_DDRABCD_CPU1_BMC_R_SCL'
 '@S9S_MB_2U_LIB.S9S_MB_2U(SCH_1):I3C_SPD_DDRABCD_CPU1_BMC_R_SCL':
 C_SIGNAL='@s9s_mb_2u_lib.s9s_mb_2u(sch_1):i3c_spd_ddrabcd_cpu1_bmc_r_scl';
NODE_NAME     R597 1
 '@S9S_MB_2U_LIB.S9S_MB_2U(SCH_1):PAGE228_I316@PURE_QUANTA.Q_RES(CHIPS)':
 'A': CDS_PINID='A';
NODE_NAME     J41 OA9
 '@S9S_MB_2U_LIB.S9S_MB_2U(SCH_1):PAGE227_I173@PURE_QUANTA.SCONN168_ME1016810202011(CHIPS)':
 'RBT_TXD0': CDS_PINID='RBT_TXD0';
NET_NAME
'I3C_SPD_DDRABCD_CPU1_BMC_R_SDA'
 '@S9S_MB_2U_LIB.S9S_MB_2U(SCH_1):I3C_SPD_DDRABCD_CPU1_BMC_R_SDA':
 C_SIGNAL='@s9s_mb_2u_lib.s9s_mb_2u(sch_1):i3c_spd_ddrabcd_cpu1_bmc_r_sda';
NODE_NAME     R598 1
 '@S9S_MB_2U_LIB.S9S_MB_2U(SCH_1):PAGE228_I315@PURE_QUANTA.Q_RES(CHIPS)':
 'A': CDS_PINID='A';
NODE_NAME     J41 OA10
 '@S9S_MB_2U_LIB.S9S_MB_2U(SCH_1):PAGE227_I173@PURE_QUANTA.SCONN168_ME1016810202011(CHIPS)':
 'GND_OA10': CDS_PINID='GND_OA10';
NET_NAME
'I3C_SPD_DDRABCD_CPU1_BMC_SCL'
 '@S9S_MB_2U_LIB.S9S_MB_2U(SCH_1):I3C_SPD_DDRABCD_CPU1_BMC_SCL':
 C_SIGNAL='@s9s_mb_2u_lib.s9s_mb_2u(sch_1):i3c_spd_ddrabcd_cpu1_bmc_scl';
NODE_NAME     R597 2
 '@S9S_MB_2U_LIB.S9S_MB_2U(SCH_1):PAGE228_I316@PURE_QUANTA.Q_RES(CHIPS)':
 'B': CDS_PINID='B';
NODE_NAME     U14 3
 '@S9S_MB_2U_LIB.S9S_MB_2U(SCH_1):PAGE218_I12@PURE_QUANTA.QS3VH257QG8(CHIPS)':
 'I1A': CDS_PINID='I1A';
NET_NAME
'I3C_SPD_DDRABCD_CPU1_BMC_SDA'
 '@S9S_MB_2U_LIB.S9S_MB_2U(SCH_1):I3C_SPD_DDRABCD_CPU1_BMC_SDA':
 C_SIGNAL='@s9s_mb_2u_lib.s9s_mb_2u(sch_1):i3c_spd_ddrabcd_cpu1_bmc_sda';
NODE_NAME     R598 2
 '@S9S_MB_2U_LIB.S9S_MB_2U(SCH_1):PAGE228_I315@PURE_QUANTA.Q_RES(CHIPS)':
 'B': CDS_PINID='B';
NODE_NAME     U14 6
 '@S9S_MB_2U_LIB.S9S_MB_2U(SCH_1):PAGE218_I12@PURE_QUANTA.QS3VH257QG8(CHIPS)':
 'I1B': CDS_PINID='I1B';
NET_NAME
'I3C_SPD_DDRABCD_CPU1_LVC1_R_SCL'
 '@S9S_MB_2U_LIB.S9S_MB_2U(SCH_1):I3C_SPD_DDRABCD_CPU1_LVC1_R_SCL':
 C_SIGNAL='@s9s_mb_2u_lib.s9s_mb_2u(sch_1):i3c_spd_ddrabcd_cpu1_lvc1_r_scl';
NODE_NAME     U14 4
 '@S9S_MB_2U_LIB.S9S_MB_2U(SCH_1):PAGE218_I12@PURE_QUANTA.QS3VH257QG8(CHIPS)':
 'YA': CDS_PINID='YA';
NODE_NAME     R665 2
 '@S9S_MB_2U_LIB.S9S_MB_2U(SCH_1):PAGE218_I23@PURE_QUANTA.Q_RES(CHIPS)':
 'B': CDS_PINID='B';
NODE_NAME     R674 1
 '@S9S_MB_2U_LIB.S9S_MB_2U(SCH_1):PAGE218_I37@PURE_QUANTA.Q_RES(CHIPS)':
 'A': CDS_PINID='A';
NET_NAME
'I3C_SPD_DDRABCD_CPU1_LVC1_R_SDA'
 '@S9S_MB_2U_LIB.S9S_MB_2U(SCH_1):I3C_SPD_DDRABCD_CPU1_LVC1_R_SDA':
 C_SIGNAL='@s9s_mb_2u_lib.s9s_mb_2u(sch_1):i3c_spd_ddrabcd_cpu1_lvc1_r_sda';
NODE_NAME     R666 2
 '@S9S_MB_2U_LIB.S9S_MB_2U(SCH_1):PAGE218_I22@PURE_QUANTA.Q_RES(CHIPS)':
 'B': CDS_PINID='B';
NODE_NAME     U14 7
 '@S9S_MB_2U_LIB.S9S_MB_2U(SCH_1):PAGE218_I12@PURE_QUANTA.QS3VH257QG8(CHIPS)':
 'YB': CDS_PINID='YB';
NODE_NAME     R675 1
 '@S9S_MB_2U_LIB.S9S_MB_2U(SCH_1):PAGE218_I36@PURE_QUANTA.Q_RES(CHIPS)':
 'A': CDS_PINID='A';
NET_NAME
'I3C_SPD_DDRABCD_CPU1_LVC1_SCL'
 '@S9S_MB_2U_LIB.S9S_MB_2U(SCH_1):I3C_SPD_DDRABCD_CPU1_LVC1_SCL':
 C_SIGNAL='@s9s_mb_2u_lib.s9s_mb_2u(sch_1):i3c_spd_ddrabcd_cpu1_lvc1_scl';
NODE_NAME     R3891 2
 '@S9S_MB_2U_LIB.S9S_MB_2U(SCH_1):PAGE98_I179@PURE_QUANTA.Q_RES(CHIPS)':
 'B': CDS_PINID='B';
NODE_NAME     R3892 2
 '@S9S_MB_2U_LIB.S9S_MB_2U(SCH_1):PAGE99_I180@PURE_QUANTA.Q_RES(CHIPS)':
 'B': CDS_PINID='B';
NODE_NAME     R3893 2
 '@S9S_MB_2U_LIB.S9S_MB_2U(SCH_1):PAGE100_I180@PURE_QUANTA.Q_RES(CHIPS)':
 'B': CDS_PINID='B';
NODE_NAME     R3894 2
 '@S9S_MB_2U_LIB.S9S_MB_2U(SCH_1):PAGE101_I180@PURE_QUANTA.Q_RES(CHIPS)':
 'B': CDS_PINID='B';
NODE_NAME     R3895 2
 '@S9S_MB_2U_LIB.S9S_MB_2U(SCH_1):PAGE102_I180@PURE_QUANTA.Q_RES(CHIPS)':
 'B': CDS_PINID='B';
NODE_NAME     R3896 2
 '@S9S_MB_2U_LIB.S9S_MB_2U(SCH_1):PAGE103_I180@PURE_QUANTA.Q_RES(CHIPS)':
 'B': CDS_PINID='B';
NODE_NAME     R3897 2
 '@S9S_MB_2U_LIB.S9S_MB_2U(SCH_1):PAGE104_I180@PURE_QUANTA.Q_RES(CHIPS)':
 'B': CDS_PINID='B';
NODE_NAME     R3898 2
 '@S9S_MB_2U_LIB.S9S_MB_2U(SCH_1):PAGE105_I183@PURE_QUANTA.Q_RES(CHIPS)':
 'B': CDS_PINID='B';
NODE_NAME     R674 2
 '@S9S_MB_2U_LIB.S9S_MB_2U(SCH_1):PAGE218_I37@PURE_QUANTA.Q_RES(CHIPS)':
 'B': CDS_PINID='B';
NET_NAME
'I3C_SPD_DDRABCD_CPU1_LVC1_SCL_1'
 '@S9S_MB_2U_LIB.S9S_MB_2U(SCH_1):I3C_SPD_DDRABCD_CPU1_LVC1_SCL_R2':
 C_SIGNAL='@s9s_mb_2u_lib.s9s_mb_2u(sch_1):i3c_spd_ddrabcd_cpu1_lvc1_scl_r2';
NODE_NAME     J18 4
 '@S9S_MB_2U_LIB.S9S_MB_2U(SCH_1):PAGE99_I24@PURE_QUANTA.SCONN288_ADR50017P087CC(CHIPS)':
 'HSCL': CDS_PINID='HSCL';
NODE_NAME     R3892 1
 '@S9S_MB_2U_LIB.S9S_MB_2U(SCH_1):PAGE99_I180@PURE_QUANTA.Q_RES(CHIPS)':
 'A': CDS_PINID='A';
NET_NAME
'I3C_SPD_DDRABCD_CPU1_LVC1_SCL_2'
 '@S9S_MB_2U_LIB.S9S_MB_2U(SCH_1):I3C_SPD_DDRABCD_CPU1_LVC1_SCL_R3':
 C_SIGNAL='@s9s_mb_2u_lib.s9s_mb_2u(sch_1):i3c_spd_ddrabcd_cpu1_lvc1_scl_r3';
NODE_NAME     J19 4
 '@S9S_MB_2U_LIB.S9S_MB_2U(SCH_1):PAGE100_I25@PURE_QUANTA.SCONN288_ADR50017P130CC(CHIPS)':
 'HSCL': CDS_PINID='HSCL';
NODE_NAME     R3893 1
 '@S9S_MB_2U_LIB.S9S_MB_2U(SCH_1):PAGE100_I180@PURE_QUANTA.Q_RES(CHIPS)':
 'A': CDS_PINID='A';
NET_NAME
'I3C_SPD_DDRABCD_CPU1_LVC1_SCL_3'
 '@S9S_MB_2U_LIB.S9S_MB_2U(SCH_1):I3C_SPD_DDRABCD_CPU1_LVC1_SCL_R4':
 C_SIGNAL='@s9s_mb_2u_lib.s9s_mb_2u(sch_1):i3c_spd_ddrabcd_cpu1_lvc1_scl_r4';
NODE_NAME     J20 4
 '@S9S_MB_2U_LIB.S9S_MB_2U(SCH_1):PAGE101_I47@PURE_QUANTA.SCONN288_ADR50017P087CC(CHIPS)':
 'HSCL': CDS_PINID='HSCL';
NODE_NAME     R3894 1
 '@S9S_MB_2U_LIB.S9S_MB_2U(SCH_1):PAGE101_I180@PURE_QUANTA.Q_RES(CHIPS)':
 'A': CDS_PINID='A';
NET_NAME
'I3C_SPD_DDRABCD_CPU1_LVC1_SCL_4'
 '@S9S_MB_2U_LIB.S9S_MB_2U(SCH_1):I3C_SPD_DDRABCD_CPU1_LVC1_SCL_R5':
 C_SIGNAL='@s9s_mb_2u_lib.s9s_mb_2u(sch_1):i3c_spd_ddrabcd_cpu1_lvc1_scl_r5';
NODE_NAME     J21 4
 '@S9S_MB_2U_LIB.S9S_MB_2U(SCH_1):PAGE102_I13@PURE_QUANTA.SCONN288_ADR50017P130CC(CHIPS)':
 'HSCL': CDS_PINID='HSCL';
NODE_NAME     R3895 1
 '@S9S_MB_2U_LIB.S9S_MB_2U(SCH_1):PAGE102_I180@PURE_QUANTA.Q_RES(CHIPS)':
 'A': CDS_PINID='A';
NET_NAME
'I3C_SPD_DDRABCD_CPU1_LVC1_SCL_5'
 '@S9S_MB_2U_LIB.S9S_MB_2U(SCH_1):I3C_SPD_DDRABCD_CPU1_LVC1_SCL_R6':
 C_SIGNAL='@s9s_mb_2u_lib.s9s_mb_2u(sch_1):i3c_spd_ddrabcd_cpu1_lvc1_scl_r6';
NODE_NAME     J22 4
 '@S9S_MB_2U_LIB.S9S_MB_2U(SCH_1):PAGE103_I51@PURE_QUANTA.SCONN288_ADR50017P087CC(CHIPS)':
 'HSCL': CDS_PINID='HSCL';
NODE_NAME     R3896 1
 '@S9S_MB_2U_LIB.S9S_MB_2U(SCH_1):PAGE103_I180@PURE_QUANTA.Q_RES(CHIPS)':
 'A': CDS_PINID='A';
NET_NAME
'I3C_SPD_DDRABCD_CPU1_LVC1_SCL_6'
 '@S9S_MB_2U_LIB.S9S_MB_2U(SCH_1):I3C_SPD_DDRABCD_CPU1_LVC1_SCL_R7':
 C_SIGNAL='@s9s_mb_2u_lib.s9s_mb_2u(sch_1):i3c_spd_ddrabcd_cpu1_lvc1_scl_r7';
NODE_NAME     J23 4
 '@S9S_MB_2U_LIB.S9S_MB_2U(SCH_1):PAGE104_I25@PURE_QUANTA.SCONN288_ADR50017P130CC(CHIPS)':
 'HSCL': CDS_PINID='HSCL';
NODE_NAME     R3897 1
 '@S9S_MB_2U_LIB.S9S_MB_2U(SCH_1):PAGE104_I180@PURE_QUANTA.Q_RES(CHIPS)':
 'A': CDS_PINID='A';
NET_NAME
'I3C_SPD_DDRABCD_CPU1_LVC1_SCL_7'
 '@S9S_MB_2U_LIB.S9S_MB_2U(SCH_1):I3C_SPD_DDRABCD_CPU1_LVC1_SCL_R8':
 C_SIGNAL='@s9s_mb_2u_lib.s9s_mb_2u(sch_1):i3c_spd_ddrabcd_cpu1_lvc1_scl_r8';
NODE_NAME     J24 4
 '@S9S_MB_2U_LIB.S9S_MB_2U(SCH_1):PAGE105_I178@PURE_QUANTA.SCONN288_ADR50017P087CC(CHIPS)':
 'HSCL': CDS_PINID='HSCL';
NODE_NAME     R3898 1
 '@S9S_MB_2U_LIB.S9S_MB_2U(SCH_1):PAGE105_I183@PURE_QUANTA.Q_RES(CHIPS)':
 'A': CDS_PINID='A';
NET_NAME
'I3C_SPD_DDRABCD_CPU1_LVC1_SCL_R'
 '@S9S_MB_2U_LIB.S9S_MB_2U(SCH_1):I3C_SPD_DDRABCD_CPU1_LVC1_SCL_R1':
 C_SIGNAL='@s9s_mb_2u_lib.s9s_mb_2u(sch_1):i3c_spd_ddrabcd_cpu1_lvc1_scl_r1';
NODE_NAME     J17 4
 '@S9S_MB_2U_LIB.S9S_MB_2U(SCH_1):PAGE98_I12@PURE_QUANTA.SCONN288_ADR50017P130CC(CHIPS)':
 'HSCL': CDS_PINID='HSCL';
NODE_NAME     R3891 1
 '@S9S_MB_2U_LIB.S9S_MB_2U(SCH_1):PAGE98_I179@PURE_QUANTA.Q_RES(CHIPS)':
 'A': CDS_PINID='A';
NET_NAME
'I3C_SPD_DDRABCD_CPU1_LVC1_SDA'
 '@S9S_MB_2U_LIB.S9S_MB_2U(SCH_1):I3C_SPD_DDRABCD_CPU1_LVC1_SDA':
 C_SIGNAL='@s9s_mb_2u_lib.s9s_mb_2u(sch_1):i3c_spd_ddrabcd_cpu1_lvc1_sda';
NODE_NAME     J17 5
 '@S9S_MB_2U_LIB.S9S_MB_2U(SCH_1):PAGE98_I12@PURE_QUANTA.SCONN288_ADR50017P130CC(CHIPS)':
 'HSDA': CDS_PINID='HSDA';
NODE_NAME     J18 5
 '@S9S_MB_2U_LIB.S9S_MB_2U(SCH_1):PAGE99_I24@PURE_QUANTA.SCONN288_ADR50017P087CC(CHIPS)':
 'HSDA': CDS_PINID='HSDA';
NODE_NAME     J19 5
 '@S9S_MB_2U_LIB.S9S_MB_2U(SCH_1):PAGE100_I25@PURE_QUANTA.SCONN288_ADR50017P130CC(CHIPS)':
 'HSDA': CDS_PINID='HSDA';
NODE_NAME     J20 5
 '@S9S_MB_2U_LIB.S9S_MB_2U(SCH_1):PAGE101_I47@PURE_QUANTA.SCONN288_ADR50017P087CC(CHIPS)':
 'HSDA': CDS_PINID='HSDA';
NODE_NAME     J21 5
 '@S9S_MB_2U_LIB.S9S_MB_2U(SCH_1):PAGE102_I13@PURE_QUANTA.SCONN288_ADR50017P130CC(CHIPS)':
 'HSDA': CDS_PINID='HSDA';
NODE_NAME     J22 5
 '@S9S_MB_2U_LIB.S9S_MB_2U(SCH_1):PAGE103_I51@PURE_QUANTA.SCONN288_ADR50017P087CC(CHIPS)':
 'HSDA': CDS_PINID='HSDA';
NODE_NAME     J23 5
 '@S9S_MB_2U_LIB.S9S_MB_2U(SCH_1):PAGE104_I25@PURE_QUANTA.SCONN288_ADR50017P130CC(CHIPS)':
 'HSDA': CDS_PINID='HSDA';
NODE_NAME     J24 5
 '@S9S_MB_2U_LIB.S9S_MB_2U(SCH_1):PAGE105_I178@PURE_QUANTA.SCONN288_ADR50017P087CC(CHIPS)':
 'HSDA': CDS_PINID='HSDA';
NODE_NAME     R675 2
 '@S9S_MB_2U_LIB.S9S_MB_2U(SCH_1):PAGE218_I36@PURE_QUANTA.Q_RES(CHIPS)':
 'B': CDS_PINID='B';
NET_NAME
'I3C_SPD_DDRABCD_CPU1_R_SCL'
 '@S9S_MB_2U_LIB.S9S_MB_2U(SCH_1):I3C_SPD_DDRABCD_CPU1_R_SCL':
 C_SIGNAL='@s9s_mb_2u_lib.s9s_mb_2u(sch_1):i3c_spd_ddrabcd_cpu1_r_scl';
NODE_NAME     R670 2
 '@S9S_MB_2U_LIB.S9S_MB_2U(SCH_1):PAGE218_I32@PURE_QUANTA.Q_RES(CHIPS)':
 'B': CDS_PINID='B';
NODE_NAME     U14 2
 '@S9S_MB_2U_LIB.S9S_MB_2U(SCH_1):PAGE218_I12@PURE_QUANTA.QS3VH257QG8(CHIPS)':
 'I0A': CDS_PINID='I0A';
NODE_NAME     R665 1
 '@S9S_MB_2U_LIB.S9S_MB_2U(SCH_1):PAGE218_I23@PURE_QUANTA.Q_RES(CHIPS)':
 'A': CDS_PINID='A';
NET_NAME
'I3C_SPD_DDRABCD_CPU1_R_SDA'
 '@S9S_MB_2U_LIB.S9S_MB_2U(SCH_1):I3C_SPD_DDRABCD_CPU1_R_SDA':
 C_SIGNAL='@s9s_mb_2u_lib.s9s_mb_2u(sch_1):i3c_spd_ddrabcd_cpu1_r_sda';
NODE_NAME     R666 1
 '@S9S_MB_2U_LIB.S9S_MB_2U(SCH_1):PAGE218_I22@PURE_QUANTA.Q_RES(CHIPS)':
 'A': CDS_PINID='A';
NODE_NAME     R671 2
 '@S9S_MB_2U_LIB.S9S_MB_2U(SCH_1):PAGE218_I33@PURE_QUANTA.Q_RES(CHIPS)':
 'B': CDS_PINID='B';
NODE_NAME     U14 5
 '@S9S_MB_2U_LIB.S9S_MB_2U(SCH_1):PAGE218_I12@PURE_QUANTA.QS3VH257QG8(CHIPS)':
 'I0B': CDS_PINID='I0B';
NET_NAME
'I3C_SPD_DDRABCD_CPU1_SCL'
 '@S9S_MB_2U_LIB.S9S_MB_2U(SCH_1):I3C_SPD_DDRABCD_CPU1_SCL':
 C_SIGNAL='@s9s_mb_2u_lib.s9s_mb_2u(sch_1):i3c_spd_ddrabcd_cpu1_scl';
NODE_NAME     U1 BT22
 '@S9S_MB_2U_LIB.S9S_MB_2U(SCH_1):PAGE44_I51@PURE_QUANTA.SOCKET4677_AZIF0045P001C01CS(CHIPS)':
 'DDR0123_SPDSCL': CDS_PINID='DDR0123_SPDSCL';
NODE_NAME     R670 1
 '@S9S_MB_2U_LIB.S9S_MB_2U(SCH_1):PAGE218_I32@PURE_QUANTA.Q_RES(CHIPS)':
 'A': CDS_PINID='A';
NODE_NAME     R662 2
 '@S9S_MB_2U_LIB.S9S_MB_2U(SCH_1):PAGE218_I17@PURE_QUANTA.Q_RES(CHIPS)':
 'B': CDS_PINID='B';
NET_NAME
'I3C_SPD_DDRABCD_CPU1_SDA'
 '@S9S_MB_2U_LIB.S9S_MB_2U(SCH_1):I3C_SPD_DDRABCD_CPU1_SDA':
 C_SIGNAL='@s9s_mb_2u_lib.s9s_mb_2u(sch_1):i3c_spd_ddrabcd_cpu1_sda';
NODE_NAME     U1 BY22
 '@S9S_MB_2U_LIB.S9S_MB_2U(SCH_1):PAGE44_I51@PURE_QUANTA.SOCKET4677_AZIF0045P001C01CS(CHIPS)':
 'DDR0123_SPDSDA': CDS_PINID='DDR0123_SPDSDA';
NODE_NAME     R663 2
 '@S9S_MB_2U_LIB.S9S_MB_2U(SCH_1):PAGE218_I18@PURE_QUANTA.Q_RES(CHIPS)':
 'B': CDS_PINID='B';
NODE_NAME     R671 1
 '@S9S_MB_2U_LIB.S9S_MB_2U(SCH_1):PAGE218_I33@PURE_QUANTA.Q_RES(CHIPS)':
 'A': CDS_PINID='A';
NET_NAME
'I3C_SPD_DDREFGH_CPU0_BMC_R_SCL'
 '@S9S_MB_2U_LIB.S9S_MB_2U(SCH_1):I3C_SPD_DDREFGH_CPU0_BMC_R_SCL':
 C_SIGNAL='@s9s_mb_2u_lib.s9s_mb_2u(sch_1):i3c_spd_ddrefgh_cpu0_bmc_r_scl';
NODE_NAME     R595 1
 '@S9S_MB_2U_LIB.S9S_MB_2U(SCH_1):PAGE228_I314@PURE_QUANTA.Q_RES(CHIPS)':
 'A': CDS_PINID='A';
NODE_NAME     J41 OA7
 '@S9S_MB_2U_LIB.S9S_MB_2U(SCH_1):PAGE227_I173@PURE_QUANTA.SCONN168_ME1016810202011(CHIPS)':
 'RBT_TX_EN': CDS_PINID='RBT_TX_EN';
NET_NAME
'I3C_SPD_DDREFGH_CPU0_BMC_R_SDA'
 '@S9S_MB_2U_LIB.S9S_MB_2U(SCH_1):I3C_SPD_DDREFGH_CPU0_BMC_R_SDA':
 C_SIGNAL='@s9s_mb_2u_lib.s9s_mb_2u(sch_1):i3c_spd_ddrefgh_cpu0_bmc_r_sda';
NODE_NAME     R596 1
 '@S9S_MB_2U_LIB.S9S_MB_2U(SCH_1):PAGE228_I313@PURE_QUANTA.Q_RES(CHIPS)':
 'A': CDS_PINID='A';
NODE_NAME     J41 OA8
 '@S9S_MB_2U_LIB.S9S_MB_2U(SCH_1):PAGE227_I173@PURE_QUANTA.SCONN168_ME1016810202011(CHIPS)':
 'RBT_TXD1': CDS_PINID='RBT_TXD1';
NET_NAME
'I3C_SPD_DDREFGH_CPU0_BMC_SCL'
 '@S9S_MB_2U_LIB.S9S_MB_2U(SCH_1):I3C_SPD_DDREFGH_CPU0_BMC_SCL':
 C_SIGNAL='@s9s_mb_2u_lib.s9s_mb_2u(sch_1):i3c_spd_ddrefgh_cpu0_bmc_scl';
NODE_NAME     R595 2
 '@S9S_MB_2U_LIB.S9S_MB_2U(SCH_1):PAGE228_I314@PURE_QUANTA.Q_RES(CHIPS)':
 'B': CDS_PINID='B';
NODE_NAME     U15 10
 '@S9S_MB_2U_LIB.S9S_MB_2U(SCH_1):PAGE217_I19@PURE_QUANTA.QS3VH257QG8(CHIPS)':
 'I1C': CDS_PINID='I1C';
NET_NAME
'I3C_SPD_DDREFGH_CPU0_BMC_SDA'
 '@S9S_MB_2U_LIB.S9S_MB_2U(SCH_1):I3C_SPD_DDREFGH_CPU0_BMC_SDA':
 C_SIGNAL='@s9s_mb_2u_lib.s9s_mb_2u(sch_1):i3c_spd_ddrefgh_cpu0_bmc_sda';
NODE_NAME     R596 2
 '@S9S_MB_2U_LIB.S9S_MB_2U(SCH_1):PAGE228_I313@PURE_QUANTA.Q_RES(CHIPS)':
 'B': CDS_PINID='B';
NODE_NAME     U15 13
 '@S9S_MB_2U_LIB.S9S_MB_2U(SCH_1):PAGE217_I19@PURE_QUANTA.QS3VH257QG8(CHIPS)':
 'I1D': CDS_PINID='I1D';
NET_NAME
'I3C_SPD_DDREFGH_CPU0_LVC1_R_SCL'
 '@S9S_MB_2U_LIB.S9S_MB_2U(SCH_1):I3C_SPD_DDREFGH_CPU0_LVC1_R_SCL':
 C_SIGNAL='@s9s_mb_2u_lib.s9s_mb_2u(sch_1):i3c_spd_ddrefgh_cpu0_lvc1_r_scl';
NODE_NAME     R684 2
 '@S9S_MB_2U_LIB.S9S_MB_2U(SCH_1):PAGE217_I17@PURE_QUANTA.Q_RES(CHIPS)':
 'B': CDS_PINID='B';
NODE_NAME     U15 9
 '@S9S_MB_2U_LIB.S9S_MB_2U(SCH_1):PAGE217_I19@PURE_QUANTA.QS3VH257QG8(CHIPS)':
 'YC': CDS_PINID='YC';
NODE_NAME     R693 1
 '@S9S_MB_2U_LIB.S9S_MB_2U(SCH_1):PAGE217_I38@PURE_QUANTA.Q_RES(CHIPS)':
 'A': CDS_PINID='A';
NET_NAME
'I3C_SPD_DDREFGH_CPU0_LVC1_R_SDA'
 '@S9S_MB_2U_LIB.S9S_MB_2U(SCH_1):I3C_SPD_DDREFGH_CPU0_LVC1_R_SDA':
 C_SIGNAL='@s9s_mb_2u_lib.s9s_mb_2u(sch_1):i3c_spd_ddrefgh_cpu0_lvc1_r_sda';
NODE_NAME     R685 2
 '@S9S_MB_2U_LIB.S9S_MB_2U(SCH_1):PAGE217_I16@PURE_QUANTA.Q_RES(CHIPS)':
 'B': CDS_PINID='B';
NODE_NAME     U15 12
 '@S9S_MB_2U_LIB.S9S_MB_2U(SCH_1):PAGE217_I19@PURE_QUANTA.QS3VH257QG8(CHIPS)':
 'YD': CDS_PINID='YD';
NODE_NAME     R694 1
 '@S9S_MB_2U_LIB.S9S_MB_2U(SCH_1):PAGE217_I37@PURE_QUANTA.Q_RES(CHIPS)':
 'A': CDS_PINID='A';
NET_NAME
'I3C_SPD_DDREFGH_CPU0_LVC1_SCL'
 '@S9S_MB_2U_LIB.S9S_MB_2U(SCH_1):I3C_SPD_DDREFGH_CPU0_LVC1_SCL':
 C_SIGNAL='@s9s_mb_2u_lib.s9s_mb_2u(sch_1):i3c_spd_ddrefgh_cpu0_lvc1_scl';
NODE_NAME     R3883 2
 '@S9S_MB_2U_LIB.S9S_MB_2U(SCH_1):PAGE90_I179@PURE_QUANTA.Q_RES(CHIPS)':
 'B': CDS_PINID='B';
NODE_NAME     R3884 2
 '@S9S_MB_2U_LIB.S9S_MB_2U(SCH_1):PAGE91_I179@PURE_QUANTA.Q_RES(CHIPS)':
 'B': CDS_PINID='B';
NODE_NAME     R3885 2
 '@S9S_MB_2U_LIB.S9S_MB_2U(SCH_1):PAGE92_I179@PURE_QUANTA.Q_RES(CHIPS)':
 'B': CDS_PINID='B';
NODE_NAME     R3886 2
 '@S9S_MB_2U_LIB.S9S_MB_2U(SCH_1):PAGE93_I179@PURE_QUANTA.Q_RES(CHIPS)':
 'B': CDS_PINID='B';
NODE_NAME     R3887 2
 '@S9S_MB_2U_LIB.S9S_MB_2U(SCH_1):PAGE94_I179@PURE_QUANTA.Q_RES(CHIPS)':
 'B': CDS_PINID='B';
NODE_NAME     R3888 2
 '@S9S_MB_2U_LIB.S9S_MB_2U(SCH_1):PAGE95_I179@PURE_QUANTA.Q_RES(CHIPS)':
 'B': CDS_PINID='B';
NODE_NAME     R3889 2
 '@S9S_MB_2U_LIB.S9S_MB_2U(SCH_1):PAGE96_I179@PURE_QUANTA.Q_RES(CHIPS)':
 'B': CDS_PINID='B';
NODE_NAME     R3890 2
 '@S9S_MB_2U_LIB.S9S_MB_2U(SCH_1):PAGE97_I179@PURE_QUANTA.Q_RES(CHIPS)':
 'B': CDS_PINID='B';
NODE_NAME     R693 2
 '@S9S_MB_2U_LIB.S9S_MB_2U(SCH_1):PAGE217_I38@PURE_QUANTA.Q_RES(CHIPS)':
 'B': CDS_PINID='B';
NET_NAME
'I3C_SPD_DDREFGH_CPU0_LVC1_SCL_1'
 '@S9S_MB_2U_LIB.S9S_MB_2U(SCH_1):I3C_SPD_DDREFGH_CPU0_LVC1_SCL_R2':
 C_SIGNAL='@s9s_mb_2u_lib.s9s_mb_2u(sch_1):i3c_spd_ddrefgh_cpu0_lvc1_scl_r2';
NODE_NAME     J10 4
 '@S9S_MB_2U_LIB.S9S_MB_2U(SCH_1):PAGE91_I13@PURE_QUANTA.SCONN288_ADR50017P087CC(CHIPS)':
 'HSCL': CDS_PINID='HSCL';
NODE_NAME     R3884 1
 '@S9S_MB_2U_LIB.S9S_MB_2U(SCH_1):PAGE91_I179@PURE_QUANTA.Q_RES(CHIPS)':
 'A': CDS_PINID='A';
NET_NAME
'I3C_SPD_DDREFGH_CPU0_LVC1_SCL_2'
 '@S9S_MB_2U_LIB.S9S_MB_2U(SCH_1):I3C_SPD_DDREFGH_CPU0_LVC1_SCL_R3':
 C_SIGNAL='@s9s_mb_2u_lib.s9s_mb_2u(sch_1):i3c_spd_ddrefgh_cpu0_lvc1_scl_r3';
NODE_NAME     J11 4
 '@S9S_MB_2U_LIB.S9S_MB_2U(SCH_1):PAGE92_I25@PURE_QUANTA.SCONN288_ADR50017P130CC(CHIPS)':
 'HSCL': CDS_PINID='HSCL';
NODE_NAME     R3885 1
 '@S9S_MB_2U_LIB.S9S_MB_2U(SCH_1):PAGE92_I179@PURE_QUANTA.Q_RES(CHIPS)':
 'A': CDS_PINID='A';
NET_NAME
'I3C_SPD_DDREFGH_CPU0_LVC1_SCL_3'
 '@S9S_MB_2U_LIB.S9S_MB_2U(SCH_1):I3C_SPD_DDREFGH_CPU0_LVC1_SCL_R4':
 C_SIGNAL='@s9s_mb_2u_lib.s9s_mb_2u(sch_1):i3c_spd_ddrefgh_cpu0_lvc1_scl_r4';
NODE_NAME     J12 4
 '@S9S_MB_2U_LIB.S9S_MB_2U(SCH_1):PAGE93_I24@PURE_QUANTA.SCONN288_ADR50017P087CC(CHIPS)':
 'HSCL': CDS_PINID='HSCL';
NODE_NAME     R3886 1
 '@S9S_MB_2U_LIB.S9S_MB_2U(SCH_1):PAGE93_I179@PURE_QUANTA.Q_RES(CHIPS)':
 'A': CDS_PINID='A';
NET_NAME
'I3C_SPD_DDREFGH_CPU0_LVC1_SCL_4'
 '@S9S_MB_2U_LIB.S9S_MB_2U(SCH_1):I3C_SPD_DDREFGH_CPU0_LVC1_SCL_R5':
 C_SIGNAL='@s9s_mb_2u_lib.s9s_mb_2u(sch_1):i3c_spd_ddrefgh_cpu0_lvc1_scl_r5';
NODE_NAME     J13 4
 '@S9S_MB_2U_LIB.S9S_MB_2U(SCH_1):PAGE94_I11@PURE_QUANTA.SCONN288_ADR50017P130CC(CHIPS)':
 'HSCL': CDS_PINID='HSCL';
NODE_NAME     R3887 1
 '@S9S_MB_2U_LIB.S9S_MB_2U(SCH_1):PAGE94_I179@PURE_QUANTA.Q_RES(CHIPS)':
 'A': CDS_PINID='A';
NET_NAME
'I3C_SPD_DDREFGH_CPU0_LVC1_SCL_5'
 '@S9S_MB_2U_LIB.S9S_MB_2U(SCH_1):I3C_SPD_DDREFGH_CPU0_LVC1_SCL_R6':
 C_SIGNAL='@s9s_mb_2u_lib.s9s_mb_2u(sch_1):i3c_spd_ddrefgh_cpu0_lvc1_scl_r6';
NODE_NAME     J14 4
 '@S9S_MB_2U_LIB.S9S_MB_2U(SCH_1):PAGE95_I47@PURE_QUANTA.SCONN288_ADR50017P087CC(CHIPS)':
 'HSCL': CDS_PINID='HSCL';
NODE_NAME     R3888 1
 '@S9S_MB_2U_LIB.S9S_MB_2U(SCH_1):PAGE95_I179@PURE_QUANTA.Q_RES(CHIPS)':
 'A': CDS_PINID='A';
NET_NAME
'I3C_SPD_DDREFGH_CPU0_LVC1_SCL_6'
 '@S9S_MB_2U_LIB.S9S_MB_2U(SCH_1):I3C_SPD_DDREFGH_CPU0_LVC1_SCL_R7':
 C_SIGNAL='@s9s_mb_2u_lib.s9s_mb_2u(sch_1):i3c_spd_ddrefgh_cpu0_lvc1_scl_r7';
NODE_NAME     J15 4
 '@S9S_MB_2U_LIB.S9S_MB_2U(SCH_1):PAGE96_I48@PURE_QUANTA.SCONN288_ADR50017P130CC(CHIPS)':
 'HSCL': CDS_PINID='HSCL';
NODE_NAME     R3889 1
 '@S9S_MB_2U_LIB.S9S_MB_2U(SCH_1):PAGE96_I179@PURE_QUANTA.Q_RES(CHIPS)':
 'A': CDS_PINID='A';
NET_NAME
'I3C_SPD_DDREFGH_CPU0_LVC1_SCL_7'
 '@S9S_MB_2U_LIB.S9S_MB_2U(SCH_1):I3C_SPD_DDREFGH_CPU0_LVC1_SCL_R8':
 C_SIGNAL='@s9s_mb_2u_lib.s9s_mb_2u(sch_1):i3c_spd_ddrefgh_cpu0_lvc1_scl_r8';
NODE_NAME     J16 4
 '@S9S_MB_2U_LIB.S9S_MB_2U(SCH_1):PAGE97_I6@PURE_QUANTA.SCONN288_ADR50017P087CC(CHIPS)':
 'HSCL': CDS_PINID='HSCL';
NODE_NAME     R3890 1
 '@S9S_MB_2U_LIB.S9S_MB_2U(SCH_1):PAGE97_I179@PURE_QUANTA.Q_RES(CHIPS)':
 'A': CDS_PINID='A';
NET_NAME
'I3C_SPD_DDREFGH_CPU0_LVC1_SCL_R'
 '@S9S_MB_2U_LIB.S9S_MB_2U(SCH_1):I3C_SPD_DDREFGH_CPU0_LVC1_SCL_R1':
 C_SIGNAL='@s9s_mb_2u_lib.s9s_mb_2u(sch_1):i3c_spd_ddrefgh_cpu0_lvc1_scl_r1';
NODE_NAME     J9 4
 '@S9S_MB_2U_LIB.S9S_MB_2U(SCH_1):PAGE90_I12@PURE_QUANTA.SCONN288_ADR50017P130CC(CHIPS)':
 'HSCL': CDS_PINID='HSCL';
NODE_NAME     R3883 1
 '@S9S_MB_2U_LIB.S9S_MB_2U(SCH_1):PAGE90_I179@PURE_QUANTA.Q_RES(CHIPS)':
 'A': CDS_PINID='A';
NET_NAME
'I3C_SPD_DDREFGH_CPU0_LVC1_SDA'
 '@S9S_MB_2U_LIB.S9S_MB_2U(SCH_1):I3C_SPD_DDREFGH_CPU0_LVC1_SDA':
 C_SIGNAL='@s9s_mb_2u_lib.s9s_mb_2u(sch_1):i3c_spd_ddrefgh_cpu0_lvc1_sda';
NODE_NAME     J9 5
 '@S9S_MB_2U_LIB.S9S_MB_2U(SCH_1):PAGE90_I12@PURE_QUANTA.SCONN288_ADR50017P130CC(CHIPS)':
 'HSDA': CDS_PINID='HSDA';
NODE_NAME     J10 5
 '@S9S_MB_2U_LIB.S9S_MB_2U(SCH_1):PAGE91_I13@PURE_QUANTA.SCONN288_ADR50017P087CC(CHIPS)':
 'HSDA': CDS_PINID='HSDA';
NODE_NAME     J11 5
 '@S9S_MB_2U_LIB.S9S_MB_2U(SCH_1):PAGE92_I25@PURE_QUANTA.SCONN288_ADR50017P130CC(CHIPS)':
 'HSDA': CDS_PINID='HSDA';
NODE_NAME     J12 5
 '@S9S_MB_2U_LIB.S9S_MB_2U(SCH_1):PAGE93_I24@PURE_QUANTA.SCONN288_ADR50017P087CC(CHIPS)':
 'HSDA': CDS_PINID='HSDA';
NODE_NAME     J13 5
 '@S9S_MB_2U_LIB.S9S_MB_2U(SCH_1):PAGE94_I11@PURE_QUANTA.SCONN288_ADR50017P130CC(CHIPS)':
 'HSDA': CDS_PINID='HSDA';
NODE_NAME     J14 5
 '@S9S_MB_2U_LIB.S9S_MB_2U(SCH_1):PAGE95_I47@PURE_QUANTA.SCONN288_ADR50017P087CC(CHIPS)':
 'HSDA': CDS_PINID='HSDA';
NODE_NAME     J15 5
 '@S9S_MB_2U_LIB.S9S_MB_2U(SCH_1):PAGE96_I48@PURE_QUANTA.SCONN288_ADR50017P130CC(CHIPS)':
 'HSDA': CDS_PINID='HSDA';
NODE_NAME     J16 5
 '@S9S_MB_2U_LIB.S9S_MB_2U(SCH_1):PAGE97_I6@PURE_QUANTA.SCONN288_ADR50017P087CC(CHIPS)':
 'HSDA': CDS_PINID='HSDA';
NODE_NAME     R694 2
 '@S9S_MB_2U_LIB.S9S_MB_2U(SCH_1):PAGE217_I37@PURE_QUANTA.Q_RES(CHIPS)':
 'B': CDS_PINID='B';
NET_NAME
'I3C_SPD_DDREFGH_CPU0_R_SCL'
 '@S9S_MB_2U_LIB.S9S_MB_2U(SCH_1):I3C_SPD_DDREFGH_CPU0_R_SCL':
 C_SIGNAL='@s9s_mb_2u_lib.s9s_mb_2u(sch_1):i3c_spd_ddrefgh_cpu0_r_scl';
NODE_NAME     R684 1
 '@S9S_MB_2U_LIB.S9S_MB_2U(SCH_1):PAGE217_I17@PURE_QUANTA.Q_RES(CHIPS)':
 'A': CDS_PINID='A';
NODE_NAME     U15 11
 '@S9S_MB_2U_LIB.S9S_MB_2U(SCH_1):PAGE217_I19@PURE_QUANTA.QS3VH257QG8(CHIPS)':
 'I0C': CDS_PINID='I0C';
NODE_NAME     R689 2
 '@S9S_MB_2U_LIB.S9S_MB_2U(SCH_1):PAGE217_I25@PURE_QUANTA.Q_RES(CHIPS)':
 'B': CDS_PINID='B';
NET_NAME
'I3C_SPD_DDREFGH_CPU0_R_SDA'
 '@S9S_MB_2U_LIB.S9S_MB_2U(SCH_1):I3C_SPD_DDREFGH_CPU0_R_SDA':
 C_SIGNAL='@s9s_mb_2u_lib.s9s_mb_2u(sch_1):i3c_spd_ddrefgh_cpu0_r_sda';
NODE_NAME     R685 1
 '@S9S_MB_2U_LIB.S9S_MB_2U(SCH_1):PAGE217_I16@PURE_QUANTA.Q_RES(CHIPS)':
 'A': CDS_PINID='A';
NODE_NAME     U15 14
 '@S9S_MB_2U_LIB.S9S_MB_2U(SCH_1):PAGE217_I19@PURE_QUANTA.QS3VH257QG8(CHIPS)':
 'I0D': CDS_PINID='I0D';
NODE_NAME     R690 2
 '@S9S_MB_2U_LIB.S9S_MB_2U(SCH_1):PAGE217_I26@PURE_QUANTA.Q_RES(CHIPS)':
 'B': CDS_PINID='B';
NET_NAME
'I3C_SPD_DDREFGH_CPU0_SCL'
 '@S9S_MB_2U_LIB.S9S_MB_2U(SCH_1):I3C_SPD_DDREFGH_CPU0_SCL':
 C_SIGNAL='@s9s_mb_2u_lib.s9s_mb_2u(sch_1):i3c_spd_ddrefgh_cpu0_scl';
NODE_NAME     U2 CU17
 '@S9S_MB_2U_LIB.S9S_MB_2U(SCH_1):PAGE13_I57@PURE_QUANTA.SOCKET4677_AZIF0045P001C01CS(CHIPS)':
 'DDR4567_SPDSCL': CDS_PINID='DDR4567_SPDSCL';
NODE_NAME     R689 1
 '@S9S_MB_2U_LIB.S9S_MB_2U(SCH_1):PAGE217_I25@PURE_QUANTA.Q_RES(CHIPS)':
 'A': CDS_PINID='A';
NODE_NAME     R681 2
 '@S9S_MB_2U_LIB.S9S_MB_2U(SCH_1):PAGE217_I32@PURE_QUANTA.Q_RES(CHIPS)':
 'B': CDS_PINID='B';
NET_NAME
'I3C_SPD_DDREFGH_CPU0_SDA'
 '@S9S_MB_2U_LIB.S9S_MB_2U(SCH_1):I3C_SPD_DDREFGH_CPU0_SDA':
 C_SIGNAL='@s9s_mb_2u_lib.s9s_mb_2u(sch_1):i3c_spd_ddrefgh_cpu0_sda';
NODE_NAME     U2 CT18
 '@S9S_MB_2U_LIB.S9S_MB_2U(SCH_1):PAGE13_I57@PURE_QUANTA.SOCKET4677_AZIF0045P001C01CS(CHIPS)':
 'DDR4567_SPDSDA': CDS_PINID='DDR4567_SPDSDA';
NODE_NAME     R690 1
 '@S9S_MB_2U_LIB.S9S_MB_2U(SCH_1):PAGE217_I26@PURE_QUANTA.Q_RES(CHIPS)':
 'A': CDS_PINID='A';
NODE_NAME     R686 2
 '@S9S_MB_2U_LIB.S9S_MB_2U(SCH_1):PAGE217_I33@PURE_QUANTA.Q_RES(CHIPS)':
 'B': CDS_PINID='B';
NET_NAME
'I3C_SPD_DDREFGH_CPU1_BMC_R_SCL'
 '@S9S_MB_2U_LIB.S9S_MB_2U(SCH_1):I3C_SPD_DDREFGH_CPU1_BMC_R_SCL':
 C_SIGNAL='@s9s_mb_2u_lib.s9s_mb_2u(sch_1):i3c_spd_ddrefgh_cpu1_bmc_r_scl';
NODE_NAME     R599 1
 '@S9S_MB_2U_LIB.S9S_MB_2U(SCH_1):PAGE228_I317@PURE_QUANTA.Q_RES(CHIPS)':
 'A': CDS_PINID='A';
NODE_NAME     J41 OA11
 '@S9S_MB_2U_LIB.S9S_MB_2U(SCH_1):PAGE227_I173@PURE_QUANTA.SCONN168_ME1016810202011(CHIPS)':
 'REFCLKN3': CDS_PINID='REFCLKN3';
NET_NAME
'I3C_SPD_DDREFGH_CPU1_BMC_R_SDA'
 '@S9S_MB_2U_LIB.S9S_MB_2U(SCH_1):I3C_SPD_DDREFGH_CPU1_BMC_R_SDA':
 C_SIGNAL='@s9s_mb_2u_lib.s9s_mb_2u(sch_1):i3c_spd_ddrefgh_cpu1_bmc_r_sda';
NODE_NAME     R600 1
 '@S9S_MB_2U_LIB.S9S_MB_2U(SCH_1):PAGE228_I318@PURE_QUANTA.Q_RES(CHIPS)':
 'A': CDS_PINID='A';
NODE_NAME     J41 OA12
 '@S9S_MB_2U_LIB.S9S_MB_2U(SCH_1):PAGE227_I173@PURE_QUANTA.SCONN168_ME1016810202011(CHIPS)':
 'REFCLKP3': CDS_PINID='REFCLKP3';
NET_NAME
'I3C_SPD_DDREFGH_CPU1_BMC_SCL'
 '@S9S_MB_2U_LIB.S9S_MB_2U(SCH_1):I3C_SPD_DDREFGH_CPU1_BMC_SCL':
 C_SIGNAL='@s9s_mb_2u_lib.s9s_mb_2u(sch_1):i3c_spd_ddrefgh_cpu1_bmc_scl';
NODE_NAME     R599 2
 '@S9S_MB_2U_LIB.S9S_MB_2U(SCH_1):PAGE228_I317@PURE_QUANTA.Q_RES(CHIPS)':
 'B': CDS_PINID='B';
NODE_NAME     U14 10
 '@S9S_MB_2U_LIB.S9S_MB_2U(SCH_1):PAGE218_I12@PURE_QUANTA.QS3VH257QG8(CHIPS)':
 'I1C': CDS_PINID='I1C';
NET_NAME
'I3C_SPD_DDREFGH_CPU1_BMC_SDA'
 '@S9S_MB_2U_LIB.S9S_MB_2U(SCH_1):I3C_SPD_DDREFGH_CPU1_BMC_SDA':
 C_SIGNAL='@s9s_mb_2u_lib.s9s_mb_2u(sch_1):i3c_spd_ddrefgh_cpu1_bmc_sda';
NODE_NAME     R600 2
 '@S9S_MB_2U_LIB.S9S_MB_2U(SCH_1):PAGE228_I318@PURE_QUANTA.Q_RES(CHIPS)':
 'B': CDS_PINID='B';
NODE_NAME     U14 13
 '@S9S_MB_2U_LIB.S9S_MB_2U(SCH_1):PAGE218_I12@PURE_QUANTA.QS3VH257QG8(CHIPS)':
 'I1D': CDS_PINID='I1D';
NET_NAME
'I3C_SPD_DDREFGH_CPU1_LVC1_R_SCL'
 '@S9S_MB_2U_LIB.S9S_MB_2U(SCH_1):I3C_SPD_DDREFGH_CPU1_LVC1_R_SCL':
 C_SIGNAL='@s9s_mb_2u_lib.s9s_mb_2u(sch_1):i3c_spd_ddrefgh_cpu1_lvc1_r_scl';
NODE_NAME     U14 9
 '@S9S_MB_2U_LIB.S9S_MB_2U(SCH_1):PAGE218_I12@PURE_QUANTA.QS3VH257QG8(CHIPS)':
 'YC': CDS_PINID='YC';
NODE_NAME     R667 2
 '@S9S_MB_2U_LIB.S9S_MB_2U(SCH_1):PAGE218_I21@PURE_QUANTA.Q_RES(CHIPS)':
 'B': CDS_PINID='B';
NODE_NAME     R676 1
 '@S9S_MB_2U_LIB.S9S_MB_2U(SCH_1):PAGE218_I35@PURE_QUANTA.Q_RES(CHIPS)':
 'A': CDS_PINID='A';
NET_NAME
'I3C_SPD_DDREFGH_CPU1_LVC1_R_SDA'
 '@S9S_MB_2U_LIB.S9S_MB_2U(SCH_1):I3C_SPD_DDREFGH_CPU1_LVC1_R_SDA':
 C_SIGNAL='@s9s_mb_2u_lib.s9s_mb_2u(sch_1):i3c_spd_ddrefgh_cpu1_lvc1_r_sda';
NODE_NAME     U14 12
 '@S9S_MB_2U_LIB.S9S_MB_2U(SCH_1):PAGE218_I12@PURE_QUANTA.QS3VH257QG8(CHIPS)':
 'YD': CDS_PINID='YD';
NODE_NAME     R668 2
 '@S9S_MB_2U_LIB.S9S_MB_2U(SCH_1):PAGE218_I20@PURE_QUANTA.Q_RES(CHIPS)':
 'B': CDS_PINID='B';
NODE_NAME     R677 1
 '@S9S_MB_2U_LIB.S9S_MB_2U(SCH_1):PAGE218_I34@PURE_QUANTA.Q_RES(CHIPS)':
 'A': CDS_PINID='A';
NET_NAME
'I3C_SPD_DDREFGH_CPU1_LVC1_SCL'
 '@S9S_MB_2U_LIB.S9S_MB_2U(SCH_1):I3C_SPD_DDREFGH_CPU1_LVC1_SCL':
 C_SIGNAL='@s9s_mb_2u_lib.s9s_mb_2u(sch_1):i3c_spd_ddrefgh_cpu1_lvc1_scl';
NODE_NAME     R3899 2
 '@S9S_MB_2U_LIB.S9S_MB_2U(SCH_1):PAGE106_I183@PURE_QUANTA.Q_RES(CHIPS)':
 'B': CDS_PINID='B';
NODE_NAME     R3900 2
 '@S9S_MB_2U_LIB.S9S_MB_2U(SCH_1):PAGE107_I183@PURE_QUANTA.Q_RES(CHIPS)':
 'B': CDS_PINID='B';
NODE_NAME     R3901 2
 '@S9S_MB_2U_LIB.S9S_MB_2U(SCH_1):PAGE108_I182@PURE_QUANTA.Q_RES(CHIPS)':
 'B': CDS_PINID='B';
NODE_NAME     R3902 2
 '@S9S_MB_2U_LIB.S9S_MB_2U(SCH_1):PAGE109_I180@PURE_QUANTA.Q_RES(CHIPS)':
 'B': CDS_PINID='B';
NODE_NAME     R3903 2
 '@S9S_MB_2U_LIB.S9S_MB_2U(SCH_1):PAGE110_I182@PURE_QUANTA.Q_RES(CHIPS)':
 'B': CDS_PINID='B';
NODE_NAME     R3904 2
 '@S9S_MB_2U_LIB.S9S_MB_2U(SCH_1):PAGE111_I182@PURE_QUANTA.Q_RES(CHIPS)':
 'B': CDS_PINID='B';
NODE_NAME     R3905 2
 '@S9S_MB_2U_LIB.S9S_MB_2U(SCH_1):PAGE112_I183@PURE_QUANTA.Q_RES(CHIPS)':
 'B': CDS_PINID='B';
NODE_NAME     R3906 2
 '@S9S_MB_2U_LIB.S9S_MB_2U(SCH_1):PAGE113_I182@PURE_QUANTA.Q_RES(CHIPS)':
 'B': CDS_PINID='B';
NODE_NAME     R676 2
 '@S9S_MB_2U_LIB.S9S_MB_2U(SCH_1):PAGE218_I35@PURE_QUANTA.Q_RES(CHIPS)':
 'B': CDS_PINID='B';
NET_NAME
'I3C_SPD_DDREFGH_CPU1_LVC1_SCL_1'
 '@S9S_MB_2U_LIB.S9S_MB_2U(SCH_1):I3C_SPD_DDREFGH_CPU1_LVC1_SCL_R2':
 C_SIGNAL='@s9s_mb_2u_lib.s9s_mb_2u(sch_1):i3c_spd_ddrefgh_cpu1_lvc1_scl_r2';
NODE_NAME     J26 4
 '@S9S_MB_2U_LIB.S9S_MB_2U(SCH_1):PAGE107_I180@PURE_QUANTA.SCONN288_ADR50017P087CC(CHIPS)':
 'HSCL': CDS_PINID='HSCL';
NODE_NAME     R3900 1
 '@S9S_MB_2U_LIB.S9S_MB_2U(SCH_1):PAGE107_I183@PURE_QUANTA.Q_RES(CHIPS)':
 'A': CDS_PINID='A';
NET_NAME
'I3C_SPD_DDREFGH_CPU1_LVC1_SCL_2'
 '@S9S_MB_2U_LIB.S9S_MB_2U(SCH_1):I3C_SPD_DDREFGH_CPU1_LVC1_SCL_R3':
 C_SIGNAL='@s9s_mb_2u_lib.s9s_mb_2u(sch_1):i3c_spd_ddrefgh_cpu1_lvc1_scl_r3';
NODE_NAME     J27 4
 '@S9S_MB_2U_LIB.S9S_MB_2U(SCH_1):PAGE108_I179@PURE_QUANTA.SCONN288_ADR50017P130CC(CHIPS)':
 'HSCL': CDS_PINID='HSCL';
NODE_NAME     R3901 1
 '@S9S_MB_2U_LIB.S9S_MB_2U(SCH_1):PAGE108_I182@PURE_QUANTA.Q_RES(CHIPS)':
 'A': CDS_PINID='A';
NET_NAME
'I3C_SPD_DDREFGH_CPU1_LVC1_SCL_3'
 '@S9S_MB_2U_LIB.S9S_MB_2U(SCH_1):I3C_SPD_DDREFGH_CPU1_LVC1_SCL_R4':
 C_SIGNAL='@s9s_mb_2u_lib.s9s_mb_2u(sch_1):i3c_spd_ddrefgh_cpu1_lvc1_scl_r4';
NODE_NAME     J28 4
 '@S9S_MB_2U_LIB.S9S_MB_2U(SCH_1):PAGE109_I47@PURE_QUANTA.SCONN288_ADR50017P087CC(CHIPS)':
 'HSCL': CDS_PINID='HSCL';
NODE_NAME     R3902 1
 '@S9S_MB_2U_LIB.S9S_MB_2U(SCH_1):PAGE109_I180@PURE_QUANTA.Q_RES(CHIPS)':
 'A': CDS_PINID='A';
NET_NAME
'I3C_SPD_DDREFGH_CPU1_LVC1_SCL_4'
 '@S9S_MB_2U_LIB.S9S_MB_2U(SCH_1):I3C_SPD_DDREFGH_CPU1_LVC1_SCL_R5':
 C_SIGNAL='@s9s_mb_2u_lib.s9s_mb_2u(sch_1):i3c_spd_ddrefgh_cpu1_lvc1_scl_r5';
NODE_NAME     J29 4
 '@S9S_MB_2U_LIB.S9S_MB_2U(SCH_1):PAGE110_I179@PURE_QUANTA.SCONN288_ADR50017P130CC(CHIPS)':
 'HSCL': CDS_PINID='HSCL';
NODE_NAME     R3903 1
 '@S9S_MB_2U_LIB.S9S_MB_2U(SCH_1):PAGE110_I182@PURE_QUANTA.Q_RES(CHIPS)':
 'A': CDS_PINID='A';
NET_NAME
'I3C_SPD_DDREFGH_CPU1_LVC1_SCL_5'
 '@S9S_MB_2U_LIB.S9S_MB_2U(SCH_1):I3C_SPD_DDREFGH_CPU1_LVC1_SCL_R6':
 C_SIGNAL='@s9s_mb_2u_lib.s9s_mb_2u(sch_1):i3c_spd_ddrefgh_cpu1_lvc1_scl_r6';
NODE_NAME     J30 4
 '@S9S_MB_2U_LIB.S9S_MB_2U(SCH_1):PAGE111_I179@PURE_QUANTA.SCONN288_ADR50017P087CC(CHIPS)':
 'HSCL': CDS_PINID='HSCL';
NODE_NAME     R3904 1
 '@S9S_MB_2U_LIB.S9S_MB_2U(SCH_1):PAGE111_I182@PURE_QUANTA.Q_RES(CHIPS)':
 'A': CDS_PINID='A';
NET_NAME
'I3C_SPD_DDREFGH_CPU1_LVC1_SCL_6'
 '@S9S_MB_2U_LIB.S9S_MB_2U(SCH_1):I3C_SPD_DDREFGH_CPU1_LVC1_SCL_R7':
 C_SIGNAL='@s9s_mb_2u_lib.s9s_mb_2u(sch_1):i3c_spd_ddrefgh_cpu1_lvc1_scl_r7';
NODE_NAME     J31 4
 '@S9S_MB_2U_LIB.S9S_MB_2U(SCH_1):PAGE112_I180@PURE_QUANTA.SCONN288_ADR50017P130CC(CHIPS)':
 'HSCL': CDS_PINID='HSCL';
NODE_NAME     R3905 1
 '@S9S_MB_2U_LIB.S9S_MB_2U(SCH_1):PAGE112_I183@PURE_QUANTA.Q_RES(CHIPS)':
 'A': CDS_PINID='A';
NET_NAME
'I3C_SPD_DDREFGH_CPU1_LVC1_SCL_7'
 '@S9S_MB_2U_LIB.S9S_MB_2U(SCH_1):I3C_SPD_DDREFGH_CPU1_LVC1_SCL_R8':
 C_SIGNAL='@s9s_mb_2u_lib.s9s_mb_2u(sch_1):i3c_spd_ddrefgh_cpu1_lvc1_scl_r8';
NODE_NAME     J32 4
 '@S9S_MB_2U_LIB.S9S_MB_2U(SCH_1):PAGE113_I179@PURE_QUANTA.SCONN288_ADR50017P087CC(CHIPS)':
 'HSCL': CDS_PINID='HSCL';
NODE_NAME     R3906 1
 '@S9S_MB_2U_LIB.S9S_MB_2U(SCH_1):PAGE113_I182@PURE_QUANTA.Q_RES(CHIPS)':
 'A': CDS_PINID='A';
NET_NAME
'I3C_SPD_DDREFGH_CPU1_LVC1_SCL_R'
 '@S9S_MB_2U_LIB.S9S_MB_2U(SCH_1):I3C_SPD_DDREFGH_CPU1_LVC1_SCL_R1':
 C_SIGNAL='@s9s_mb_2u_lib.s9s_mb_2u(sch_1):i3c_spd_ddrefgh_cpu1_lvc1_scl_r1';
NODE_NAME     J25 4
 '@S9S_MB_2U_LIB.S9S_MB_2U(SCH_1):PAGE106_I180@PURE_QUANTA.SCONN288_ADR50017P130CC(CHIPS)':
 'HSCL': CDS_PINID='HSCL';
NODE_NAME     R3899 1
 '@S9S_MB_2U_LIB.S9S_MB_2U(SCH_1):PAGE106_I183@PURE_QUANTA.Q_RES(CHIPS)':
 'A': CDS_PINID='A';
NET_NAME
'I3C_SPD_DDREFGH_CPU1_LVC1_SDA'
 '@S9S_MB_2U_LIB.S9S_MB_2U(SCH_1):I3C_SPD_DDREFGH_CPU1_LVC1_SDA':
 C_SIGNAL='@s9s_mb_2u_lib.s9s_mb_2u(sch_1):i3c_spd_ddrefgh_cpu1_lvc1_sda';
NODE_NAME     J25 5
 '@S9S_MB_2U_LIB.S9S_MB_2U(SCH_1):PAGE106_I180@PURE_QUANTA.SCONN288_ADR50017P130CC(CHIPS)':
 'HSDA': CDS_PINID='HSDA';
NODE_NAME     J26 5
 '@S9S_MB_2U_LIB.S9S_MB_2U(SCH_1):PAGE107_I180@PURE_QUANTA.SCONN288_ADR50017P087CC(CHIPS)':
 'HSDA': CDS_PINID='HSDA';
NODE_NAME     J27 5
 '@S9S_MB_2U_LIB.S9S_MB_2U(SCH_1):PAGE108_I179@PURE_QUANTA.SCONN288_ADR50017P130CC(CHIPS)':
 'HSDA': CDS_PINID='HSDA';
NODE_NAME     J28 5
 '@S9S_MB_2U_LIB.S9S_MB_2U(SCH_1):PAGE109_I47@PURE_QUANTA.SCONN288_ADR50017P087CC(CHIPS)':
 'HSDA': CDS_PINID='HSDA';
NODE_NAME     J29 5
 '@S9S_MB_2U_LIB.S9S_MB_2U(SCH_1):PAGE110_I179@PURE_QUANTA.SCONN288_ADR50017P130CC(CHIPS)':
 'HSDA': CDS_PINID='HSDA';
NODE_NAME     J30 5
 '@S9S_MB_2U_LIB.S9S_MB_2U(SCH_1):PAGE111_I179@PURE_QUANTA.SCONN288_ADR50017P087CC(CHIPS)':
 'HSDA': CDS_PINID='HSDA';
NODE_NAME     J31 5
 '@S9S_MB_2U_LIB.S9S_MB_2U(SCH_1):PAGE112_I180@PURE_QUANTA.SCONN288_ADR50017P130CC(CHIPS)':
 'HSDA': CDS_PINID='HSDA';
NODE_NAME     J32 5
 '@S9S_MB_2U_LIB.S9S_MB_2U(SCH_1):PAGE113_I179@PURE_QUANTA.SCONN288_ADR50017P087CC(CHIPS)':
 'HSDA': CDS_PINID='HSDA';
NODE_NAME     R677 2
 '@S9S_MB_2U_LIB.S9S_MB_2U(SCH_1):PAGE218_I34@PURE_QUANTA.Q_RES(CHIPS)':
 'B': CDS_PINID='B';
NET_NAME
'I3C_SPD_DDREFGH_CPU1_R_SCL'
 '@S9S_MB_2U_LIB.S9S_MB_2U(SCH_1):I3C_SPD_DDREFGH_CPU1_R_SCL':
 C_SIGNAL='@s9s_mb_2u_lib.s9s_mb_2u(sch_1):i3c_spd_ddrefgh_cpu1_r_scl';
NODE_NAME     R672 2
 '@S9S_MB_2U_LIB.S9S_MB_2U(SCH_1):PAGE218_I30@PURE_QUANTA.Q_RES(CHIPS)':
 'B': CDS_PINID='B';
NODE_NAME     U14 11
 '@S9S_MB_2U_LIB.S9S_MB_2U(SCH_1):PAGE218_I12@PURE_QUANTA.QS3VH257QG8(CHIPS)':
 'I0C': CDS_PINID='I0C';
NODE_NAME     R667 1
 '@S9S_MB_2U_LIB.S9S_MB_2U(SCH_1):PAGE218_I21@PURE_QUANTA.Q_RES(CHIPS)':
 'A': CDS_PINID='A';
NET_NAME
'I3C_SPD_DDREFGH_CPU1_R_SDA'
 '@S9S_MB_2U_LIB.S9S_MB_2U(SCH_1):I3C_SPD_DDREFGH_CPU1_R_SDA':
 C_SIGNAL='@s9s_mb_2u_lib.s9s_mb_2u(sch_1):i3c_spd_ddrefgh_cpu1_r_sda';
NODE_NAME     R673 2
 '@S9S_MB_2U_LIB.S9S_MB_2U(SCH_1):PAGE218_I31@PURE_QUANTA.Q_RES(CHIPS)':
 'B': CDS_PINID='B';
NODE_NAME     U14 14
 '@S9S_MB_2U_LIB.S9S_MB_2U(SCH_1):PAGE218_I12@PURE_QUANTA.QS3VH257QG8(CHIPS)':
 'I0D': CDS_PINID='I0D';
NODE_NAME     R668 1
 '@S9S_MB_2U_LIB.S9S_MB_2U(SCH_1):PAGE218_I20@PURE_QUANTA.Q_RES(CHIPS)':
 'A': CDS_PINID='A';
NET_NAME
'I3C_SPD_DDREFGH_CPU1_SCL'
 '@S9S_MB_2U_LIB.S9S_MB_2U(SCH_1):I3C_SPD_DDREFGH_CPU1_SCL':
 C_SIGNAL='@s9s_mb_2u_lib.s9s_mb_2u(sch_1):i3c_spd_ddrefgh_cpu1_scl';
NODE_NAME     U1 CU17
 '@S9S_MB_2U_LIB.S9S_MB_2U(SCH_1):PAGE44_I51@PURE_QUANTA.SOCKET4677_AZIF0045P001C01CS(CHIPS)':
 'DDR4567_SPDSCL': CDS_PINID='DDR4567_SPDSCL';
NODE_NAME     R664 2
 '@S9S_MB_2U_LIB.S9S_MB_2U(SCH_1):PAGE218_I28@PURE_QUANTA.Q_RES(CHIPS)':
 'B': CDS_PINID='B';
NODE_NAME     R672 1
 '@S9S_MB_2U_LIB.S9S_MB_2U(SCH_1):PAGE218_I30@PURE_QUANTA.Q_RES(CHIPS)':
 'A': CDS_PINID='A';
NET_NAME
'I3C_SPD_DDREFGH_CPU1_SDA'
 '@S9S_MB_2U_LIB.S9S_MB_2U(SCH_1):I3C_SPD_DDREFGH_CPU1_SDA':
 C_SIGNAL='@s9s_mb_2u_lib.s9s_mb_2u(sch_1):i3c_spd_ddrefgh_cpu1_sda';
NODE_NAME     U1 CT18
 '@S9S_MB_2U_LIB.S9S_MB_2U(SCH_1):PAGE44_I51@PURE_QUANTA.SOCKET4677_AZIF0045P001C01CS(CHIPS)':
 'DDR4567_SPDSDA': CDS_PINID='DDR4567_SPDSDA';
NODE_NAME     R673 1
 '@S9S_MB_2U_LIB.S9S_MB_2U(SCH_1):PAGE218_I31@PURE_QUANTA.Q_RES(CHIPS)':
 'A': CDS_PINID='A';
NODE_NAME     R669 2
 '@S9S_MB_2U_LIB.S9S_MB_2U(SCH_1):PAGE218_I29@PURE_QUANTA.Q_RES(CHIPS)':
 'B': CDS_PINID='B';
NET_NAME
'INA230_1_A0'
 '@S9S_MB_2U_LIB.S9S_MB_2U(SCH_1):INA230_1_A0':
 C_SIGNAL='@s9s_mb_2u_lib.s9s_mb_2u(sch_1):ina230_1_a0';
NODE_NAME     U266 2
 '@S9S_MB_2U_LIB.S9S_MB_2U(SCH_1):PAGE295_I30@PURE_QUANTA.INA230AIRGTR(CHIPS)':
 'A0': CDS_PINID='A0';
NODE_NAME     R3617 2
 '@S9S_MB_2U_LIB.S9S_MB_2U(SCH_1):PAGE295_I40@PURE_QUANTA.Q_RES(CHIPS)':
 'B': CDS_PINID='B';
NODE_NAME     R3627 2
 '@S9S_MB_2U_LIB.S9S_MB_2U(SCH_1):PAGE295_I89@PURE_QUANTA.Q_RES(CHIPS)':
 'B': CDS_PINID='B';
NET_NAME
'INA230_1_A1'
 '@S9S_MB_2U_LIB.S9S_MB_2U(SCH_1):INA230_1_A1':
 C_SIGNAL='@s9s_mb_2u_lib.s9s_mb_2u(sch_1):ina230_1_a1';
NODE_NAME     U266 1
 '@S9S_MB_2U_LIB.S9S_MB_2U(SCH_1):PAGE295_I30@PURE_QUANTA.INA230AIRGTR(CHIPS)':
 'A1': CDS_PINID='A1';
NODE_NAME     R3616 2
 '@S9S_MB_2U_LIB.S9S_MB_2U(SCH_1):PAGE295_I31@PURE_QUANTA.Q_RES(CHIPS)':
 'B': CDS_PINID='B';
NODE_NAME     R3628 2
 '@S9S_MB_2U_LIB.S9S_MB_2U(SCH_1):PAGE295_I88@PURE_QUANTA.Q_RES(CHIPS)':
 'B': CDS_PINID='B';
NET_NAME
'INA230_2_A0'
 '@S9S_MB_2U_LIB.S9S_MB_2U(SCH_1):INA230_2_A0':
 C_SIGNAL='@s9s_mb_2u_lib.s9s_mb_2u(sch_1):ina230_2_a0';
NODE_NAME     U276 2
 '@S9S_MB_2U_LIB.S9S_MB_2U(SCH_1):PAGE295_I129@PURE_QUANTA.INA230AIRGTR(CHIPS)':
 'A0': CDS_PINID='A0';
NODE_NAME     R3764 2
 '@S9S_MB_2U_LIB.S9S_MB_2U(SCH_1):PAGE295_I135@PURE_QUANTA.Q_RES(CHIPS)':
 'B': CDS_PINID='B';
NODE_NAME     R3751 1
 '@S9S_MB_2U_LIB.S9S_MB_2U(SCH_1):PAGE295_I146@PURE_QUANTA.Q_RES(CHIPS)':
 'A': CDS_PINID='A';
NET_NAME
'INA230_2_A1'
 '@S9S_MB_2U_LIB.S9S_MB_2U(SCH_1):INA230_2_A1':
 C_SIGNAL='@s9s_mb_2u_lib.s9s_mb_2u(sch_1):ina230_2_a1';
NODE_NAME     U276 1
 '@S9S_MB_2U_LIB.S9S_MB_2U(SCH_1):PAGE295_I129@PURE_QUANTA.INA230AIRGTR(CHIPS)':
 'A1': CDS_PINID='A1';
NODE_NAME     R3763 2
 '@S9S_MB_2U_LIB.S9S_MB_2U(SCH_1):PAGE295_I136@PURE_QUANTA.Q_RES(CHIPS)':
 'B': CDS_PINID='B';
NET_NAME
'INA230_3_A0'
 '@S9S_MB_2U_LIB.S9S_MB_2U(SCH_1):INA230_3_A0':
 C_SIGNAL='@s9s_mb_2u_lib.s9s_mb_2u(sch_1):ina230_3_a0';
NODE_NAME     U263 2
 '@S9S_MB_2U_LIB.S9S_MB_2U(SCH_1):PAGE163_I94@PURE_QUANTA.INA230AIRGTR(CHIPS)':
 'A0': CDS_PINID='A0';
NODE_NAME     R3620 1
 '@S9S_MB_2U_LIB.S9S_MB_2U(SCH_1):PAGE163_I100@PURE_QUANTA.Q_RES(CHIPS)':
 'A': CDS_PINID='A';
NODE_NAME     R3609 2
 '@S9S_MB_2U_LIB.S9S_MB_2U(SCH_1):PAGE163_I104@PURE_QUANTA.Q_RES(CHIPS)':
 'B': CDS_PINID='B';
NET_NAME
'INA230_3_A1'
 '@S9S_MB_2U_LIB.S9S_MB_2U(SCH_1):INA230_3_A1':
 C_SIGNAL='@s9s_mb_2u_lib.s9s_mb_2u(sch_1):ina230_3_a1';
NODE_NAME     U263 1
 '@S9S_MB_2U_LIB.S9S_MB_2U(SCH_1):PAGE163_I94@PURE_QUANTA.INA230AIRGTR(CHIPS)':
 'A1': CDS_PINID='A1';
NODE_NAME     R3608 2
 '@S9S_MB_2U_LIB.S9S_MB_2U(SCH_1):PAGE163_I103@PURE_QUANTA.Q_RES(CHIPS)':
 'B': CDS_PINID='B';
NET_NAME
'INA230_4_A0'
 '@S9S_MB_2U_LIB.S9S_MB_2U(SCH_1):INA230_4_A0':
 C_SIGNAL='@s9s_mb_2u_lib.s9s_mb_2u(sch_1):ina230_4_a0';
NODE_NAME     R3611 2
 '@S9S_MB_2U_LIB.S9S_MB_2U(SCH_1):PAGE163_I36@PURE_QUANTA.Q_RES(CHIPS)':
 'B': CDS_PINID='B';
NODE_NAME     U264 2
 '@S9S_MB_2U_LIB.S9S_MB_2U(SCH_1):PAGE163_I46@PURE_QUANTA.INA230AIRGTR(CHIPS)':
 'A0': CDS_PINID='A0';
NODE_NAME     R3621 2
 '@S9S_MB_2U_LIB.S9S_MB_2U(SCH_1):PAGE163_I87@PURE_QUANTA.Q_RES(CHIPS)':
 'B': CDS_PINID='B';
NET_NAME
'INA230_4_A1'
 '@S9S_MB_2U_LIB.S9S_MB_2U(SCH_1):INA230_4_A1':
 C_SIGNAL='@s9s_mb_2u_lib.s9s_mb_2u(sch_1):ina230_4_a1';
NODE_NAME     R3610 2
 '@S9S_MB_2U_LIB.S9S_MB_2U(SCH_1):PAGE163_I45@PURE_QUANTA.Q_RES(CHIPS)':
 'B': CDS_PINID='B';
NODE_NAME     U264 1
 '@S9S_MB_2U_LIB.S9S_MB_2U(SCH_1):PAGE163_I46@PURE_QUANTA.INA230AIRGTR(CHIPS)':
 'A1': CDS_PINID='A1';
NODE_NAME     R3623 2
 '@S9S_MB_2U_LIB.S9S_MB_2U(SCH_1):PAGE163_I86@PURE_QUANTA.Q_RES(CHIPS)':
 'B': CDS_PINID='B';
NET_NAME
'INA230_5_A0'
 '@S9S_MB_2U_LIB.S9S_MB_2U(SCH_1):INA230_5_A0':
 C_SIGNAL='@s9s_mb_2u_lib.s9s_mb_2u(sch_1):ina230_5_a0';
NODE_NAME     R3613 2
 '@S9S_MB_2U_LIB.S9S_MB_2U(SCH_1):PAGE163_I59@PURE_QUANTA.Q_RES(CHIPS)':
 'B': CDS_PINID='B';
NODE_NAME     U265 2
 '@S9S_MB_2U_LIB.S9S_MB_2U(SCH_1):PAGE163_I69@PURE_QUANTA.INA230AIRGTR(CHIPS)':
 'A0': CDS_PINID='A0';
NODE_NAME     R3622 2
 '@S9S_MB_2U_LIB.S9S_MB_2U(SCH_1):PAGE163_I90@PURE_QUANTA.Q_RES(CHIPS)':
 'B': CDS_PINID='B';
NET_NAME
'INA230_5_A1'
 '@S9S_MB_2U_LIB.S9S_MB_2U(SCH_1):INA230_5_A1':
 C_SIGNAL='@s9s_mb_2u_lib.s9s_mb_2u(sch_1):ina230_5_a1';
NODE_NAME     R3612 2
 '@S9S_MB_2U_LIB.S9S_MB_2U(SCH_1):PAGE163_I68@PURE_QUANTA.Q_RES(CHIPS)':
 'B': CDS_PINID='B';
NODE_NAME     U265 1
 '@S9S_MB_2U_LIB.S9S_MB_2U(SCH_1):PAGE163_I69@PURE_QUANTA.INA230AIRGTR(CHIPS)':
 'A1': CDS_PINID='A1';
NODE_NAME     R3624 2
 '@S9S_MB_2U_LIB.S9S_MB_2U(SCH_1):PAGE163_I89@PURE_QUANTA.Q_RES(CHIPS)':
 'B': CDS_PINID='B';
NET_NAME
'IND_P0_CPL1'
 '@S9S_MB_2U_LIB.S9S_MB_2U(SCH_1):IND_P0_CPL1':
 C_SIGNAL='@s9s_mb_2u_lib.s9s_mb_2u(sch_1):ind_p0_cpl1';
NODE_NAME     PL114 2
 '@S9S_MB_2U_LIB.S9S_MB_2U(SCH_1):PAGE253_I46@PURE_QUANTA.Q_INDUCTOR4P_14(CHIPS)':
 '2': CDS_PINID='\2\';
NODE_NAME     PL9 3
 '@S9S_MB_2U_LIB.S9S_MB_2U(SCH_1):PAGE255_I32@PURE_QUANTA.Q_INDUCTOR4P_14(CHIPS)':
 '3': CDS_PINID='\3\';
NET_NAME
'IND_P0_CPL2'
 '@S9S_MB_2U_LIB.S9S_MB_2U(SCH_1):IND_P0_CPL2':
 C_SIGNAL='@s9s_mb_2u_lib.s9s_mb_2u(sch_1):ind_p0_cpl2';
NODE_NAME     PL114 3
 '@S9S_MB_2U_LIB.S9S_MB_2U(SCH_1):PAGE253_I46@PURE_QUANTA.Q_INDUCTOR4P_14(CHIPS)':
 '3': CDS_PINID='\3\';
NODE_NAME     PL13 2
 '@S9S_MB_2U_LIB.S9S_MB_2U(SCH_1):PAGE253_I21@PURE_QUANTA.Q_INDUCTOR4P_14(CHIPS)':
 '2': CDS_PINID='\2\';
NET_NAME
'IND_P0_CPL3'
 '@S9S_MB_2U_LIB.S9S_MB_2U(SCH_1):IND_P0_CPL3':
 C_SIGNAL='@s9s_mb_2u_lib.s9s_mb_2u(sch_1):ind_p0_cpl3';
NODE_NAME     PL112 2
 '@S9S_MB_2U_LIB.S9S_MB_2U(SCH_1):PAGE254_I50@PURE_QUANTA.Q_INDUCTOR4P_14(CHIPS)':
 '2': CDS_PINID='\2\';
NODE_NAME     PL13 3
 '@S9S_MB_2U_LIB.S9S_MB_2U(SCH_1):PAGE253_I21@PURE_QUANTA.Q_INDUCTOR4P_14(CHIPS)':
 '3': CDS_PINID='\3\';
NET_NAME
'IND_P0_CPL4'
 '@S9S_MB_2U_LIB.S9S_MB_2U(SCH_1):IND_P0_CPL4':
 C_SIGNAL='@s9s_mb_2u_lib.s9s_mb_2u(sch_1):ind_p0_cpl4';
NODE_NAME     PL112 3
 '@S9S_MB_2U_LIB.S9S_MB_2U(SCH_1):PAGE254_I50@PURE_QUANTA.Q_INDUCTOR4P_14(CHIPS)':
 '3': CDS_PINID='\3\';
NODE_NAME     PL11 2
 '@S9S_MB_2U_LIB.S9S_MB_2U(SCH_1):PAGE254_I33@PURE_QUANTA.Q_INDUCTOR4P_14(CHIPS)':
 '2': CDS_PINID='\2\';
NET_NAME
'IND_P0_CPL5'
 '@S9S_MB_2U_LIB.S9S_MB_2U(SCH_1):IND_P0_CPL5':
 C_SIGNAL='@s9s_mb_2u_lib.s9s_mb_2u(sch_1):ind_p0_cpl5';
NODE_NAME     PL11 3
 '@S9S_MB_2U_LIB.S9S_MB_2U(SCH_1):PAGE254_I33@PURE_QUANTA.Q_INDUCTOR4P_14(CHIPS)':
 '3': CDS_PINID='\3\';
NODE_NAME     PL10 2
 '@S9S_MB_2U_LIB.S9S_MB_2U(SCH_1):PAGE255_I50@PURE_QUANTA.Q_INDUCTOR4P_14(CHIPS)':
 '2': CDS_PINID='\2\';
NET_NAME
'IND_P0_CPL6'
 '@S9S_MB_2U_LIB.S9S_MB_2U(SCH_1):IND_P0_CPL6':
 C_SIGNAL='@s9s_mb_2u_lib.s9s_mb_2u(sch_1):ind_p0_cpl6';
NODE_NAME     PL9 2
 '@S9S_MB_2U_LIB.S9S_MB_2U(SCH_1):PAGE255_I32@PURE_QUANTA.Q_INDUCTOR4P_14(CHIPS)':
 '2': CDS_PINID='\2\';
NODE_NAME     PL8 3
 '@S9S_MB_2U_LIB.S9S_MB_2U(SCH_1):PAGE256_I58@PURE_QUANTA.Q_INDUCTOR4P_14(CHIPS)':
 '3': CDS_PINID='\3\';
NET_NAME
'IND_P0_CPL7'
 '@S9S_MB_2U_LIB.S9S_MB_2U(SCH_1):IND_P0_CPL7':
 C_SIGNAL='@s9s_mb_2u_lib.s9s_mb_2u(sch_1):ind_p0_cpl7';
NODE_NAME     PL105 1
 '@S9S_MB_2U_LIB.S9S_MB_2U(SCH_1):PAGE256_I39@PURE_QUANTA.Q_INDUCTOR(CHIPS)':
 '1': CDS_PINID='\1\';
NODE_NAME     PL8 2
 '@S9S_MB_2U_LIB.S9S_MB_2U(SCH_1):PAGE256_I58@PURE_QUANTA.Q_INDUCTOR4P_14(CHIPS)':
 '2': CDS_PINID='\2\';
NET_NAME
'IND_P0_CPL8'
 '@S9S_MB_2U_LIB.S9S_MB_2U(SCH_1):IND_P0_CPL8':
 C_SIGNAL='@s9s_mb_2u_lib.s9s_mb_2u(sch_1):ind_p0_cpl8';
NODE_NAME     PL10 3
 '@S9S_MB_2U_LIB.S9S_MB_2U(SCH_1):PAGE255_I50@PURE_QUANTA.Q_INDUCTOR4P_14(CHIPS)':
 '3': CDS_PINID='\3\';
NODE_NAME     PL7 2
 '@S9S_MB_2U_LIB.S9S_MB_2U(SCH_1):PAGE256_I44@PURE_QUANTA.Q_INDUCTOR4P_14(CHIPS)':
 '2': CDS_PINID='\2\';
NET_NAME
'IND_P1_CPL1'
 '@S9S_MB_2U_LIB.S9S_MB_2U(SCH_1):IND_P1_CPL1':
 C_SIGNAL='@s9s_mb_2u_lib.s9s_mb_2u(sch_1):ind_p1_cpl1';
NODE_NAME     PL31 2
 '@S9S_MB_2U_LIB.S9S_MB_2U(SCH_1):PAGE271_I74@PURE_QUANTA.Q_INDUCTOR4P_14(CHIPS)':
 '2': CDS_PINID='\2\';
NODE_NAME     PL30 3
 '@S9S_MB_2U_LIB.S9S_MB_2U(SCH_1):PAGE271_I18@PURE_QUANTA.Q_INDUCTOR4P_14(CHIPS)':
 '3': CDS_PINID='\3\';
NET_NAME
'IND_P1_CPL2'
 '@S9S_MB_2U_LIB.S9S_MB_2U(SCH_1):IND_P1_CPL2':
 C_SIGNAL='@s9s_mb_2u_lib.s9s_mb_2u(sch_1):ind_p1_cpl2';
NODE_NAME     PL29 3
 '@S9S_MB_2U_LIB.S9S_MB_2U(SCH_1):PAGE272_I51@PURE_QUANTA.Q_INDUCTOR4P_14(CHIPS)':
 '3': CDS_PINID='\3\';
NODE_NAME     PL30 2
 '@S9S_MB_2U_LIB.S9S_MB_2U(SCH_1):PAGE271_I18@PURE_QUANTA.Q_INDUCTOR4P_14(CHIPS)':
 '2': CDS_PINID='\2\';
NET_NAME
'IND_P1_CPL3'
 '@S9S_MB_2U_LIB.S9S_MB_2U(SCH_1):IND_P1_CPL3':
 C_SIGNAL='@s9s_mb_2u_lib.s9s_mb_2u(sch_1):ind_p1_cpl3';
NODE_NAME     PL28 3
 '@S9S_MB_2U_LIB.S9S_MB_2U(SCH_1):PAGE272_I37@PURE_QUANTA.Q_INDUCTOR4P_14(CHIPS)':
 '3': CDS_PINID='\3\';
NODE_NAME     PL29 2
 '@S9S_MB_2U_LIB.S9S_MB_2U(SCH_1):PAGE272_I51@PURE_QUANTA.Q_INDUCTOR4P_14(CHIPS)':
 '2': CDS_PINID='\2\';
NET_NAME
'IND_P1_CPL4'
 '@S9S_MB_2U_LIB.S9S_MB_2U(SCH_1):IND_P1_CPL4':
 C_SIGNAL='@s9s_mb_2u_lib.s9s_mb_2u(sch_1):ind_p1_cpl4';
NODE_NAME     PL27 3
 '@S9S_MB_2U_LIB.S9S_MB_2U(SCH_1):PAGE273_I48@PURE_QUANTA.Q_INDUCTOR4P_14(CHIPS)':
 '3': CDS_PINID='\3\';
NODE_NAME     PL28 2
 '@S9S_MB_2U_LIB.S9S_MB_2U(SCH_1):PAGE272_I37@PURE_QUANTA.Q_INDUCTOR4P_14(CHIPS)':
 '2': CDS_PINID='\2\';
NET_NAME
'IND_P1_CPL5'
 '@S9S_MB_2U_LIB.S9S_MB_2U(SCH_1):IND_P1_CPL5':
 C_SIGNAL='@s9s_mb_2u_lib.s9s_mb_2u(sch_1):ind_p1_cpl5';
NODE_NAME     PL27 2
 '@S9S_MB_2U_LIB.S9S_MB_2U(SCH_1):PAGE273_I48@PURE_QUANTA.Q_INDUCTOR4P_14(CHIPS)':
 '2': CDS_PINID='\2\';
NODE_NAME     PL24 3
 '@S9S_MB_2U_LIB.S9S_MB_2U(SCH_1):PAGE274_I43@PURE_QUANTA.Q_INDUCTOR4P_14(CHIPS)':
 '3': CDS_PINID='\3\';
NET_NAME
'IND_P1_CPL6'
 '@S9S_MB_2U_LIB.S9S_MB_2U(SCH_1):IND_P1_CPL6':
 C_SIGNAL='@s9s_mb_2u_lib.s9s_mb_2u(sch_1):ind_p1_cpl6';
NODE_NAME     PL31 3
 '@S9S_MB_2U_LIB.S9S_MB_2U(SCH_1):PAGE271_I74@PURE_QUANTA.Q_INDUCTOR4P_14(CHIPS)':
 '3': CDS_PINID='\3\';
NODE_NAME     PL26 2
 '@S9S_MB_2U_LIB.S9S_MB_2U(SCH_1):PAGE273_I28@PURE_QUANTA.Q_INDUCTOR4P_14(CHIPS)':
 '2': CDS_PINID='\2\';
NET_NAME
'IND_P1_CPL7'
 '@S9S_MB_2U_LIB.S9S_MB_2U(SCH_1):IND_P1_CPL7':
 C_SIGNAL='@s9s_mb_2u_lib.s9s_mb_2u(sch_1):ind_p1_cpl7';
NODE_NAME     PL26 3
 '@S9S_MB_2U_LIB.S9S_MB_2U(SCH_1):PAGE273_I28@PURE_QUANTA.Q_INDUCTOR4P_14(CHIPS)':
 '3': CDS_PINID='\3\';
NODE_NAME     PL25 2
 '@S9S_MB_2U_LIB.S9S_MB_2U(SCH_1):PAGE274_I58@PURE_QUANTA.Q_INDUCTOR4P_14(CHIPS)':
 '2': CDS_PINID='\2\';
NET_NAME
'IND_P1_CPL8'
 '@S9S_MB_2U_LIB.S9S_MB_2U(SCH_1):IND_P1_CPL8':
 C_SIGNAL='@s9s_mb_2u_lib.s9s_mb_2u(sch_1):ind_p1_cpl8';
NODE_NAME     PL24 2
 '@S9S_MB_2U_LIB.S9S_MB_2U(SCH_1):PAGE274_I43@PURE_QUANTA.Q_INDUCTOR4P_14(CHIPS)':
 '2': CDS_PINID='\2\';
NODE_NAME     PL106 1
 '@S9S_MB_2U_LIB.S9S_MB_2U(SCH_1):PAGE274_I23@PURE_QUANTA.Q_INDUCTOR(CHIPS)':
 '1': CDS_PINID='\1\';
NET_NAME
'IRQ0_A57'
 '@S9S_MB_2U_LIB.S9S_MB_2U(SCH_1):IRQ0_A57':
 C_SIGNAL='@s9s_mb_2u_lib.s9s_mb_2u(sch_1):irq0_a57';
NODE_NAME     R506 2
 '@S9S_MB_2U_LIB.S9S_MB_2U(SCH_1):PAGE227_I18@PURE_QUANTA.Q_RES(CHIPS)':
 'B': CDS_PINID='B';
NODE_NAME     J41 A56
 '@S9S_MB_2U_LIB.S9S_MB_2U(SCH_1):PAGE227_I173@PURE_QUANTA.SCONN168_ME1016810202011(CHIPS)':
 'PERN12': CDS_PINID='PERN12';
NET_NAME
'IRQ_BMC_CPU_NMI_R1'
 '@S9S_MB_2U_LIB.S9S_MB_2U(SCH_1):IRQ_BMC_CPU_NMI_R1':
 C_SIGNAL='@s9s_mb_2u_lib.s9s_mb_2u(sch_1):irq_bmc_cpu_nmi_r1';
NODE_NAME     U249 U13
 '@S9S_MB_2U_LIB.S9S_MB_2U(SCH_1):PAGE312_I1@PURE_QUANTA.LCMXO3LF9400C5BG484C(CHIPS)':
 'PB29D': CDS_PINID='PB29D';
NODE_NAME     R1465 2
 '@S9S_MB_2U_LIB.S9S_MB_2U(SCH_1):PAGE312_I3@PURE_QUANTA.Q_RES(CHIPS)':
 'B': CDS_PINID='B';
NET_NAME
'IRQ_BMC_PCH_NMI'
 '@S9S_MB_2U_LIB.S9S_MB_2U(SCH_1):IRQ_BMC_PCH_NMI':
 C_SIGNAL='@s9s_mb_2u_lib.s9s_mb_2u(sch_1):irq_bmc_pch_nmi';
NODE_NAME     U4 BF13
 '@S9S_MB_2U_LIB.S9S_MB_2U(SCH_1):PAGE175_I93@PURE_QUANTA.EMMITSBURG_REV0P9(CHIPS)':
 'GPPC_A_17_SRCCLKREQ_N_7': CDS_PINID='GPPC_A_17_SRCCLKREQ_N_7';
NODE_NAME     R1268 2
 '@S9S_MB_2U_LIB.S9S_MB_2U(SCH_1):PAGE175_I222@PURE_QUANTA.Q_RES(CHIPS)':
 'B': CDS_PINID='B';
NODE_NAME     R1269 1
 '@S9S_MB_2U_LIB.S9S_MB_2U(SCH_1):PAGE175_I225@PURE_QUANTA.Q_RES(CHIPS)':
 'A': CDS_PINID='A';
NET_NAME
'IRQ_BMC_PCH_NMI_R'
 '@S9S_MB_2U_LIB.S9S_MB_2U(SCH_1):IRQ_BMC_PCH_NMI_R':
 C_SIGNAL='@s9s_mb_2u_lib.s9s_mb_2u(sch_1):irq_bmc_pch_nmi_r';
NODE_NAME     R1268 1
 '@S9S_MB_2U_LIB.S9S_MB_2U(SCH_1):PAGE175_I222@PURE_QUANTA.Q_RES(CHIPS)':
 'A': CDS_PINID='A';
NODE_NAME     U249 AB4
 '@S9S_MB_2U_LIB.S9S_MB_2U(SCH_1):PAGE312_I1@PURE_QUANTA.LCMXO3LF9400C5BG484C(CHIPS)':
 'PB8B': CDS_PINID='PB8B';
NET_NAME
'IRQ_ESPI_LPC_SERIRQ_ALERT_N'
 '@S9S_MB_2U_LIB.S9S_MB_2U(SCH_1):IRQ_ESPI_LPC_SERIRQ_ALERT_N':
 C_SIGNAL='@s9s_mb_2u_lib.s9s_mb_2u(sch_1):irq_espi_lpc_serirq_alert_n';
NODE_NAME     U60 4
 '@S9S_MB_2U_LIB.S9S_MB_2U(SCH_1):PAGE190_I34@PURE_QUANTA.NC7SB3157(CHIPS)':
 'A': CDS_PINID='A';
NODE_NAME     R1215 1
 '@S9S_MB_2U_LIB.S9S_MB_2U(SCH_1):PAGE190_I38@PURE_QUANTA.Q_RES(CHIPS)':
 'A': CDS_PINID='A';
NET_NAME
'IRQ_ESPI_LPC_SERIRQ_ALERT_R_N'
 '@S9S_MB_2U_LIB.S9S_MB_2U(SCH_1):IRQ_ESPI_LPC_SERIRQ_ALERT_R_N':
 C_SIGNAL='@s9s_mb_2u_lib.s9s_mb_2u(sch_1):irq_espi_lpc_serirq_alert_r_n';
NODE_NAME     R1215 2
 '@S9S_MB_2U_LIB.S9S_MB_2U(SCH_1):PAGE190_I38@PURE_QUANTA.Q_RES(CHIPS)':
 'B': CDS_PINID='B';
NODE_NAME     J41 B3
 '@S9S_MB_2U_LIB.S9S_MB_2U(SCH_1):PAGE227_I173@PURE_QUANTA.SCONN168_ME1016810202011(CHIPS)':
 '+12V_EDGE_B3': CDS_PINID='\+12v_edge_b3\';
NET_NAME
'IRQ_HSC_FAULT_N'
 '@S9S_MB_2U_LIB.S9S_MB_2U(SCH_1):IRQ_HSC_FAULT_N':
 C_SIGNAL='@s9s_mb_2u_lib.s9s_mb_2u(sch_1):irq_hsc_fault_n';
NODE_NAME     R3043 1
 '@S9S_MB_2U_LIB.S9S_MB_2U(SCH_1):PAGE314_I111@PURE_QUANTA.Q_RES(CHIPS)':
 'A': CDS_PINID='A';
NODE_NAME     R2588 2
 '@S9S_MB_2U_LIB.S9S_MB_2U(SCH_1):PAGE303_I81@PURE_QUANTA.Q_RES(CHIPS)':
 'B': CDS_PINID='B';
NODE_NAME     PJ42 13
 '@S9S_MB_2U_LIB.S9S_MB_2U(SCH_1):PAGE327_I34@PURE_QUANTA.SCONN21_9193031121LF(CHIPS)':
 '13': CDS_PINID='\13\';
NODE_NAME     R2587 2
 '@S9S_MB_2U_LIB.S9S_MB_2U(SCH_1):PAGE303_I93@PURE_QUANTA.Q_RES(CHIPS)':
 'B': CDS_PINID='B';
NET_NAME
'IRQ_HSC_FAULT_R1_N'
 '@S9S_MB_2U_LIB.S9S_MB_2U(SCH_1):IRQ_HSC_FAULT_R1_N':
 C_SIGNAL='@s9s_mb_2u_lib.s9s_mb_2u(sch_1):irq_hsc_fault_r1_n';
NODE_NAME     R3043 2
 '@S9S_MB_2U_LIB.S9S_MB_2U(SCH_1):PAGE314_I111@PURE_QUANTA.Q_RES(CHIPS)':
 'B': CDS_PINID='B';
NODE_NAME     U249 B5
 '@S9S_MB_2U_LIB.S9S_MB_2U(SCH_1):PAGE314_I188@PURE_QUANTA.LCMXO3LF9400C5BG484C(CHIPS)':
 'PT13A': CDS_PINID='PT13A';
NET_NAME
'IRQ_LPC_PIRQA_N_ESPI_ALERT0_N'
 '@S9S_MB_2U_LIB.S9S_MB_2U(SCH_1):IRQ_LPC_PIRQA_N_ESPI_ALERT0_N':
 C_SIGNAL='@s9s_mb_2u_lib.s9s_mb_2u(sch_1):irq_lpc_pirqa_n_espi_alert0_n';
NODE_NAME     U4 BG20
 '@S9S_MB_2U_LIB.S9S_MB_2U(SCH_1):PAGE175_I93@PURE_QUANTA.EMMITSBURG_REV0P9(CHIPS)':
 'GPPC_A_0_ESPI_ALERT0_N': CDS_PINID='GPPC_A_0_ESPI_ALERT0_N';
NODE_NAME     R1214 1
 '@S9S_MB_2U_LIB.S9S_MB_2U(SCH_1):PAGE190_I33@PURE_QUANTA.Q_RES(CHIPS)':
 'A': CDS_PINID='A';
NODE_NAME     R1253 2
 '@S9S_MB_2U_LIB.S9S_MB_2U(SCH_1):PAGE192_I23@PURE_QUANTA.Q_RES(CHIPS)':
 'B': CDS_PINID='B';
NET_NAME
'IRQ_LPC_PIRQA_N_ESPI_ALERT0_R_N'
 '@S9S_MB_2U_LIB.S9S_MB_2U(SCH_1):IRQ_LPC_PIRQA_N_ESPI_ALERT0_R_N':
 C_SIGNAL='@s9s_mb_2u_lib.s9s_mb_2u(sch_1):irq_lpc_pirqa_n_espi_alert0_r_n';
NODE_NAME     R1214 2
 '@S9S_MB_2U_LIB.S9S_MB_2U(SCH_1):PAGE190_I33@PURE_QUANTA.Q_RES(CHIPS)':
 'B': CDS_PINID='B';
NODE_NAME     U60 1
 '@S9S_MB_2U_LIB.S9S_MB_2U(SCH_1):PAGE190_I34@PURE_QUANTA.NC7SB3157(CHIPS)':
 'B1': CDS_PINID='B1';
NET_NAME
'IRQ_LPC_SERIRQ_ESPI_CS1_N'
 '@S9S_MB_2U_LIB.S9S_MB_2U(SCH_1):IRQ_LPC_SERIRQ_ESPI_CS1_N':
 C_SIGNAL='@s9s_mb_2u_lib.s9s_mb_2u(sch_1):irq_lpc_serirq_espi_cs1_n';
NODE_NAME     U4 BE16
 '@S9S_MB_2U_LIB.S9S_MB_2U(SCH_1):PAGE175_I93@PURE_QUANTA.EMMITSBURG_REV0P9(CHIPS)':
 'GPPC_A_7_ESPI_CS1_N': CDS_PINID='GPPC_A_7_ESPI_CS1_N';
NODE_NAME     R1254 2
 '@S9S_MB_2U_LIB.S9S_MB_2U(SCH_1):PAGE192_I24@PURE_QUANTA.Q_RES(CHIPS)':
 'B': CDS_PINID='B';
NODE_NAME     R4118 1
 '@S9S_MB_2U_LIB.S9S_MB_2U(SCH_1):PAGE190_I105@PURE_QUANTA.Q_RES(CHIPS)':
 'A': CDS_PINID='A';
NET_NAME
'IRQ_LPC_SERIRQ_ESPI_CS1_R_N'
 '@S9S_MB_2U_LIB.S9S_MB_2U(SCH_1):IRQ_LPC_SERIRQ_ESPI_CS1_R_N':
 C_SIGNAL='@s9s_mb_2u_lib.s9s_mb_2u(sch_1):irq_lpc_serirq_espi_cs1_r_n';
NODE_NAME     U60 3
 '@S9S_MB_2U_LIB.S9S_MB_2U(SCH_1):PAGE190_I34@PURE_QUANTA.NC7SB3157(CHIPS)':
 'B0': CDS_PINID='B0';
NODE_NAME     R4118 2
 '@S9S_MB_2U_LIB.S9S_MB_2U(SCH_1):PAGE190_I105@PURE_QUANTA.Q_RES(CHIPS)':
 'B': CDS_PINID='B';
NET_NAME
'IRQ_LVC3_OCP_SFF_WAKE_N'
 '@S9S_MB_2U_LIB.S9S_MB_2U(SCH_1):IRQ_LVC3_OCP_SFF_WAKE_N':
 C_SIGNAL='@s9s_mb_2u_lib.s9s_mb_2u(sch_1):irq_lvc3_ocp_sff_wake_n';
NODE_NAME     R1824 2
 '@S9S_MB_2U_LIB.S9S_MB_2U(SCH_1):PAGE152_I62@PURE_QUANTA.Q_RES(CHIPS)':
 'B': CDS_PINID='B';
NODE_NAME     J37 OA3
 '@S9S_MB_2U_LIB.S9S_MB_2U(SCH_1):PAGE150_I199@PURE_QUANTA.SCONN168_ME1016810202011(CHIPS)':
 'WAKE#': CDS_PINID='\wake#\';
NODE_NAME     U82 2
 '@S9S_MB_2U_LIB.S9S_MB_2U(SCH_1):PAGE152_I79@PURE_QUANTA.74LVC1G126SE7(CHIPS)':
 'A': CDS_PINID='A';
NET_NAME
'IRQ_LVC3_OCP_V3_2_WAKE_N'
 '@S9S_MB_2U_LIB.S9S_MB_2U(SCH_1):IRQ_LVC3_OCP_V3_2_WAKE_N':
 C_SIGNAL='@s9s_mb_2u_lib.s9s_mb_2u(sch_1):irq_lvc3_ocp_v3_2_wake_n';
NODE_NAME     R3182 2
 '@S9S_MB_2U_LIB.S9S_MB_2U(SCH_1):PAGE156_I6@PURE_QUANTA.Q_RES(CHIPS)':
 'B': CDS_PINID='B';
NODE_NAME     J35 OA3
 '@S9S_MB_2U_LIB.S9S_MB_2U(SCH_1):PAGE146_I303@PURE_QUANTA.SCONN168_ME1016810202011(CHIPS)':
 'WAKE#': CDS_PINID='\wake#\';
NODE_NAME     U217 2
 '@S9S_MB_2U_LIB.S9S_MB_2U(SCH_1):PAGE156_I79@PURE_QUANTA.74LVC1G126SE7(CHIPS)':
 'A': CDS_PINID='A';
NET_NAME
'IRQ_LVC3_V3_2_WAKE_BUF_N'
 '@S9S_MB_2U_LIB.S9S_MB_2U(SCH_1):IRQ_LVC3_V3_2_WAKE_BUF_N':
 C_SIGNAL='@s9s_mb_2u_lib.s9s_mb_2u(sch_1):irq_lvc3_v3_2_wake_buf_n';
NODE_NAME     R3193 1
 '@S9S_MB_2U_LIB.S9S_MB_2U(SCH_1):PAGE156_I55@PURE_QUANTA.Q_RES(CHIPS)':
 'A': CDS_PINID='A';
NODE_NAME     R3192 2
 '@S9S_MB_2U_LIB.S9S_MB_2U(SCH_1):PAGE156_I59@PURE_QUANTA.Q_RES(CHIPS)':
 'B': CDS_PINID='B';
NODE_NAME     U219 4
 '@S9S_MB_2U_LIB.S9S_MB_2U(SCH_1):PAGE156_I61@PURE_QUANTA.74LVC1G07GV(CHIPS)':
 'Y': CDS_PINID='Y';
NET_NAME
'IRQ_LVC3_WAKE_BUF_N'
 '@S9S_MB_2U_LIB.S9S_MB_2U(SCH_1):IRQ_LVC3_WAKE_BUF_N':
 C_SIGNAL='@s9s_mb_2u_lib.s9s_mb_2u(sch_1):irq_lvc3_wake_buf_n';
NODE_NAME     U157 4
 '@S9S_MB_2U_LIB.S9S_MB_2U(SCH_1):PAGE152_I65@PURE_QUANTA.74LVC1G07GV(CHIPS)':
 'Y': CDS_PINID='Y';
NODE_NAME     R2487 2
 '@S9S_MB_2U_LIB.S9S_MB_2U(SCH_1):PAGE152_I71@PURE_QUANTA.Q_RES(CHIPS)':
 'B': CDS_PINID='B';
NODE_NAME     R2489 1
 '@S9S_MB_2U_LIB.S9S_MB_2U(SCH_1):PAGE152_I75@PURE_QUANTA.Q_RES(CHIPS)':
 'A': CDS_PINID='A';
NET_NAME
'IRQ_LVC3_WAKE_N'
 '@S9S_MB_2U_LIB.S9S_MB_2U(SCH_1):IRQ_LVC3_WAKE_N':
 C_SIGNAL='@s9s_mb_2u_lib.s9s_mb_2u(sch_1):irq_lvc3_wake_n';
NODE_NAME     R2489 2
 '@S9S_MB_2U_LIB.S9S_MB_2U(SCH_1):PAGE152_I75@PURE_QUANTA.Q_RES(CHIPS)':
 'B': CDS_PINID='B';
NODE_NAME     U4 AH11
 '@S9S_MB_2U_LIB.S9S_MB_2U(SCH_1):PAGE174_I36@PURE_QUANTA.EMMITSBURG_REV0P9(CHIPS)':
 'WAKE_N': CDS_PINID='WAKE_N';
NODE_NAME     R3193 2
 '@S9S_MB_2U_LIB.S9S_MB_2U(SCH_1):PAGE156_I55@PURE_QUANTA.Q_RES(CHIPS)':
 'B': CDS_PINID='B';
NODE_NAME     R3301 1
 '@S9S_MB_2U_LIB.S9S_MB_2U(SCH_1):PAGE182_I299@PURE_QUANTA.Q_RES(CHIPS)':
 'A': CDS_PINID='A';
NODE_NAME     R494 2
 '@S9S_MB_2U_LIB.S9S_MB_2U(SCH_1):PAGE174_I98@PURE_QUANTA.Q_RES(CHIPS)':
 'B': CDS_PINID='B';
NET_NAME
'IRQ_PCH_CPU_NMI_EVENT_N'
 '@S9S_MB_2U_LIB.S9S_MB_2U(SCH_1):IRQ_PCH_CPU_NMI_EVENT_N':
 C_SIGNAL='@s9s_mb_2u_lib.s9s_mb_2u(sch_1):irq_pch_cpu_nmi_event_n';
NODE_NAME     R1310 2
 '@S9S_MB_2U_LIB.S9S_MB_2U(SCH_1):PAGE193_I20@PURE_QUANTA.Q_RES(CHIPS)':
 'B': CDS_PINID='B';
NODE_NAME     U249 V13
 '@S9S_MB_2U_LIB.S9S_MB_2U(SCH_1):PAGE312_I1@PURE_QUANTA.LCMXO3LF9400C5BG484C(CHIPS)':
 'PB29C': CDS_PINID='PB29C';
NET_NAME
'IRQ_PCH_CPU_NMI_EVENT_R_N'
 '@S9S_MB_2U_LIB.S9S_MB_2U(SCH_1):IRQ_PCH_CPU_NMI_EVENT_R_N':
 C_SIGNAL='@s9s_mb_2u_lib.s9s_mb_2u(sch_1):irq_pch_cpu_nmi_event_r_n';
NODE_NAME     U4 AP15
 '@S9S_MB_2U_LIB.S9S_MB_2U(SCH_1):PAGE177_I27@PURE_QUANTA.EMMITSBURG_REV0P9(CHIPS)':
 'GPPC_S_8_NMI_N': CDS_PINID='GPPC_S_8_NMI_N';
NODE_NAME     R1459 2
 '@S9S_MB_2U_LIB.S9S_MB_2U(SCH_1):PAGE192_I51@PURE_QUANTA.Q_RES(CHIPS)':
 'B': CDS_PINID='B';
NODE_NAME     R1310 1
 '@S9S_MB_2U_LIB.S9S_MB_2U(SCH_1):PAGE193_I20@PURE_QUANTA.Q_RES(CHIPS)':
 'A': CDS_PINID='A';
NET_NAME
'IRQ_PCH_SCI_WHEA_N'
 '@S9S_MB_2U_LIB.S9S_MB_2U(SCH_1):IRQ_PCH_SCI_WHEA_N':
 C_SIGNAL='@s9s_mb_2u_lib.s9s_mb_2u(sch_1):irq_pch_sci_whea_n';
NODE_NAME     U4 AB2
 '@S9S_MB_2U_LIB.S9S_MB_2U(SCH_1):PAGE175_I93@PURE_QUANTA.EMMITSBURG_REV0P9(CHIPS)':
 'GPP_D_10_BM_BUSY_N_SX_EXIT_HOLDOFF_N': CDS_PINID='GPP_D_10_BM_BUSY_N_SX_EXIT_HOLDOFF_N';
NODE_NAME     R3040 2
 '@S9S_MB_2U_LIB.S9S_MB_2U(SCH_1):PAGE192_I1@PURE_QUANTA.Q_RES(CHIPS)':
 'B': CDS_PINID='B';
NODE_NAME     R1944 2
 '@S9S_MB_2U_LIB.S9S_MB_2U(SCH_1):PAGE312_I170@PURE_QUANTA.Q_RES(CHIPS)':
 'B': CDS_PINID='B';
NET_NAME
'IRQ_PCH_SCI_WHEA_R_N'
 '@S9S_MB_2U_LIB.S9S_MB_2U(SCH_1):IRQ_PCH_SCI_WHEA_R_N':
 C_SIGNAL='@s9s_mb_2u_lib.s9s_mb_2u(sch_1):irq_pch_sci_whea_r_n';
NODE_NAME     U249 W13
 '@S9S_MB_2U_LIB.S9S_MB_2U(SCH_1):PAGE312_I1@PURE_QUANTA.LCMXO3LF9400C5BG484C(CHIPS)':
 'PB30D': CDS_PINID='PB30D';
NODE_NAME     R1944 1
 '@S9S_MB_2U_LIB.S9S_MB_2U(SCH_1):PAGE312_I170@PURE_QUANTA.Q_RES(CHIPS)':
 'A': CDS_PINID='A';
NET_NAME
'IRQ_PSU_ALERT_R_N'
 '@S9S_MB_2U_LIB.S9S_MB_2U(SCH_1):IRQ_PSU_ALERT_R_N':
 C_SIGNAL='@s9s_mb_2u_lib.s9s_mb_2u(sch_1):irq_psu_alert_r_n';
NODE_NAME     U249 Y13
 '@S9S_MB_2U_LIB.S9S_MB_2U(SCH_1):PAGE312_I1@PURE_QUANTA.LCMXO3LF9400C5BG484C(CHIPS)':
 'PB30C': CDS_PINID='PB30C';
NODE_NAME     R3049 2
 '@S9S_MB_2U_LIB.S9S_MB_2U(SCH_1):PAGE312_I176@PURE_QUANTA.Q_RES(CHIPS)':
 'B': CDS_PINID='B';
NET_NAME
'IRQ_PSYS_CRIT_N'
 '@S9S_MB_2U_LIB.S9S_MB_2U(SCH_1):IRQ_PSYS_CRIT_N':
 C_SIGNAL='@s9s_mb_2u_lib.s9s_mb_2u(sch_1):irq_psys_crit_n';
NODE_NAME     U249 AA12
 '@S9S_MB_2U_LIB.S9S_MB_2U(SCH_1):PAGE312_I1@PURE_QUANTA.LCMXO3LF9400C5BG484C(CHIPS)':
 'PB29B||PCLKC2_1': CDS_PINID='\pb29b||pclkc2_1\';
NODE_NAME     R2376 1
 '@S9S_MB_2U_LIB.S9S_MB_2U(SCH_1):PAGE252_I17@PURE_QUANTA.Q_RES(CHIPS)':
 'A': CDS_PINID='A';
NET_NAME
'IRQ_PVCCD_CPU0_VRHOT_LVC3_N'
 '@S9S_MB_2U_LIB.S9S_MB_2U(SCH_1):IRQ_PVCCD_CPU0_VRHOT_LVC3_N':
 C_SIGNAL='@s9s_mb_2u_lib.s9s_mb_2u(sch_1):irq_pvccd_cpu0_vrhot_lvc3_n';
NODE_NAME     R2405 2
 '@S9S_MB_2U_LIB.S9S_MB_2U(SCH_1):PAGE264_I60@PURE_QUANTA.Q_RES(CHIPS)':
 'B': CDS_PINID='B';
NODE_NAME     U249 AA4
 '@S9S_MB_2U_LIB.S9S_MB_2U(SCH_1):PAGE312_I1@PURE_QUANTA.LCMXO3LF9400C5BG484C(CHIPS)':
 'PB8A': CDS_PINID='PB8A';
NODE_NAME     R2404 2
 '@S9S_MB_2U_LIB.S9S_MB_2U(SCH_1):PAGE264_I85@PURE_QUANTA.Q_RES(CHIPS)':
 'B': CDS_PINID='B';
NET_NAME
'IRQ_PVCCD_CPU0_VRHOT_LVC3_R_N'
 '@S9S_MB_2U_LIB.S9S_MB_2U(SCH_1):IRQ_PVCCD_CPU0_VRHOT_LVC3_R_N':
 C_SIGNAL='@s9s_mb_2u_lib.s9s_mb_2u(sch_1):irq_pvccd_cpu0_vrhot_lvc3_r_n';
NODE_NAME     R2405 1
 '@S9S_MB_2U_LIB.S9S_MB_2U(SCH_1):PAGE264_I60@PURE_QUANTA.Q_RES(CHIPS)':
 'A': CDS_PINID='A';
NODE_NAME     PU35 14
 '@S9S_MB_2U_LIB.S9S_MB_2U(SCH_1):PAGE264_I53@PURE_QUANTA.ISL69260IRAZT(CHIPS)':
 'NVRHOT#': CDS_PINID='\nvrhot#\';
NET_NAME
'IRQ_PVCCD_CPU1_VRHOT_LVC3_N'
 '@S9S_MB_2U_LIB.S9S_MB_2U(SCH_1):IRQ_PVCCD_CPU1_VRHOT_LVC3_N':
 C_SIGNAL='@s9s_mb_2u_lib.s9s_mb_2u(sch_1):irq_pvccd_cpu1_vrhot_lvc3_n';
NODE_NAME     U249 AA13
 '@S9S_MB_2U_LIB.S9S_MB_2U(SCH_1):PAGE312_I1@PURE_QUANTA.LCMXO3LF9400C5BG484C(CHIPS)':
 'PB30B': CDS_PINID='PB30B';
NODE_NAME     R2557 2
 '@S9S_MB_2U_LIB.S9S_MB_2U(SCH_1):PAGE282_I58@PURE_QUANTA.Q_RES(CHIPS)':
 'B': CDS_PINID='B';
NODE_NAME     R223 2
 '@S9S_MB_2U_LIB.S9S_MB_2U(SCH_1):PAGE282_I85@PURE_QUANTA.Q_RES(CHIPS)':
 'B': CDS_PINID='B';
NET_NAME
'IRQ_PVCCD_CPU1_VRHOT_LVC3_R_N'
 '@S9S_MB_2U_LIB.S9S_MB_2U(SCH_1):IRQ_PVCCD_CPU1_VRHOT_LVC3_R_N':
 C_SIGNAL='@s9s_mb_2u_lib.s9s_mb_2u(sch_1):irq_pvccd_cpu1_vrhot_lvc3_r_n';
NODE_NAME     PU18 14
 '@S9S_MB_2U_LIB.S9S_MB_2U(SCH_1):PAGE282_I53@PURE_QUANTA.ISL69260IRAZT(CHIPS)':
 'NVRHOT#': CDS_PINID='\nvrhot#\';
NODE_NAME     R2557 1
 '@S9S_MB_2U_LIB.S9S_MB_2U(SCH_1):PAGE282_I58@PURE_QUANTA.Q_RES(CHIPS)':
 'A': CDS_PINID='A';
NET_NAME
'IRQ_PVCCFA_CPU0_VRHOT_N'
 '@S9S_MB_2U_LIB.S9S_MB_2U(SCH_1):IRQ_PVCCFA_CPU0_VRHOT_N':
 C_SIGNAL='@s9s_mb_2u_lib.s9s_mb_2u(sch_1):irq_pvccfa_cpu0_vrhot_n';
NODE_NAME     PU5 14
 '@S9S_MB_2U_LIB.S9S_MB_2U(SCH_1):PAGE260_I65@PURE_QUANTA.ISL69260IRAZT(CHIPS)':
 'NVRHOT#': CDS_PINID='\nvrhot#\';
NODE_NAME     R2597 1
 '@S9S_MB_2U_LIB.S9S_MB_2U(SCH_1):PAGE260_I78@PURE_QUANTA.Q_RES(CHIPS)':
 'A': CDS_PINID='A';
NET_NAME
'IRQ_PVCCFA_CPU0_VRHOT_R_N'
 '@S9S_MB_2U_LIB.S9S_MB_2U(SCH_1):IRQ_PVCCFA_CPU0_VRHOT_R_N':
 C_SIGNAL='@s9s_mb_2u_lib.s9s_mb_2u(sch_1):irq_pvccfa_cpu0_vrhot_r_n';
NODE_NAME     U249 J21
 '@S9S_MB_2U_LIB.S9S_MB_2U(SCH_1):PAGE313_I1@PURE_QUANTA.LCMXO3LF9400C5BG484C(CHIPS)':
 'PR12A': CDS_PINID='PR12A';
NODE_NAME     R2398 2
 '@S9S_MB_2U_LIB.S9S_MB_2U(SCH_1):PAGE260_I79@PURE_QUANTA.Q_RES(CHIPS)':
 'B': CDS_PINID='B';
NODE_NAME     R2597 2
 '@S9S_MB_2U_LIB.S9S_MB_2U(SCH_1):PAGE260_I78@PURE_QUANTA.Q_RES(CHIPS)':
 'B': CDS_PINID='B';
NET_NAME
'IRQ_PVCCFA_CPU1_VRHOT_N'
 '@S9S_MB_2U_LIB.S9S_MB_2U(SCH_1):IRQ_PVCCFA_CPU1_VRHOT_N':
 C_SIGNAL='@s9s_mb_2u_lib.s9s_mb_2u(sch_1):irq_pvccfa_cpu1_vrhot_n';
NODE_NAME     PU22 14
 '@S9S_MB_2U_LIB.S9S_MB_2U(SCH_1):PAGE278_I38@PURE_QUANTA.ISL69260IRAZT(CHIPS)':
 'NVRHOT#': CDS_PINID='\nvrhot#\';
NODE_NAME     R2574 1
 '@S9S_MB_2U_LIB.S9S_MB_2U(SCH_1):PAGE278_I70@PURE_QUANTA.Q_RES(CHIPS)':
 'A': CDS_PINID='A';
NET_NAME
'IRQ_PVCCFA_CPU1_VRHOT_R_N'
 '@S9S_MB_2U_LIB.S9S_MB_2U(SCH_1):IRQ_PVCCFA_CPU1_VRHOT_R_N':
 C_SIGNAL='@s9s_mb_2u_lib.s9s_mb_2u(sch_1):irq_pvccfa_cpu1_vrhot_r_n';
NODE_NAME     U249 J22
 '@S9S_MB_2U_LIB.S9S_MB_2U(SCH_1):PAGE313_I1@PURE_QUANTA.LCMXO3LF9400C5BG484C(CHIPS)':
 'PR12B': CDS_PINID='PR12B';
NODE_NAME     R2573 2
 '@S9S_MB_2U_LIB.S9S_MB_2U(SCH_1):PAGE278_I73@PURE_QUANTA.Q_RES(CHIPS)':
 'B': CDS_PINID='B';
NODE_NAME     R2574 2
 '@S9S_MB_2U_LIB.S9S_MB_2U(SCH_1):PAGE278_I70@PURE_QUANTA.Q_RES(CHIPS)':
 'B': CDS_PINID='B';
NET_NAME
'IRQ_PVCCIN_CPU0_VRHOT_N'
 '@S9S_MB_2U_LIB.S9S_MB_2U(SCH_1):IRQ_PVCCIN_CPU0_VRHOT_N':
 C_SIGNAL='@s9s_mb_2u_lib.s9s_mb_2u(sch_1):irq_pvccin_cpu0_vrhot_n';
NODE_NAME     PU14 18
 '@S9S_MB_2U_LIB.S9S_MB_2U(SCH_1):PAGE252_I63@PURE_QUANTA.RAA229126GNPHA0(CHIPS)':
 'NVRHOT': CDS_PINID='NVRHOT';
NODE_NAME     R4593 2
 '@S9S_MB_2U_LIB.S9S_MB_2U(SCH_1):PAGE252_I66@PURE_QUANTA.Q_RES(CHIPS)':
 'B': CDS_PINID='B';
NET_NAME
'IRQ_PVCCIN_CPU0_VRHOT_R_N'
 '@S9S_MB_2U_LIB.S9S_MB_2U(SCH_1):IRQ_PVCCIN_CPU0_VRHOT_R_N':
 C_SIGNAL='@s9s_mb_2u_lib.s9s_mb_2u(sch_1):irq_pvccin_cpu0_vrhot_r_n';
NODE_NAME     U249 T21
 '@S9S_MB_2U_LIB.S9S_MB_2U(SCH_1):PAGE313_I1@PURE_QUANTA.LCMXO3LF9400C5BG484C(CHIPS)':
 'PR21B': CDS_PINID='PR21B';
NODE_NAME     R4593 1
 '@S9S_MB_2U_LIB.S9S_MB_2U(SCH_1):PAGE252_I66@PURE_QUANTA.Q_RES(CHIPS)':
 'A': CDS_PINID='A';
NODE_NAME     R2373 2
 '@S9S_MB_2U_LIB.S9S_MB_2U(SCH_1):PAGE252_I23@PURE_QUANTA.Q_RES(CHIPS)':
 'B': CDS_PINID='B';
NET_NAME
'IRQ_PVCCIN_CPU1_VRHOT_N'
 '@S9S_MB_2U_LIB.S9S_MB_2U(SCH_1):IRQ_PVCCIN_CPU1_VRHOT_N':
 C_SIGNAL='@s9s_mb_2u_lib.s9s_mb_2u(sch_1):irq_pvccin_cpu1_vrhot_n';
NODE_NAME     R2523 2
 '@S9S_MB_2U_LIB.S9S_MB_2U(SCH_1):PAGE270_I36@PURE_QUANTA.Q_RES(CHIPS)':
 'B': CDS_PINID='B';
NODE_NAME     PU29 18
 '@S9S_MB_2U_LIB.S9S_MB_2U(SCH_1):PAGE270_I33@PURE_QUANTA.RAA229126GNPHA0(CHIPS)':
 'NVRHOT': CDS_PINID='NVRHOT';
NET_NAME
'IRQ_PVCCIN_CPU1_VRHOT_R_N'
 '@S9S_MB_2U_LIB.S9S_MB_2U(SCH_1):IRQ_PVCCIN_CPU1_VRHOT_R_N':
 C_SIGNAL='@s9s_mb_2u_lib.s9s_mb_2u(sch_1):irq_pvccin_cpu1_vrhot_r_n';
NODE_NAME     U249 P19
 '@S9S_MB_2U_LIB.S9S_MB_2U(SCH_1):PAGE313_I1@PURE_QUANTA.LCMXO3LF9400C5BG484C(CHIPS)':
 'PR21C': CDS_PINID='PR21C';
NODE_NAME     R2522 2
 '@S9S_MB_2U_LIB.S9S_MB_2U(SCH_1):PAGE270_I25@PURE_QUANTA.Q_RES(CHIPS)':
 'B': CDS_PINID='B';
NODE_NAME     R2523 1
 '@S9S_MB_2U_LIB.S9S_MB_2U(SCH_1):PAGE270_I36@PURE_QUANTA.Q_RES(CHIPS)':
 'A': CDS_PINID='A';
NET_NAME
'IRQ_SGPIO_INTR_N'
 '@S9S_MB_2U_LIB.S9S_MB_2U(SCH_1):IRQ_SGPIO_INTR_N':
 C_SIGNAL='@s9s_mb_2u_lib.s9s_mb_2u(sch_1):irq_sgpio_intr_n';
NODE_NAME     R1812 1
 '@S9S_MB_2U_LIB.S9S_MB_2U(SCH_1):PAGE211_I111@PURE_QUANTA.Q_RES(CHIPS)':
 'A': CDS_PINID='A';
NODE_NAME     J41 B40
 '@S9S_MB_2U_LIB.S9S_MB_2U(SCH_1):PAGE227_I173@PURE_QUANTA.SCONN168_ME1016810202011(CHIPS)':
 'PETP7': CDS_PINID='PETP7';
NET_NAME
'IRQ_SGPIO_INTR_N_R'
 '@S9S_MB_2U_LIB.S9S_MB_2U(SCH_1):IRQ_SGPIO_INTR_N_R':
 C_SIGNAL='@s9s_mb_2u_lib.s9s_mb_2u(sch_1):irq_sgpio_intr_n_r';
NODE_NAME     R1812 2
 '@S9S_MB_2U_LIB.S9S_MB_2U(SCH_1):PAGE211_I111@PURE_QUANTA.Q_RES(CHIPS)':
 'B': CDS_PINID='B';
NODE_NAME     U249 AB12
 '@S9S_MB_2U_LIB.S9S_MB_2U(SCH_1):PAGE312_I1@PURE_QUANTA.LCMXO3LF9400C5BG484C(CHIPS)':
 'PB29A||PCLKT2_1': CDS_PINID='\pb29a||pclkt2_1\';
NET_NAME
'IRQ_SMI_ACTIVE_BMC_N'
 '@S9S_MB_2U_LIB.S9S_MB_2U(SCH_1):IRQ_SMI_ACTIVE_BMC_N':
 C_SIGNAL='@s9s_mb_2u_lib.s9s_mb_2u(sch_1):irq_smi_active_bmc_n';
NODE_NAME     R1309 2
 '@S9S_MB_2U_LIB.S9S_MB_2U(SCH_1):PAGE193_I10@PURE_QUANTA.Q_RES(CHIPS)':
 'B': CDS_PINID='B';
NODE_NAME     R506 1
 '@S9S_MB_2U_LIB.S9S_MB_2U(SCH_1):PAGE227_I18@PURE_QUANTA.Q_RES(CHIPS)':
 'A': CDS_PINID='A';
NET_NAME
'IRQ_SMI_ACTIVE_N'
 '@S9S_MB_2U_LIB.S9S_MB_2U(SCH_1):IRQ_SMI_ACTIVE_N':
 C_SIGNAL='@s9s_mb_2u_lib.s9s_mb_2u(sch_1):irq_smi_active_n';
NODE_NAME     U4 AV18
 '@S9S_MB_2U_LIB.S9S_MB_2U(SCH_1):PAGE177_I27@PURE_QUANTA.EMMITSBURG_REV0P9(CHIPS)':
 'GPPC_S_9_SMI_N': CDS_PINID='GPPC_S_9_SMI_N';
NODE_NAME     R1458 2
 '@S9S_MB_2U_LIB.S9S_MB_2U(SCH_1):PAGE192_I50@PURE_QUANTA.Q_RES(CHIPS)':
 'B': CDS_PINID='B';
NODE_NAME     R1309 1
 '@S9S_MB_2U_LIB.S9S_MB_2U(SCH_1):PAGE193_I10@PURE_QUANTA.Q_RES(CHIPS)':
 'A': CDS_PINID='A';
NET_NAME
'IRQ_SML0_ALERT_N'
 '@S9S_MB_2U_LIB.S9S_MB_2U(SCH_1):IRQ_SML0_ALERT_N':
 C_SIGNAL='@s9s_mb_2u_lib.s9s_mb_2u(sch_1):irq_sml0_alert_n';
NODE_NAME     U4 AU2
 '@S9S_MB_2U_LIB.S9S_MB_2U(SCH_1):PAGE175_I93@PURE_QUANTA.EMMITSBURG_REV0P9(CHIPS)':
 'GPPC_C_2_ME_SML0ALERT_N': CDS_PINID='GPPC_C_2_ME_SML0ALERT_N';
NODE_NAME     R1600 1
 '@S9S_MB_2U_LIB.S9S_MB_2U(SCH_1):PAGE175_I148@PURE_QUANTA.Q_RES(CHIPS)':
 'A': CDS_PINID='A';
NODE_NAME     R1601 1
 '@S9S_MB_2U_LIB.S9S_MB_2U(SCH_1):PAGE175_I151@PURE_QUANTA.Q_RES(CHIPS)':
 'A': CDS_PINID='A';
NET_NAME
'IRQ_SML0_ALERT_R1_N'
 '@S9S_MB_2U_LIB.S9S_MB_2U(SCH_1):IRQ_SML0_ALERT_R1_N':
 C_SIGNAL='@s9s_mb_2u_lib.s9s_mb_2u(sch_1):irq_sml0_alert_r1_n';
NODE_NAME     R3103 2
 '@S9S_MB_2U_LIB.S9S_MB_2U(SCH_1):PAGE215_I28@PURE_QUANTA.Q_RES(CHIPS)':
 'B': CDS_PINID='B';
NODE_NAME     J100 4
 '@S9S_MB_2U_LIB.S9S_MB_2U(SCH_1):PAGE215_I32@PURE_QUANTA.SCONN20_513860200CV01(CHIPS)':
 '4': CDS_PINID='\4\';
NET_NAME
'IRQ_SML0_ALERT_R_N'
 '@S9S_MB_2U_LIB.S9S_MB_2U(SCH_1):IRQ_SML0_ALERT_R_N':
 C_SIGNAL='@s9s_mb_2u_lib.s9s_mb_2u(sch_1):irq_sml0_alert_r_n';
NODE_NAME     R1600 2
 '@S9S_MB_2U_LIB.S9S_MB_2U(SCH_1):PAGE175_I148@PURE_QUANTA.Q_RES(CHIPS)':
 'B': CDS_PINID='B';
NODE_NAME     R3103 1
 '@S9S_MB_2U_LIB.S9S_MB_2U(SCH_1):PAGE215_I28@PURE_QUANTA.Q_RES(CHIPS)':
 'A': CDS_PINID='A';
NODE_NAME     U249 B8
 '@S9S_MB_2U_LIB.S9S_MB_2U(SCH_1):PAGE314_I188@PURE_QUANTA.LCMXO3LF9400C5BG484C(CHIPS)':
 'PT20A': CDS_PINID='PT20A';
NET_NAME
'IRQ_SML1_PMBUS_ALERT'
 '@S9S_MB_2U_LIB.S9S_MB_2U(SCH_1):IRQ_SML1_PMBUS_ALERT':
 C_SIGNAL='@s9s_mb_2u_lib.s9s_mb_2u(sch_1):irq_sml1_pmbus_alert';
NODE_NAME     PU289 10
 '@S9S_MB_2U_LIB.S9S_MB_2U(SCH_1):PAGE303_I56@PURE_QUANTA.MP5990GMA1111Z(CHIPS)':
 'ALT#': CDS_PINID='\alt#\';
NODE_NAME     R3924 2
 '@S9S_MB_2U_LIB.S9S_MB_2U(SCH_1):PAGE303_I17@PURE_QUANTA.Q_RES(CHIPS)':
 'B': CDS_PINID='B';
NODE_NAME     R3925 1
 '@S9S_MB_2U_LIB.S9S_MB_2U(SCH_1):PAGE303_I33@PURE_QUANTA.Q_RES(CHIPS)':
 'A': CDS_PINID='A';
NET_NAME
'IRQ_SML1_PMBUS_ALERT_N'
 '@S9S_MB_2U_LIB.S9S_MB_2U(SCH_1):IRQ_SML1_PMBUS_ALERT_N':
 C_SIGNAL='@s9s_mb_2u_lib.s9s_mb_2u(sch_1):irq_sml1_pmbus_alert_n';
NODE_NAME     U4 AR4
 '@S9S_MB_2U_LIB.S9S_MB_2U(SCH_1):PAGE175_I93@PURE_QUANTA.EMMITSBURG_REV0P9(CHIPS)':
 'GPPC_C_8_ME_SML1ALERT_N': CDS_PINID='GPPC_C_8_ME_SML1ALERT_N';
NODE_NAME     R1656 1
 '@S9S_MB_2U_LIB.S9S_MB_2U(SCH_1):PAGE175_I178@PURE_QUANTA.Q_RES(CHIPS)':
 'A': CDS_PINID='A';
NODE_NAME     R1657 1
 '@S9S_MB_2U_LIB.S9S_MB_2U(SCH_1):PAGE175_I180@PURE_QUANTA.Q_RES(CHIPS)':
 'A': CDS_PINID='A';
NODE_NAME     R3051 2
 '@S9S_MB_2U_LIB.S9S_MB_2U(SCH_1):PAGE215_I2@PURE_QUANTA.Q_RES(CHIPS)':
 'B': CDS_PINID='B';
NODE_NAME     R3049 1
 '@S9S_MB_2U_LIB.S9S_MB_2U(SCH_1):PAGE312_I176@PURE_QUANTA.Q_RES(CHIPS)':
 'A': CDS_PINID='A';
NODE_NAME     R3924 1
 '@S9S_MB_2U_LIB.S9S_MB_2U(SCH_1):PAGE303_I17@PURE_QUANTA.Q_RES(CHIPS)':
 'A': CDS_PINID='A';
NODE_NAME     PJ42 20
 '@S9S_MB_2U_LIB.S9S_MB_2U(SCH_1):PAGE327_I34@PURE_QUANTA.SCONN21_9193031121LF(CHIPS)':
 '20': CDS_PINID='\20\';
NET_NAME
'IRQ_SML1_PMBUS_ALERT_R_N'
 '@S9S_MB_2U_LIB.S9S_MB_2U(SCH_1):IRQ_SML1_PMBUS_ALERT_R_N':
 C_SIGNAL='@s9s_mb_2u_lib.s9s_mb_2u(sch_1):irq_sml1_pmbus_alert_r_n';
NODE_NAME     R3051 1
 '@S9S_MB_2U_LIB.S9S_MB_2U(SCH_1):PAGE215_I2@PURE_QUANTA.Q_RES(CHIPS)':
 'A': CDS_PINID='A';
NODE_NAME     J100 8
 '@S9S_MB_2U_LIB.S9S_MB_2U(SCH_1):PAGE215_I32@PURE_QUANTA.SCONN20_513860200CV01(CHIPS)':
 '8': CDS_PINID='\8\';
NET_NAME
'IRQ_SML1_PMBUS_BMC_ALERT_N'
 '@S9S_MB_2U_LIB.S9S_MB_2U(SCH_1):IRQ_SML1_PMBUS_BMC_ALERT_N':
 C_SIGNAL='@s9s_mb_2u_lib.s9s_mb_2u(sch_1):irq_sml1_pmbus_bmc_alert_n';
NODE_NAME     R1657 2
 '@S9S_MB_2U_LIB.S9S_MB_2U(SCH_1):PAGE175_I180@PURE_QUANTA.Q_RES(CHIPS)':
 'B': CDS_PINID='B';
NODE_NAME     U249 D8
 '@S9S_MB_2U_LIB.S9S_MB_2U(SCH_1):PAGE314_I188@PURE_QUANTA.LCMXO3LF9400C5BG484C(CHIPS)':
 'PT15B': CDS_PINID='PT15B';
NET_NAME
'IRQ_SML1_PMBUS_PLD_ALERT_N'
 '@S9S_MB_2U_LIB.S9S_MB_2U(SCH_1):IRQ_SML1_PMBUS_PLD_ALERT_N':
 C_SIGNAL='@s9s_mb_2u_lib.s9s_mb_2u(sch_1):irq_sml1_pmbus_pld_alert_n';
NODE_NAME     R1656 2
 '@S9S_MB_2U_LIB.S9S_MB_2U(SCH_1):PAGE175_I178@PURE_QUANTA.Q_RES(CHIPS)':
 'B': CDS_PINID='B';
NODE_NAME     U249 A8
 '@S9S_MB_2U_LIB.S9S_MB_2U(SCH_1):PAGE314_I188@PURE_QUANTA.LCMXO3LF9400C5BG484C(CHIPS)':
 'PT20B': CDS_PINID='PT20B';
NET_NAME
'IRQ_TPM_SPI_N'
 '@S9S_MB_2U_LIB.S9S_MB_2U(SCH_1):IRQ_TPM_SPI_N':
 C_SIGNAL='@s9s_mb_2u_lib.s9s_mb_2u(sch_1):irq_tpm_spi_n';
NODE_NAME     U4 N4
 '@S9S_MB_2U_LIB.S9S_MB_2U(SCH_1):PAGE176_I22@PURE_QUANTA.EMMITSBURG_REV0P9(CHIPS)':
 'GPP_I_21': CDS_PINID='GPP_I_21';
NODE_NAME     R401 2
 '@S9S_MB_2U_LIB.S9S_MB_2U(SCH_1):PAGE192_I69@PURE_QUANTA.Q_RES(CHIPS)':
 'B': CDS_PINID='B';
NODE_NAME     U249 AB13
 '@S9S_MB_2U_LIB.S9S_MB_2U(SCH_1):PAGE312_I1@PURE_QUANTA.LCMXO3LF9400C5BG484C(CHIPS)':
 'PB30A': CDS_PINID='PB30A';
NET_NAME
'IRQ_UV_DETECT_N'
 '@S9S_MB_2U_LIB.S9S_MB_2U(SCH_1):IRQ_UV_DETECT_N':
 C_SIGNAL='@s9s_mb_2u_lib.s9s_mb_2u(sch_1):irq_uv_detect_n';
NODE_NAME     R3045 1
 '@S9S_MB_2U_LIB.S9S_MB_2U(SCH_1):PAGE312_I164@PURE_QUANTA.Q_RES(CHIPS)':
 'A': CDS_PINID='A';
NODE_NAME     U325 D
 '@S9S_MB_2U_LIB.S9S_MB_2U(SCH_1):PAGE326_I38@PURE_QUANTA.MOSFET_N(CHIPS)':
 'DRAIN': CDS_PINID='DRAIN';
NODE_NAME     R4620 2
 '@S9S_MB_2U_LIB.S9S_MB_2U(SCH_1):PAGE326_I45@PURE_QUANTA.Q_RES(CHIPS)':
 'B': CDS_PINID='B';
NODE_NAME     R4785 2
 '@S9S_MB_2U_LIB.S9S_MB_2U(SCH_1):PAGE329_I25@PURE_QUANTA.Q_RES(CHIPS)':
 'B': CDS_PINID='B';
NODE_NAME     R4783 2
 '@S9S_MB_2U_LIB.S9S_MB_2U(SCH_1):PAGE329_I27@PURE_QUANTA.Q_RES(CHIPS)':
 'B': CDS_PINID='B';
NET_NAME
'IRQ_UV_DETECT_R2_N'
 '@S9S_MB_2U_LIB.S9S_MB_2U(SCH_1):IRQ_UV_DETECT_R2_N':
 C_SIGNAL='@s9s_mb_2u_lib.s9s_mb_2u(sch_1):irq_uv_detect_r2_n';
NODE_NAME     U340 4
 '@S9S_MB_2U_LIB.S9S_MB_2U(SCH_1):PAGE329_I23@PURE_QUANTA.AP331AWG7(CHIPS)':
 'OUTPUT': CDS_PINID='OUTPUT';
NODE_NAME     R4783 1
 '@S9S_MB_2U_LIB.S9S_MB_2U(SCH_1):PAGE329_I27@PURE_QUANTA.Q_RES(CHIPS)':
 'A': CDS_PINID='A';
NODE_NAME     R4779 2
 '@S9S_MB_2U_LIB.S9S_MB_2U(SCH_1):PAGE329_I31@PURE_QUANTA.Q_RES(CHIPS)':
 'B': CDS_PINID='B';
NET_NAME
'IRQ_UV_DETECT_R_N'
 '@S9S_MB_2U_LIB.S9S_MB_2U(SCH_1):IRQ_UV_DETECT_R_N':
 C_SIGNAL='@s9s_mb_2u_lib.s9s_mb_2u(sch_1):irq_uv_detect_r_n';
NODE_NAME     U249 Y4
 '@S9S_MB_2U_LIB.S9S_MB_2U(SCH_1):PAGE312_I1@PURE_QUANTA.LCMXO3LF9400C5BG484C(CHIPS)':
 'PB7C': CDS_PINID='PB7C';
NODE_NAME     R3045 2
 '@S9S_MB_2U_LIB.S9S_MB_2U(SCH_1):PAGE312_I164@PURE_QUANTA.Q_RES(CHIPS)':
 'B': CDS_PINID='B';
NET_NAME
'JTAG_BMC_CPU_TCK'
 '@S9S_MB_2U_LIB.S9S_MB_2U(SCH_1):JTAG_BMC_CPU_TCK':
 C_SIGNAL='@s9s_mb_2u_lib.s9s_mb_2u(sch_1):jtag_bmc_cpu_tck';
NODE_NAME     U86 4
 '@S9S_MB_2U_LIB.S9S_MB_2U(SCH_1):PAGE137_I84@PURE_QUANTA.74CBTLV3126PW(CHIPS)':
 '2OE': CDS_PINID='\2oe\';
NODE_NAME     R3027 1
 '@S9S_MB_2U_LIB.S9S_MB_2U(SCH_1):PAGE137_I105@PURE_QUANTA.Q_RES(CHIPS)':
 'A': CDS_PINID='A';
NODE_NAME     U85 3
 '@S9S_MB_2U_LIB.S9S_MB_2U(SCH_1):PAGE137_I109@PURE_QUANTA.NC7SB3157(CHIPS)':
 'B0': CDS_PINID='B0';
NET_NAME
'JTAG_BMC_DBP_PREQ_N'
 '@S9S_MB_2U_LIB.S9S_MB_2U(SCH_1):JTAG_BMC_DBP_PREQ_N':
 C_SIGNAL='@s9s_mb_2u_lib.s9s_mb_2u(sch_1):jtag_bmc_dbp_preq_n';
NODE_NAME     R1383 2
 '@S9S_MB_2U_LIB.S9S_MB_2U(SCH_1):PAGE226_I1@PURE_QUANTA.Q_RES(CHIPS)':
 'B': CDS_PINID='B';
NODE_NAME     R3057 2
 '@S9S_MB_2U_LIB.S9S_MB_2U(SCH_1):PAGE226_I12@PURE_QUANTA.Q_RES(CHIPS)':
 'B': CDS_PINID='B';
NODE_NAME     R1832 1
 '@S9S_MB_2U_LIB.S9S_MB_2U(SCH_1):PAGE226_I80@PURE_QUANTA.Q_RES(CHIPS)':
 'A': CDS_PINID='A';
NODE_NAME     J41 A49
 '@S9S_MB_2U_LIB.S9S_MB_2U(SCH_1):PAGE227_I173@PURE_QUANTA.SCONN168_ME1016810202011(CHIPS)':
 'GND_A49': CDS_PINID='GND_A49';
NET_NAME
'JTAG_BMC_DBP_TCK'
 '@S9S_MB_2U_LIB.S9S_MB_2U(SCH_1):JTAG_BMC_DBP_TCK':
 C_SIGNAL='@s9s_mb_2u_lib.s9s_mb_2u(sch_1):jtag_bmc_dbp_tck';
NODE_NAME     U85 4
 '@S9S_MB_2U_LIB.S9S_MB_2U(SCH_1):PAGE137_I109@PURE_QUANTA.NC7SB3157(CHIPS)':
 'A': CDS_PINID='A';
NODE_NAME     U97 4
 '@S9S_MB_2U_LIB.S9S_MB_2U(SCH_1):PAGE226_I38@PURE_QUANTA.NX3L2267GM(CHIPS)':
 '2Y1': CDS_PINID='\2y1\';
NET_NAME
'JTAG_BMC_DBP_TDI'
 '@S9S_MB_2U_LIB.S9S_MB_2U(SCH_1):JTAG_BMC_DBP_TDI':
 C_SIGNAL='@s9s_mb_2u_lib.s9s_mb_2u(sch_1):jtag_bmc_dbp_tdi';
NODE_NAME     R1345 2
 '@S9S_MB_2U_LIB.S9S_MB_2U(SCH_1):PAGE226_I13@PURE_QUANTA.Q_RES(CHIPS)':
 'B': CDS_PINID='B';
NODE_NAME     U96 2
 '@S9S_MB_2U_LIB.S9S_MB_2U(SCH_1):PAGE226_I68@PURE_QUANTA.NX3L2267GM(CHIPS)':
 '1Y1': CDS_PINID='\1y1\';
NODE_NAME     R2507 2
 '@S9S_MB_2U_LIB.S9S_MB_2U(SCH_1):PAGE226_I88@PURE_QUANTA.Q_RES(CHIPS)':
 'B': CDS_PINID='B';
NET_NAME
'JTAG_BMC_DBP_TDI_R'
 '@S9S_MB_2U_LIB.S9S_MB_2U(SCH_1):JTAG_BMC_DBP_TDI_R':
 C_SIGNAL='@s9s_mb_2u_lib.s9s_mb_2u(sch_1):jtag_bmc_dbp_tdi_r';
NODE_NAME     R1345 1
 '@S9S_MB_2U_LIB.S9S_MB_2U(SCH_1):PAGE226_I13@PURE_QUANTA.Q_RES(CHIPS)':
 'A': CDS_PINID='A';
NODE_NAME     U84 10
 '@S9S_MB_2U_LIB.S9S_MB_2U(SCH_1):PAGE226_I18@PURE_QUANTA.GTL2014PW(CHIPS)':
 'A2': CDS_PINID='A2';
NET_NAME
'JTAG_BMC_DBP_TDO'
 '@S9S_MB_2U_LIB.S9S_MB_2U(SCH_1):JTAG_BMC_DBP_TDO':
 C_SIGNAL='@s9s_mb_2u_lib.s9s_mb_2u(sch_1):jtag_bmc_dbp_tdo';
NODE_NAME     R1380 2
 '@S9S_MB_2U_LIB.S9S_MB_2U(SCH_1):PAGE226_I31@PURE_QUANTA.Q_RES(CHIPS)':
 'B': CDS_PINID='B';
NODE_NAME     R483 2
 '@S9S_MB_2U_LIB.S9S_MB_2U(SCH_1):PAGE226_I37@PURE_QUANTA.Q_RES(CHIPS)':
 'B': CDS_PINID='B';
NODE_NAME     U96 4
 '@S9S_MB_2U_LIB.S9S_MB_2U(SCH_1):PAGE226_I68@PURE_QUANTA.NX3L2267GM(CHIPS)':
 '2Y1': CDS_PINID='\2y1\';
NET_NAME
'JTAG_BMC_DBP_TDO_R'
 '@S9S_MB_2U_LIB.S9S_MB_2U(SCH_1):JTAG_BMC_DBP_TDO_R':
 C_SIGNAL='@s9s_mb_2u_lib.s9s_mb_2u(sch_1):jtag_bmc_dbp_tdo_r';
NODE_NAME     R483 1
 '@S9S_MB_2U_LIB.S9S_MB_2U(SCH_1):PAGE226_I37@PURE_QUANTA.Q_RES(CHIPS)':
 'A': CDS_PINID='A';
NODE_NAME     U83 9
 '@S9S_MB_2U_LIB.S9S_MB_2U(SCH_1):PAGE226_I45@PURE_QUANTA.GTL2014PW(CHIPS)':
 'A3': CDS_PINID='A3';
NET_NAME
'JTAG_BMC_DBP_TMS'
 '@S9S_MB_2U_LIB.S9S_MB_2U(SCH_1):JTAG_BMC_DBP_TMS':
 C_SIGNAL='@s9s_mb_2u_lib.s9s_mb_2u(sch_1):jtag_bmc_dbp_tms';
NODE_NAME     R1184 2
 '@S9S_MB_2U_LIB.S9S_MB_2U(SCH_1):PAGE226_I14@PURE_QUANTA.Q_RES(CHIPS)':
 'B': CDS_PINID='B';
NODE_NAME     U97 2
 '@S9S_MB_2U_LIB.S9S_MB_2U(SCH_1):PAGE226_I38@PURE_QUANTA.NX3L2267GM(CHIPS)':
 '1Y1': CDS_PINID='\1y1\';
NODE_NAME     R2506 2
 '@S9S_MB_2U_LIB.S9S_MB_2U(SCH_1):PAGE226_I87@PURE_QUANTA.Q_RES(CHIPS)':
 'B': CDS_PINID='B';
NET_NAME
'JTAG_BMC_DBP_TMS_R'
 '@S9S_MB_2U_LIB.S9S_MB_2U(SCH_1):JTAG_BMC_DBP_TMS_R':
 C_SIGNAL='@s9s_mb_2u_lib.s9s_mb_2u(sch_1):jtag_bmc_dbp_tms_r';
NODE_NAME     R1184 1
 '@S9S_MB_2U_LIB.S9S_MB_2U(SCH_1):PAGE226_I14@PURE_QUANTA.Q_RES(CHIPS)':
 'A': CDS_PINID='A';
NODE_NAME     U84 9
 '@S9S_MB_2U_LIB.S9S_MB_2U(SCH_1):PAGE226_I18@PURE_QUANTA.GTL2014PW(CHIPS)':
 'A3': CDS_PINID='A3';
NET_NAME
'JTAG_BMC_PCH_TCK'
 '@S9S_MB_2U_LIB.S9S_MB_2U(SCH_1):JTAG_BMC_PCH_TCK':
 C_SIGNAL='@s9s_mb_2u_lib.s9s_mb_2u(sch_1):jtag_bmc_pch_tck';
NODE_NAME     U86 10
 '@S9S_MB_2U_LIB.S9S_MB_2U(SCH_1):PAGE137_I84@PURE_QUANTA.74CBTLV3126PW(CHIPS)':
 '3OE': CDS_PINID='\3oe\';
NODE_NAME     R3026 1
 '@S9S_MB_2U_LIB.S9S_MB_2U(SCH_1):PAGE137_I106@PURE_QUANTA.Q_RES(CHIPS)':
 'A': CDS_PINID='A';
NODE_NAME     U85 1
 '@S9S_MB_2U_LIB.S9S_MB_2U(SCH_1):PAGE137_I109@PURE_QUANTA.NC7SB3157(CHIPS)':
 'B1': CDS_PINID='B1';
NET_NAME
'JTAG_BMC_PLD_TCK'
 '@S9S_MB_2U_LIB.S9S_MB_2U(SCH_1):JTAG_BMC_PLD_TCK':
 C_SIGNAL='@s9s_mb_2u_lib.s9s_mb_2u(sch_1):jtag_bmc_pld_tck';
NODE_NAME     R806 2
 '@S9S_MB_2U_LIB.S9S_MB_2U(SCH_1):PAGE210_I54@PURE_QUANTA.Q_RES(CHIPS)':
 'B': CDS_PINID='B';
NODE_NAME     R930 1
 '@S9S_MB_2U_LIB.S9S_MB_2U(SCH_1):PAGE210_I63@PURE_QUANTA.Q_RES(CHIPS)':
 'A': CDS_PINID='A';
NODE_NAME     U97 3
 '@S9S_MB_2U_LIB.S9S_MB_2U(SCH_1):PAGE226_I38@PURE_QUANTA.NX3L2267GM(CHIPS)':
 '2Y0': CDS_PINID='\2y0\';
NODE_NAME     J43 8
 '@S9S_MB_2U_LIB.S9S_MB_2U(SCH_1):PAGE210_I79@PURE_QUANTA.CONN8_210HP1080BR1(CHIPS)':
 '8': CDS_PINID='\8\';
NET_NAME
'JTAG_BMC_PLD_TDI'
 '@S9S_MB_2U_LIB.S9S_MB_2U(SCH_1):JTAG_BMC_PLD_TDI':
 C_SIGNAL='@s9s_mb_2u_lib.s9s_mb_2u(sch_1):jtag_bmc_pld_tdi';
NODE_NAME     R803 2
 '@S9S_MB_2U_LIB.S9S_MB_2U(SCH_1):PAGE210_I19@PURE_QUANTA.Q_RES(CHIPS)':
 'B': CDS_PINID='B';
NODE_NAME     R927 2
 '@S9S_MB_2U_LIB.S9S_MB_2U(SCH_1):PAGE210_I61@PURE_QUANTA.Q_RES(CHIPS)':
 'B': CDS_PINID='B';
NODE_NAME     U96 1
 '@S9S_MB_2U_LIB.S9S_MB_2U(SCH_1):PAGE226_I68@PURE_QUANTA.NX3L2267GM(CHIPS)':
 '1Y0': CDS_PINID='\1y0\';
NODE_NAME     J43 3
 '@S9S_MB_2U_LIB.S9S_MB_2U(SCH_1):PAGE210_I79@PURE_QUANTA.CONN8_210HP1080BR1(CHIPS)':
 '3': CDS_PINID='\3\';
NET_NAME
'JTAG_BMC_PLD_TDO'
 '@S9S_MB_2U_LIB.S9S_MB_2U(SCH_1):JTAG_BMC_PLD_TDO':
 C_SIGNAL='@s9s_mb_2u_lib.s9s_mb_2u(sch_1):jtag_bmc_pld_tdo';
NODE_NAME     R804 2
 '@S9S_MB_2U_LIB.S9S_MB_2U(SCH_1):PAGE210_I20@PURE_QUANTA.Q_RES(CHIPS)':
 'B': CDS_PINID='B';
NODE_NAME     R928 2
 '@S9S_MB_2U_LIB.S9S_MB_2U(SCH_1):PAGE210_I60@PURE_QUANTA.Q_RES(CHIPS)':
 'B': CDS_PINID='B';
NODE_NAME     U96 3
 '@S9S_MB_2U_LIB.S9S_MB_2U(SCH_1):PAGE226_I68@PURE_QUANTA.NX3L2267GM(CHIPS)':
 '2Y0': CDS_PINID='\2y0\';
NODE_NAME     J43 2
 '@S9S_MB_2U_LIB.S9S_MB_2U(SCH_1):PAGE210_I79@PURE_QUANTA.CONN8_210HP1080BR1(CHIPS)':
 '2': CDS_PINID='\2\';
NET_NAME
'JTAG_BMC_PLD_TMS'
 '@S9S_MB_2U_LIB.S9S_MB_2U(SCH_1):JTAG_BMC_PLD_TMS':
 C_SIGNAL='@s9s_mb_2u_lib.s9s_mb_2u(sch_1):jtag_bmc_pld_tms';
NODE_NAME     R805 2
 '@S9S_MB_2U_LIB.S9S_MB_2U(SCH_1):PAGE210_I25@PURE_QUANTA.Q_RES(CHIPS)':
 'B': CDS_PINID='B';
NODE_NAME     R929 2
 '@S9S_MB_2U_LIB.S9S_MB_2U(SCH_1):PAGE210_I59@PURE_QUANTA.Q_RES(CHIPS)':
 'B': CDS_PINID='B';
NODE_NAME     U97 1
 '@S9S_MB_2U_LIB.S9S_MB_2U(SCH_1):PAGE226_I38@PURE_QUANTA.NX3L2267GM(CHIPS)':
 '1Y0': CDS_PINID='\1y0\';
NODE_NAME     J43 6
 '@S9S_MB_2U_LIB.S9S_MB_2U(SCH_1):PAGE210_I79@PURE_QUANTA.CONN8_210HP1080BR1(CHIPS)':
 '6': CDS_PINID='\6\';
NET_NAME
'JTAG_BMC_SW_OE'
 '@S9S_MB_2U_LIB.S9S_MB_2U(SCH_1):JTAG_BMC_SW_OE':
 C_SIGNAL='@s9s_mb_2u_lib.s9s_mb_2u(sch_1):jtag_bmc_sw_oe';
NODE_NAME     R4625 1
 '@S9S_MB_2U_LIB.S9S_MB_2U(SCH_1):PAGE314_I140@PURE_QUANTA.Q_RES(CHIPS)':
 'A': CDS_PINID='A';
NODE_NAME     R4635 1
 '@S9S_MB_2U_LIB.S9S_MB_2U(SCH_1):PAGE235_I3@PURE_QUANTA.Q_RES(CHIPS)':
 'A': CDS_PINID='A';
NODE_NAME     R4634 2
 '@S9S_MB_2U_LIB.S9S_MB_2U(SCH_1):PAGE235_I4@PURE_QUANTA.Q_RES(CHIPS)':
 'B': CDS_PINID='B';
NODE_NAME     JP16 2
 '@S9S_MB_2U_LIB.S9S_MB_2U(SCH_1):PAGE235_I13@PURE_QUANTA.CONN3_210HP1030BR1(CHIPS)':
 '2': CDS_PINID='\2\';
NODE_NAME     R4624 1
 '@S9S_MB_2U_LIB.S9S_MB_2U(SCH_1):PAGE235_I14@PURE_QUANTA.Q_RES(CHIPS)':
 'A': CDS_PINID='A';
NET_NAME
'JTAG_BMC_SW_PLD_OE'
 '@S9S_MB_2U_LIB.S9S_MB_2U(SCH_1):JTAG_BMC_SW_PLD_OE':
 C_SIGNAL='@s9s_mb_2u_lib.s9s_mb_2u(sch_1):jtag_bmc_sw_pld_oe';
NODE_NAME     R4625 2
 '@S9S_MB_2U_LIB.S9S_MB_2U(SCH_1):PAGE314_I140@PURE_QUANTA.Q_RES(CHIPS)':
 'B': CDS_PINID='B';
NODE_NAME     U249 C18
 '@S9S_MB_2U_LIB.S9S_MB_2U(SCH_1):PAGE314_I188@PURE_QUANTA.LCMXO3LF9400C5BG484C(CHIPS)':
 'PT41C': CDS_PINID='PT41C';
NET_NAME
'JTAG_BMC_SW_R_OE'
 '@S9S_MB_2U_LIB.S9S_MB_2U(SCH_1):JTAG_BMC_SW_R_OE':
 C_SIGNAL='@s9s_mb_2u_lib.s9s_mb_2u(sch_1):jtag_bmc_sw_r_oe';
NODE_NAME     R4624 2
 '@S9S_MB_2U_LIB.S9S_MB_2U(SCH_1):PAGE235_I14@PURE_QUANTA.Q_RES(CHIPS)':
 'B': CDS_PINID='B';
NODE_NAME     U327 1
 '@S9S_MB_2U_LIB.S9S_MB_2U(SCH_1):PAGE235_I19@PURE_QUANTA.74CBTLV3126PW(CHIPS)':
 '1OE': CDS_PINID='\1oe\';
NODE_NAME     U327 4
 '@S9S_MB_2U_LIB.S9S_MB_2U(SCH_1):PAGE235_I19@PURE_QUANTA.74CBTLV3126PW(CHIPS)':
 '2OE': CDS_PINID='\2oe\';
NODE_NAME     U327 10
 '@S9S_MB_2U_LIB.S9S_MB_2U(SCH_1):PAGE235_I19@PURE_QUANTA.74CBTLV3126PW(CHIPS)':
 '3OE': CDS_PINID='\3oe\';
NODE_NAME     U327 13
 '@S9S_MB_2U_LIB.S9S_MB_2U(SCH_1):PAGE235_I19@PURE_QUANTA.74CBTLV3126PW(CHIPS)':
 '4OE': CDS_PINID='\4oe\';
NET_NAME
'JTAG_BMC_SW_TCK'
 '@S9S_MB_2U_LIB.S9S_MB_2U(SCH_1):JTAG_BMC_SW_TCK':
 C_SIGNAL='@s9s_mb_2u_lib.s9s_mb_2u(sch_1):jtag_bmc_sw_tck';
NODE_NAME     U97 6
 '@S9S_MB_2U_LIB.S9S_MB_2U(SCH_1):PAGE226_I38@PURE_QUANTA.NX3L2267GM(CHIPS)':
 '2Z': CDS_PINID='\2z\';
NODE_NAME     R4633 2
 '@S9S_MB_2U_LIB.S9S_MB_2U(SCH_1):PAGE235_I24@PURE_QUANTA.Q_RES(CHIPS)':
 'B': CDS_PINID='B';
NET_NAME
'JTAG_BMC_SW_TCK_R'
 '@S9S_MB_2U_LIB.S9S_MB_2U(SCH_1):JTAG_BMC_SW_TCK_R':
 C_SIGNAL='@s9s_mb_2u_lib.s9s_mb_2u(sch_1):jtag_bmc_sw_tck_r';
NODE_NAME     U327 3
 '@S9S_MB_2U_LIB.S9S_MB_2U(SCH_1):PAGE235_I19@PURE_QUANTA.74CBTLV3126PW(CHIPS)':
 '1B': CDS_PINID='\1b\';
NODE_NAME     R4633 1
 '@S9S_MB_2U_LIB.S9S_MB_2U(SCH_1):PAGE235_I24@PURE_QUANTA.Q_RES(CHIPS)':
 'A': CDS_PINID='A';
NET_NAME
'JTAG_BMC_SW_TDI'
 '@S9S_MB_2U_LIB.S9S_MB_2U(SCH_1):JTAG_BMC_SW_TDI':
 C_SIGNAL='@s9s_mb_2u_lib.s9s_mb_2u(sch_1):jtag_bmc_sw_tdi';
NODE_NAME     U96 9
 '@S9S_MB_2U_LIB.S9S_MB_2U(SCH_1):PAGE226_I68@PURE_QUANTA.NX3L2267GM(CHIPS)':
 '1Z': CDS_PINID='\1z\';
NODE_NAME     R4631 2
 '@S9S_MB_2U_LIB.S9S_MB_2U(SCH_1):PAGE235_I25@PURE_QUANTA.Q_RES(CHIPS)':
 'B': CDS_PINID='B';
NET_NAME
'JTAG_BMC_SW_TDI_R'
 '@S9S_MB_2U_LIB.S9S_MB_2U(SCH_1):JTAG_BMC_SW_TDI_R':
 C_SIGNAL='@s9s_mb_2u_lib.s9s_mb_2u(sch_1):jtag_bmc_sw_tdi_r';
NODE_NAME     R4631 1
 '@S9S_MB_2U_LIB.S9S_MB_2U(SCH_1):PAGE235_I25@PURE_QUANTA.Q_RES(CHIPS)':
 'A': CDS_PINID='A';
NODE_NAME     U327 8
 '@S9S_MB_2U_LIB.S9S_MB_2U(SCH_1):PAGE235_I19@PURE_QUANTA.74CBTLV3126PW(CHIPS)':
 '3B': CDS_PINID='\3b\';
NET_NAME
'JTAG_BMC_SW_TDO'
 '@S9S_MB_2U_LIB.S9S_MB_2U(SCH_1):JTAG_BMC_SW_TDO':
 C_SIGNAL='@s9s_mb_2u_lib.s9s_mb_2u(sch_1):jtag_bmc_sw_tdo';
NODE_NAME     U96 6
 '@S9S_MB_2U_LIB.S9S_MB_2U(SCH_1):PAGE226_I68@PURE_QUANTA.NX3L2267GM(CHIPS)':
 '2Z': CDS_PINID='\2z\';
NODE_NAME     R4630 2
 '@S9S_MB_2U_LIB.S9S_MB_2U(SCH_1):PAGE235_I27@PURE_QUANTA.Q_RES(CHIPS)':
 'B': CDS_PINID='B';
NET_NAME
'JTAG_BMC_SW_TDO_R'
 '@S9S_MB_2U_LIB.S9S_MB_2U(SCH_1):JTAG_BMC_SW_TDO_R':
 C_SIGNAL='@s9s_mb_2u_lib.s9s_mb_2u(sch_1):jtag_bmc_sw_tdo_r';
NODE_NAME     R4630 1
 '@S9S_MB_2U_LIB.S9S_MB_2U(SCH_1):PAGE235_I27@PURE_QUANTA.Q_RES(CHIPS)':
 'A': CDS_PINID='A';
NODE_NAME     U327 11
 '@S9S_MB_2U_LIB.S9S_MB_2U(SCH_1):PAGE235_I19@PURE_QUANTA.74CBTLV3126PW(CHIPS)':
 '4B': CDS_PINID='\4b\';
NET_NAME
'JTAG_BMC_SW_TMS'
 '@S9S_MB_2U_LIB.S9S_MB_2U(SCH_1):JTAG_BMC_SW_TMS':
 C_SIGNAL='@s9s_mb_2u_lib.s9s_mb_2u(sch_1):jtag_bmc_sw_tms';
NODE_NAME     U97 9
 '@S9S_MB_2U_LIB.S9S_MB_2U(SCH_1):PAGE226_I38@PURE_QUANTA.NX3L2267GM(CHIPS)':
 '1Z': CDS_PINID='\1z\';
NODE_NAME     R4632 2
 '@S9S_MB_2U_LIB.S9S_MB_2U(SCH_1):PAGE235_I26@PURE_QUANTA.Q_RES(CHIPS)':
 'B': CDS_PINID='B';
NET_NAME
'JTAG_BMC_SW_TMS_R'
 '@S9S_MB_2U_LIB.S9S_MB_2U(SCH_1):JTAG_BMC_SW_TMS_R':
 C_SIGNAL='@s9s_mb_2u_lib.s9s_mb_2u(sch_1):jtag_bmc_sw_tms_r';
NODE_NAME     U327 6
 '@S9S_MB_2U_LIB.S9S_MB_2U(SCH_1):PAGE235_I19@PURE_QUANTA.74CBTLV3126PW(CHIPS)':
 '2B': CDS_PINID='\2b\';
NODE_NAME     R4632 1
 '@S9S_MB_2U_LIB.S9S_MB_2U(SCH_1):PAGE235_I26@PURE_QUANTA.Q_RES(CHIPS)':
 'A': CDS_PINID='A';
NET_NAME
'JTAG_BMC_TCK'
 '@S9S_MB_2U_LIB.S9S_MB_2U(SCH_1):JTAG_BMC_TCK':
 C_SIGNAL='@s9s_mb_2u_lib.s9s_mb_2u(sch_1):jtag_bmc_tck';
NODE_NAME     R4629 1
 '@S9S_MB_2U_LIB.S9S_MB_2U(SCH_1):PAGE235_I15@PURE_QUANTA.Q_RES(CHIPS)':
 'A': CDS_PINID='A';
NODE_NAME     J41 A34
 '@S9S_MB_2U_LIB.S9S_MB_2U(SCH_1):PAGE227_I173@PURE_QUANTA.SCONN168_ME1016810202011(CHIPS)':
 'PERP5': CDS_PINID='PERP5';
NET_NAME
'JTAG_BMC_TCK_R'
 '@S9S_MB_2U_LIB.S9S_MB_2U(SCH_1):JTAG_BMC_TCK_R':
 C_SIGNAL='@s9s_mb_2u_lib.s9s_mb_2u(sch_1):jtag_bmc_tck_r';
NODE_NAME     R4629 2
 '@S9S_MB_2U_LIB.S9S_MB_2U(SCH_1):PAGE235_I15@PURE_QUANTA.Q_RES(CHIPS)':
 'B': CDS_PINID='B';
NODE_NAME     U327 2
 '@S9S_MB_2U_LIB.S9S_MB_2U(SCH_1):PAGE235_I19@PURE_QUANTA.74CBTLV3126PW(CHIPS)':
 '1A': CDS_PINID='\1a\';
NET_NAME
'JTAG_BMC_TDI'
 '@S9S_MB_2U_LIB.S9S_MB_2U(SCH_1):JTAG_BMC_TDI':
 C_SIGNAL='@s9s_mb_2u_lib.s9s_mb_2u(sch_1):jtag_bmc_tdi';
NODE_NAME     R4627 1
 '@S9S_MB_2U_LIB.S9S_MB_2U(SCH_1):PAGE235_I17@PURE_QUANTA.Q_RES(CHIPS)':
 'A': CDS_PINID='A';
NODE_NAME     J41 A36
 '@S9S_MB_2U_LIB.S9S_MB_2U(SCH_1):PAGE227_I173@PURE_QUANTA.SCONN168_ME1016810202011(CHIPS)':
 'PERN6': CDS_PINID='PERN6';
NET_NAME
'JTAG_BMC_TDI_R'
 '@S9S_MB_2U_LIB.S9S_MB_2U(SCH_1):JTAG_BMC_TDI_R':
 C_SIGNAL='@s9s_mb_2u_lib.s9s_mb_2u(sch_1):jtag_bmc_tdi_r';
NODE_NAME     R4627 2
 '@S9S_MB_2U_LIB.S9S_MB_2U(SCH_1):PAGE235_I17@PURE_QUANTA.Q_RES(CHIPS)':
 'B': CDS_PINID='B';
NODE_NAME     U327 9
 '@S9S_MB_2U_LIB.S9S_MB_2U(SCH_1):PAGE235_I19@PURE_QUANTA.74CBTLV3126PW(CHIPS)':
 '3A': CDS_PINID='\3a\';
NET_NAME
'JTAG_BMC_TDO'
 '@S9S_MB_2U_LIB.S9S_MB_2U(SCH_1):JTAG_BMC_TDO':
 C_SIGNAL='@s9s_mb_2u_lib.s9s_mb_2u(sch_1):jtag_bmc_tdo';
NODE_NAME     R4626 1
 '@S9S_MB_2U_LIB.S9S_MB_2U(SCH_1):PAGE235_I18@PURE_QUANTA.Q_RES(CHIPS)':
 'A': CDS_PINID='A';
NODE_NAME     J41 A37
 '@S9S_MB_2U_LIB.S9S_MB_2U(SCH_1):PAGE227_I173@PURE_QUANTA.SCONN168_ME1016810202011(CHIPS)':
 'PERP6': CDS_PINID='PERP6';
NET_NAME
'JTAG_BMC_TDO_R'
 '@S9S_MB_2U_LIB.S9S_MB_2U(SCH_1):JTAG_BMC_TDO_R':
 C_SIGNAL='@s9s_mb_2u_lib.s9s_mb_2u(sch_1):jtag_bmc_tdo_r';
NODE_NAME     R4626 2
 '@S9S_MB_2U_LIB.S9S_MB_2U(SCH_1):PAGE235_I18@PURE_QUANTA.Q_RES(CHIPS)':
 'B': CDS_PINID='B';
NODE_NAME     U327 12
 '@S9S_MB_2U_LIB.S9S_MB_2U(SCH_1):PAGE235_I19@PURE_QUANTA.74CBTLV3126PW(CHIPS)':
 '4A': CDS_PINID='\4a\';
NET_NAME
'JTAG_BMC_TMS'
 '@S9S_MB_2U_LIB.S9S_MB_2U(SCH_1):JTAG_BMC_TMS':
 C_SIGNAL='@s9s_mb_2u_lib.s9s_mb_2u(sch_1):jtag_bmc_tms';
NODE_NAME     R4628 1
 '@S9S_MB_2U_LIB.S9S_MB_2U(SCH_1):PAGE235_I16@PURE_QUANTA.Q_RES(CHIPS)':
 'A': CDS_PINID='A';
NODE_NAME     J41 A35
 '@S9S_MB_2U_LIB.S9S_MB_2U(SCH_1):PAGE227_I173@PURE_QUANTA.SCONN168_ME1016810202011(CHIPS)':
 'GND_A35': CDS_PINID='GND_A35';
NET_NAME
'JTAG_BMC_TMS_R'
 '@S9S_MB_2U_LIB.S9S_MB_2U(SCH_1):JTAG_BMC_TMS_R':
 C_SIGNAL='@s9s_mb_2u_lib.s9s_mb_2u(sch_1):jtag_bmc_tms_r';
NODE_NAME     R4628 2
 '@S9S_MB_2U_LIB.S9S_MB_2U(SCH_1):PAGE235_I16@PURE_QUANTA.Q_RES(CHIPS)':
 'B': CDS_PINID='B';
NODE_NAME     U327 5
 '@S9S_MB_2U_LIB.S9S_MB_2U(SCH_1):PAGE235_I19@PURE_QUANTA.74CBTLV3126PW(CHIPS)':
 '2A': CDS_PINID='\2a\';
NET_NAME
'JTAG_CPU0_MUX_GTL_TDO'
 '@S9S_MB_2U_LIB.S9S_MB_2U(SCH_1):JTAG_CPU0_MUX_GTL_TDO':
 C_SIGNAL='@s9s_mb_2u_lib.s9s_mb_2u(sch_1):jtag_cpu0_mux_gtl_tdo';
NODE_NAME     U2 BW25
 '@S9S_MB_2U_LIB.S9S_MB_2U(SCH_1):PAGE13_I57@PURE_QUANTA.SOCKET4677_AZIF0045P001C01CS(CHIPS)':
 'TDO': CDS_PINID='TDO';
NODE_NAME     U22 1
 '@S9S_MB_2U_LIB.S9S_MB_2U(SCH_1):PAGE135_I71@PURE_QUANTA.NC7SB3157(CHIPS)':
 'B1': CDS_PINID='B1';
NODE_NAME     R744 2
 '@S9S_MB_2U_LIB.S9S_MB_2U(SCH_1):PAGE135_I77@PURE_QUANTA.Q_RES(CHIPS)':
 'B': CDS_PINID='B';
NODE_NAME     U16 1
 '@S9S_MB_2U_LIB.S9S_MB_2U(SCH_1):PAGE135_I115@PURE_QUANTA.74LVC1G66GV(CHIPS)':
 'Y': CDS_PINID='Y';
NET_NAME
'JTAG_CPU1_MUX_GTL_TDO'
 '@S9S_MB_2U_LIB.S9S_MB_2U(SCH_1):JTAG_CPU1_MUX_GTL_TDO':
 C_SIGNAL='@s9s_mb_2u_lib.s9s_mb_2u(sch_1):jtag_cpu1_mux_gtl_tdo';
NODE_NAME     U1 BW25
 '@S9S_MB_2U_LIB.S9S_MB_2U(SCH_1):PAGE44_I51@PURE_QUANTA.SOCKET4677_AZIF0045P001C01CS(CHIPS)':
 'TDO': CDS_PINID='TDO';
NODE_NAME     U22 3
 '@S9S_MB_2U_LIB.S9S_MB_2U(SCH_1):PAGE135_I71@PURE_QUANTA.NC7SB3157(CHIPS)':
 'B0': CDS_PINID='B0';
NODE_NAME     R742 2
 '@S9S_MB_2U_LIB.S9S_MB_2U(SCH_1):PAGE135_I78@PURE_QUANTA.Q_RES(CHIPS)':
 'B': CDS_PINID='B';
NET_NAME
'JTAG_DBP_BMC_PRDY_N'
 '@S9S_MB_2U_LIB.S9S_MB_2U(SCH_1):JTAG_DBP_BMC_PRDY_N':
 C_SIGNAL='@s9s_mb_2u_lib.s9s_mb_2u(sch_1):jtag_dbp_bmc_prdy_n';
NODE_NAME     R1382 2
 '@S9S_MB_2U_LIB.S9S_MB_2U(SCH_1):PAGE226_I20@PURE_QUANTA.Q_RES(CHIPS)':
 'B': CDS_PINID='B';
NODE_NAME     R3056 2
 '@S9S_MB_2U_LIB.S9S_MB_2U(SCH_1):PAGE226_I36@PURE_QUANTA.Q_RES(CHIPS)':
 'B': CDS_PINID='B';
NODE_NAME     R1831 1
 '@S9S_MB_2U_LIB.S9S_MB_2U(SCH_1):PAGE226_I82@PURE_QUANTA.Q_RES(CHIPS)':
 'A': CDS_PINID='A';
NODE_NAME     J41 A50
 '@S9S_MB_2U_LIB.S9S_MB_2U(SCH_1):PAGE227_I173@PURE_QUANTA.SCONN168_ME1016810202011(CHIPS)':
 'PERN10': CDS_PINID='PERN10';
NET_NAME
'JTAG_DBP_BMC_PRDY_R1_N'
 '@S9S_MB_2U_LIB.S9S_MB_2U(SCH_1):JTAG_DBP_BMC_PRDY_R1_N':
 C_SIGNAL='@s9s_mb_2u_lib.s9s_mb_2u(sch_1):jtag_dbp_bmc_prdy_r1_n';
NODE_NAME     R3056 1
 '@S9S_MB_2U_LIB.S9S_MB_2U(SCH_1):PAGE226_I36@PURE_QUANTA.Q_RES(CHIPS)':
 'A': CDS_PINID='A';
NODE_NAME     U83 12
 '@S9S_MB_2U_LIB.S9S_MB_2U(SCH_1):PAGE226_I45@PURE_QUANTA.GTL2014PW(CHIPS)':
 'A1': CDS_PINID='A1';
NET_NAME
'JTAG_DBP_BMC_PRDY_R_N'
 '@S9S_MB_2U_LIB.S9S_MB_2U(SCH_1):JTAG_DBP_BMC_PRDY_R_N':
 C_SIGNAL='@s9s_mb_2u_lib.s9s_mb_2u(sch_1):jtag_dbp_bmc_prdy_r_n';
NODE_NAME     R1831 2
 '@S9S_MB_2U_LIB.S9S_MB_2U(SCH_1):PAGE226_I82@PURE_QUANTA.Q_RES(CHIPS)':
 'B': CDS_PINID='B';
NODE_NAME     U249 AA9
 '@S9S_MB_2U_LIB.S9S_MB_2U(SCH_1):PAGE312_I1@PURE_QUANTA.LCMXO3LF9400C5BG484C(CHIPS)':
 'PB19A': CDS_PINID='PB19A';
NET_NAME
'JTAG_DBP_BMC_PREQ_R1_N'
 '@S9S_MB_2U_LIB.S9S_MB_2U(SCH_1):JTAG_DBP_BMC_PREQ_R1_N':
 C_SIGNAL='@s9s_mb_2u_lib.s9s_mb_2u(sch_1):jtag_dbp_bmc_preq_r1_n';
NODE_NAME     R3057 1
 '@S9S_MB_2U_LIB.S9S_MB_2U(SCH_1):PAGE226_I12@PURE_QUANTA.Q_RES(CHIPS)':
 'A': CDS_PINID='A';
NODE_NAME     U84 13
 '@S9S_MB_2U_LIB.S9S_MB_2U(SCH_1):PAGE226_I18@PURE_QUANTA.GTL2014PW(CHIPS)':
 'A0': CDS_PINID='A0';
NET_NAME
'JTAG_DBP_BMC_PREQ_R_N'
 '@S9S_MB_2U_LIB.S9S_MB_2U(SCH_1):JTAG_DBP_BMC_PREQ_R_N':
 C_SIGNAL='@s9s_mb_2u_lib.s9s_mb_2u(sch_1):jtag_dbp_bmc_preq_r_n';
NODE_NAME     R1832 2
 '@S9S_MB_2U_LIB.S9S_MB_2U(SCH_1):PAGE226_I80@PURE_QUANTA.Q_RES(CHIPS)':
 'B': CDS_PINID='B';
NODE_NAME     U249 AB18
 '@S9S_MB_2U_LIB.S9S_MB_2U(SCH_1):PAGE312_I1@PURE_QUANTA.LCMXO3LF9400C5BG484C(CHIPS)':
 'PB41A': CDS_PINID='PB41A';
NET_NAME
'JTAG_DBP_BOOT_HALT_N'
 '@S9S_MB_2U_LIB.S9S_MB_2U(SCH_1):JTAG_DBP_BOOT_HALT_N':
 C_SIGNAL='@s9s_mb_2u_lib.s9s_mb_2u(sch_1):jtag_dbp_boot_halt_n';
NODE_NAME     R778 2
 '@S9S_MB_2U_LIB.S9S_MB_2U(SCH_1):PAGE133_I15@PURE_QUANTA.Q_RES(CHIPS)':
 'B': CDS_PINID='B';
NODE_NAME     J42 36
 '@S9S_MB_2U_LIB.S9S_MB_2U(SCH_1):PAGE133_I44@PURE_QUANTA.SCONN60_ASP21410801(CHIPS)':
 '36': CDS_PINID='\36\';
NODE_NAME     R773 1
 '@S9S_MB_2U_LIB.S9S_MB_2U(SCH_1):PAGE133_I124@PURE_QUANTA.Q_RES(CHIPS)':
 'A': CDS_PINID='A';
NET_NAME
'JTAG_DBP_CPU0_GTL_R_TCK'
 '@S9S_MB_2U_LIB.S9S_MB_2U(SCH_1):JTAG_DBP_CPU0_GTL_R_TCK':
 C_SIGNAL='@s9s_mb_2u_lib.s9s_mb_2u(sch_1):jtag_dbp_cpu0_gtl_r_tck';
NODE_NAME     R5 2
 '@S9S_MB_2U_LIB.S9S_MB_2U(SCH_1):PAGE13_I24@PURE_QUANTA.Q_RES(CHIPS)':
 'B': CDS_PINID='B';
NODE_NAME     U2 BT24
 '@S9S_MB_2U_LIB.S9S_MB_2U(SCH_1):PAGE13_I57@PURE_QUANTA.SOCKET4677_AZIF0045P001C01CS(CHIPS)':
 'TCK': CDS_PINID='TCK';
NET_NAME
'JTAG_DBP_CPU0_GTL_R_TDI'
 '@S9S_MB_2U_LIB.S9S_MB_2U(SCH_1):JTAG_DBP_CPU0_GTL_R_TDI':
 C_SIGNAL='@s9s_mb_2u_lib.s9s_mb_2u(sch_1):jtag_dbp_cpu0_gtl_r_tdi';
NODE_NAME     R4 2
 '@S9S_MB_2U_LIB.S9S_MB_2U(SCH_1):PAGE13_I29@PURE_QUANTA.Q_RES(CHIPS)':
 'B': CDS_PINID='B';
NODE_NAME     U2 BV24
 '@S9S_MB_2U_LIB.S9S_MB_2U(SCH_1):PAGE13_I57@PURE_QUANTA.SOCKET4677_AZIF0045P001C01CS(CHIPS)':
 'TDI': CDS_PINID='TDI';
NET_NAME
'JTAG_DBP_CPU0_QS_GTL_R_TMS'
 '@S9S_MB_2U_LIB.S9S_MB_2U(SCH_1):JTAG_DBP_CPU0_QS_GTL_R_TMS':
 C_SIGNAL='@s9s_mb_2u_lib.s9s_mb_2u(sch_1):jtag_dbp_cpu0_qs_gtl_r_tms';
NODE_NAME     R6 2
 '@S9S_MB_2U_LIB.S9S_MB_2U(SCH_1):PAGE13_I25@PURE_QUANTA.Q_RES(CHIPS)':
 'B': CDS_PINID='B';
NODE_NAME     U2 BR25
 '@S9S_MB_2U_LIB.S9S_MB_2U(SCH_1):PAGE13_I57@PURE_QUANTA.SOCKET4677_AZIF0045P001C01CS(CHIPS)':
 'TMS': CDS_PINID='TMS';
NET_NAME
'JTAG_DBP_CPU1_GTL_R_TCK'
 '@S9S_MB_2U_LIB.S9S_MB_2U(SCH_1):JTAG_DBP_CPU1_GTL_R_TCK':
 C_SIGNAL='@s9s_mb_2u_lib.s9s_mb_2u(sch_1):jtag_dbp_cpu1_gtl_r_tck';
NODE_NAME     R65 2
 '@S9S_MB_2U_LIB.S9S_MB_2U(SCH_1):PAGE44_I8@PURE_QUANTA.Q_RES(CHIPS)':
 'B': CDS_PINID='B';
NODE_NAME     U1 BT24
 '@S9S_MB_2U_LIB.S9S_MB_2U(SCH_1):PAGE44_I51@PURE_QUANTA.SOCKET4677_AZIF0045P001C01CS(CHIPS)':
 'TCK': CDS_PINID='TCK';
NET_NAME
'JTAG_DBP_CPU1_GTL_R_TDI'
 '@S9S_MB_2U_LIB.S9S_MB_2U(SCH_1):JTAG_DBP_CPU1_GTL_R_TDI':
 C_SIGNAL='@s9s_mb_2u_lib.s9s_mb_2u(sch_1):jtag_dbp_cpu1_gtl_r_tdi';
NODE_NAME     R64 2
 '@S9S_MB_2U_LIB.S9S_MB_2U(SCH_1):PAGE44_I9@PURE_QUANTA.Q_RES(CHIPS)':
 'B': CDS_PINID='B';
NODE_NAME     U1 BV24
 '@S9S_MB_2U_LIB.S9S_MB_2U(SCH_1):PAGE44_I51@PURE_QUANTA.SOCKET4677_AZIF0045P001C01CS(CHIPS)':
 'TDI': CDS_PINID='TDI';
NET_NAME
'JTAG_DBP_CPU1_QS_GTL_R_TMS'
 '@S9S_MB_2U_LIB.S9S_MB_2U(SCH_1):JTAG_DBP_CPU1_QS_GTL_R_TMS':
 C_SIGNAL='@s9s_mb_2u_lib.s9s_mb_2u(sch_1):jtag_dbp_cpu1_qs_gtl_r_tms';
NODE_NAME     R66 2
 '@S9S_MB_2U_LIB.S9S_MB_2U(SCH_1):PAGE44_I7@PURE_QUANTA.Q_RES(CHIPS)':
 'B': CDS_PINID='B';
NODE_NAME     U1 BR25
 '@S9S_MB_2U_LIB.S9S_MB_2U(SCH_1):PAGE44_I51@PURE_QUANTA.SOCKET4677_AZIF0045P001C01CS(CHIPS)':
 'TMS': CDS_PINID='TMS';
NET_NAME
'JTAG_DBP_CPU_GTL_TCK'
 '@S9S_MB_2U_LIB.S9S_MB_2U(SCH_1):JTAG_DBP_CPU_GTL_TCK':
 C_SIGNAL='@s9s_mb_2u_lib.s9s_mb_2u(sch_1):jtag_dbp_cpu_gtl_tck';
NODE_NAME     R5 1
 '@S9S_MB_2U_LIB.S9S_MB_2U(SCH_1):PAGE13_I24@PURE_QUANTA.Q_RES(CHIPS)':
 'A': CDS_PINID='A';
NODE_NAME     R65 1
 '@S9S_MB_2U_LIB.S9S_MB_2U(SCH_1):PAGE44_I8@PURE_QUANTA.Q_RES(CHIPS)':
 'A': CDS_PINID='A';
NODE_NAME     R762 1
 '@S9S_MB_2U_LIB.S9S_MB_2U(SCH_1):PAGE133_I71@PURE_QUANTA.Q_RES(CHIPS)':
 'A': CDS_PINID='A';
NODE_NAME     R774 1
 '@S9S_MB_2U_LIB.S9S_MB_2U(SCH_1):PAGE133_I132@PURE_QUANTA.Q_RES(CHIPS)':
 'A': CDS_PINID='A';
NODE_NAME     R1348 2
 '@S9S_MB_2U_LIB.S9S_MB_2U(SCH_1):PAGE137_I88@PURE_QUANTA.Q_RES(CHIPS)':
 'B': CDS_PINID='B';
NODE_NAME     U4 BD35
 '@S9S_MB_2U_LIB.S9S_MB_2U(SCH_1):PAGE174_I36@PURE_QUANTA.EMMITSBURG_REV0P9(CHIPS)':
 'JTAGX': CDS_PINID='JTAGX';
NODE_NAME     R1025 1
 '@S9S_MB_2U_LIB.S9S_MB_2U(SCH_1):PAGE174_I38@PURE_QUANTA.Q_RES(CHIPS)':
 'A': CDS_PINID='A';
NET_NAME
'JTAG_DBP_CPU_GTL_TCK_R'
 '@S9S_MB_2U_LIB.S9S_MB_2U(SCH_1):JTAG_DBP_CPU_GTL_TCK_R':
 C_SIGNAL='@s9s_mb_2u_lib.s9s_mb_2u(sch_1):jtag_dbp_cpu_gtl_tck_r';
NODE_NAME     J42 3
 '@S9S_MB_2U_LIB.S9S_MB_2U(SCH_1):PAGE133_I44@PURE_QUANTA.SCONN60_ASP21410801(CHIPS)':
 '3': CDS_PINID='\3\';
NODE_NAME     R762 2
 '@S9S_MB_2U_LIB.S9S_MB_2U(SCH_1):PAGE133_I71@PURE_QUANTA.Q_RES(CHIPS)':
 'B': CDS_PINID='B';
NET_NAME
'JTAG_DBP_CPU_GTL_TCK_R1'
 '@S9S_MB_2U_LIB.S9S_MB_2U(SCH_1):JTAG_DBP_CPU_GTL_TCK_R1':
 C_SIGNAL='@s9s_mb_2u_lib.s9s_mb_2u(sch_1):jtag_dbp_cpu_gtl_tck_r1';
NODE_NAME     U86 6
 '@S9S_MB_2U_LIB.S9S_MB_2U(SCH_1):PAGE137_I84@PURE_QUANTA.74CBTLV3126PW(CHIPS)':
 '2B': CDS_PINID='\2b\';
NODE_NAME     R1348 1
 '@S9S_MB_2U_LIB.S9S_MB_2U(SCH_1):PAGE137_I88@PURE_QUANTA.Q_RES(CHIPS)':
 'A': CDS_PINID='A';
NET_NAME
'JTAG_DBP_CPU_HOOK8_MBP2_GTL_N'
 '@S9S_MB_2U_LIB.S9S_MB_2U(SCH_1):JTAG_DBP_CPU_HOOK8_MBP2_GTL_N':
 C_SIGNAL='@s9s_mb_2u_lib.s9s_mb_2u(sch_1):jtag_dbp_cpu_hook8_mbp2_gtl_n';
NODE_NAME     J42 55
 '@S9S_MB_2U_LIB.S9S_MB_2U(SCH_1):PAGE133_I44@PURE_QUANTA.SCONN60_ASP21410801(CHIPS)':
 '55': CDS_PINID='\55\';
NODE_NAME     U18 5
 '@S9S_MB_2U_LIB.S9S_MB_2U(SCH_1):PAGE134_I129@PURE_QUANTA.74CBTLV3126PW(CHIPS)':
 '2A': CDS_PINID='\2a\';
NET_NAME
'JTAG_DBP_CPU_HOOK9_MBP3_GTL_N'
 '@S9S_MB_2U_LIB.S9S_MB_2U(SCH_1):JTAG_DBP_CPU_HOOK9_MBP3_GTL_N':
 C_SIGNAL='@s9s_mb_2u_lib.s9s_mb_2u(sch_1):jtag_dbp_cpu_hook9_mbp3_gtl_n';
NODE_NAME     J42 53
 '@S9S_MB_2U_LIB.S9S_MB_2U(SCH_1):PAGE133_I44@PURE_QUANTA.SCONN60_ASP21410801(CHIPS)':
 '53': CDS_PINID='\53\';
NODE_NAME     U18 2
 '@S9S_MB_2U_LIB.S9S_MB_2U(SCH_1):PAGE134_I129@PURE_QUANTA.74CBTLV3126PW(CHIPS)':
 '1A': CDS_PINID='\1a\';
NET_NAME
'JTAG_DBP_CPU_QS_GTL_TMS'
 '@S9S_MB_2U_LIB.S9S_MB_2U(SCH_1):JTAG_DBP_CPU_QS_GTL_TMS':
 C_SIGNAL='@s9s_mb_2u_lib.s9s_mb_2u(sch_1):jtag_dbp_cpu_qs_gtl_tms';
NODE_NAME     R6 1
 '@S9S_MB_2U_LIB.S9S_MB_2U(SCH_1):PAGE13_I25@PURE_QUANTA.Q_RES(CHIPS)':
 'A': CDS_PINID='A';
NODE_NAME     R66 1
 '@S9S_MB_2U_LIB.S9S_MB_2U(SCH_1):PAGE44_I7@PURE_QUANTA.Q_RES(CHIPS)':
 'A': CDS_PINID='A';
NODE_NAME     U17 3
 '@S9S_MB_2U_LIB.S9S_MB_2U(SCH_1):PAGE134_I80@PURE_QUANTA.74CBTLV3126PW(CHIPS)':
 '1B': CDS_PINID='\1b\';
NODE_NAME     R757 2
 '@S9S_MB_2U_LIB.S9S_MB_2U(SCH_1):PAGE134_I166@PURE_QUANTA.Q_RES(CHIPS)':
 'B': CDS_PINID='B';
NET_NAME
'JTAG_DBP_FB_TDI'
 '@S9S_MB_2U_LIB.S9S_MB_2U(SCH_1):JTAG_DBP_FB_TDI':
 C_SIGNAL='@s9s_mb_2u_lib.s9s_mb_2u(sch_1):jtag_dbp_fb_tdi';
NODE_NAME     U84 5
 '@S9S_MB_2U_LIB.S9S_MB_2U(SCH_1):PAGE226_I18@PURE_QUANTA.GTL2014PW(CHIPS)':
 'B2': CDS_PINID='B2';
NODE_NAME     R481 2
 '@S9S_MB_2U_LIB.S9S_MB_2U(SCH_1):PAGE226_I58@PURE_QUANTA.Q_RES(CHIPS)':
 'B': CDS_PINID='B';
NET_NAME
'JTAG_DBP_FB_TDO'
 '@S9S_MB_2U_LIB.S9S_MB_2U(SCH_1):JTAG_DBP_FB_TDO':
 C_SIGNAL='@s9s_mb_2u_lib.s9s_mb_2u(sch_1):jtag_dbp_fb_tdo';
NODE_NAME     U83 6
 '@S9S_MB_2U_LIB.S9S_MB_2U(SCH_1):PAGE226_I45@PURE_QUANTA.GTL2014PW(CHIPS)':
 'B3': CDS_PINID='B3';
NODE_NAME     R1366 2
 '@S9S_MB_2U_LIB.S9S_MB_2U(SCH_1):PAGE226_I64@PURE_QUANTA.Q_RES(CHIPS)':
 'B': CDS_PINID='B';
NET_NAME
'JTAG_DBP_FB_TMS'
 '@S9S_MB_2U_LIB.S9S_MB_2U(SCH_1):JTAG_DBP_FB_TMS':
 C_SIGNAL='@s9s_mb_2u_lib.s9s_mb_2u(sch_1):jtag_dbp_fb_tms';
NODE_NAME     U84 6
 '@S9S_MB_2U_LIB.S9S_MB_2U(SCH_1):PAGE226_I18@PURE_QUANTA.GTL2014PW(CHIPS)':
 'B3': CDS_PINID='B3';
NODE_NAME     R480 2
 '@S9S_MB_2U_LIB.S9S_MB_2U(SCH_1):PAGE226_I59@PURE_QUANTA.Q_RES(CHIPS)':
 'B': CDS_PINID='B';
NET_NAME
'JTAG_DBP_PCH_DEBUG_CONSENT_N'
 '@S9S_MB_2U_LIB.S9S_MB_2U(SCH_1):JTAG_DBP_PCH_DEBUG_CONSENT_N':
 C_SIGNAL='@s9s_mb_2u_lib.s9s_mb_2u(sch_1):jtag_dbp_pch_debug_consent_n';
NODE_NAME     J42 15
 '@S9S_MB_2U_LIB.S9S_MB_2U(SCH_1):PAGE133_I44@PURE_QUANTA.SCONN60_ASP21410801(CHIPS)':
 '15': CDS_PINID='\15\';
NODE_NAME     R771 1
 '@S9S_MB_2U_LIB.S9S_MB_2U(SCH_1):PAGE133_I120@PURE_QUANTA.Q_RES(CHIPS)':
 'A': CDS_PINID='A';
NET_NAME
'JTAG_DBP_PMODE'
 '@S9S_MB_2U_LIB.S9S_MB_2U(SCH_1):JTAG_DBP_PMODE':
 C_SIGNAL='@s9s_mb_2u_lib.s9s_mb_2u(sch_1):jtag_dbp_pmode';
NODE_NAME     J42 7
 '@S9S_MB_2U_LIB.S9S_MB_2U(SCH_1):PAGE133_I44@PURE_QUANTA.SCONN60_ASP21410801(CHIPS)':
 '7': CDS_PINID='\7\';
NODE_NAME     U4 BE40
 '@S9S_MB_2U_LIB.S9S_MB_2U(SCH_1):PAGE174_I36@PURE_QUANTA.EMMITSBURG_REV0P9(CHIPS)':
 'DBG_PMODE': CDS_PINID='DBG_PMODE';
NODE_NAME     R1026 1
 '@S9S_MB_2U_LIB.S9S_MB_2U(SCH_1):PAGE174_I37@PURE_QUANTA.Q_RES(CHIPS)':
 'A': CDS_PINID='A';
NET_NAME
'JTAG_DBP_POWER_BTN_N'
 '@S9S_MB_2U_LIB.S9S_MB_2U(SCH_1):JTAG_DBP_POWER_BTN_N':
 C_SIGNAL='@s9s_mb_2u_lib.s9s_mb_2u(sch_1):jtag_dbp_power_btn_n';
NODE_NAME     J42 40
 '@S9S_MB_2U_LIB.S9S_MB_2U(SCH_1):PAGE133_I44@PURE_QUANTA.SCONN60_ASP21410801(CHIPS)':
 '40': CDS_PINID='\40\';
NODE_NAME     R766 2
 '@S9S_MB_2U_LIB.S9S_MB_2U(SCH_1):PAGE133_I111@PURE_QUANTA.Q_RES(CHIPS)':
 'B': CDS_PINID='B';
NODE_NAME     C548 1
 '@S9S_MB_2U_LIB.S9S_MB_2U(SCH_1):PAGE133_I130@PURE_QUANTA.Q_CAP(CHIPS)':
 'A': CDS_PINID='A';
NET_NAME
'JTAG_DBP_PRDY_N'
 '@S9S_MB_2U_LIB.S9S_MB_2U(SCH_1):JTAG_DBP_PRDY_N':
 C_SIGNAL='@s9s_mb_2u_lib.s9s_mb_2u(sch_1):jtag_dbp_prdy_n';
NODE_NAME     R764 1
 '@S9S_MB_2U_LIB.S9S_MB_2U(SCH_1):PAGE133_I83@PURE_QUANTA.Q_RES(CHIPS)':
 'A': CDS_PINID='A';
NODE_NAME     U18 9
 '@S9S_MB_2U_LIB.S9S_MB_2U(SCH_1):PAGE134_I129@PURE_QUANTA.74CBTLV3126PW(CHIPS)':
 '3A': CDS_PINID='\3a\';
NODE_NAME     R756 1
 '@S9S_MB_2U_LIB.S9S_MB_2U(SCH_1):PAGE134_I148@PURE_QUANTA.Q_RES(CHIPS)':
 'A': CDS_PINID='A';
NODE_NAME     R1367 1
 '@S9S_MB_2U_LIB.S9S_MB_2U(SCH_1):PAGE226_I65@PURE_QUANTA.Q_RES(CHIPS)':
 'A': CDS_PINID='A';
NET_NAME
'JTAG_DBP_PRDY_R1_N'
 '@S9S_MB_2U_LIB.S9S_MB_2U(SCH_1):JTAG_DBP_PRDY_R1_N':
 C_SIGNAL='@s9s_mb_2u_lib.s9s_mb_2u(sch_1):jtag_dbp_prdy_r1_n';
NODE_NAME     J42 11
 '@S9S_MB_2U_LIB.S9S_MB_2U(SCH_1):PAGE133_I44@PURE_QUANTA.SCONN60_ASP21410801(CHIPS)':
 '11': CDS_PINID='\11\';
NODE_NAME     R764 2
 '@S9S_MB_2U_LIB.S9S_MB_2U(SCH_1):PAGE133_I83@PURE_QUANTA.Q_RES(CHIPS)':
 'B': CDS_PINID='B';
NET_NAME
'JTAG_DBP_PRDY_R_N'
 '@S9S_MB_2U_LIB.S9S_MB_2U(SCH_1):JTAG_DBP_PRDY_R_N':
 C_SIGNAL='@s9s_mb_2u_lib.s9s_mb_2u(sch_1):jtag_dbp_prdy_r_n';
NODE_NAME     U83 3
 '@S9S_MB_2U_LIB.S9S_MB_2U(SCH_1):PAGE226_I45@PURE_QUANTA.GTL2014PW(CHIPS)':
 'B1': CDS_PINID='B1';
NODE_NAME     R1367 2
 '@S9S_MB_2U_LIB.S9S_MB_2U(SCH_1):PAGE226_I65@PURE_QUANTA.Q_RES(CHIPS)':
 'B': CDS_PINID='B';
NET_NAME
'JTAG_DBP_PREQ_N'
 '@S9S_MB_2U_LIB.S9S_MB_2U(SCH_1):JTAG_DBP_PREQ_N':
 C_SIGNAL='@s9s_mb_2u_lib.s9s_mb_2u(sch_1):jtag_dbp_preq_n';
NODE_NAME     R777 2
 '@S9S_MB_2U_LIB.S9S_MB_2U(SCH_1):PAGE133_I10@PURE_QUANTA.Q_RES(CHIPS)':
 'B': CDS_PINID='B';
NODE_NAME     U18 12
 '@S9S_MB_2U_LIB.S9S_MB_2U(SCH_1):PAGE134_I129@PURE_QUANTA.74CBTLV3126PW(CHIPS)':
 '4A': CDS_PINID='\4a\';
NODE_NAME     R755 1
 '@S9S_MB_2U_LIB.S9S_MB_2U(SCH_1):PAGE134_I147@PURE_QUANTA.Q_RES(CHIPS)':
 'A': CDS_PINID='A';
NODE_NAME     R482 1
 '@S9S_MB_2U_LIB.S9S_MB_2U(SCH_1):PAGE226_I57@PURE_QUANTA.Q_RES(CHIPS)':
 'A': CDS_PINID='A';
NET_NAME
'JTAG_DBP_PREQ_N_R'
 '@S9S_MB_2U_LIB.S9S_MB_2U(SCH_1):JTAG_DBP_PREQ_N_R':
 C_SIGNAL='@s9s_mb_2u_lib.s9s_mb_2u(sch_1):jtag_dbp_preq_n_r';
NODE_NAME     R777 1
 '@S9S_MB_2U_LIB.S9S_MB_2U(SCH_1):PAGE133_I10@PURE_QUANTA.Q_RES(CHIPS)':
 'A': CDS_PINID='A';
NODE_NAME     J42 10
 '@S9S_MB_2U_LIB.S9S_MB_2U(SCH_1):PAGE133_I44@PURE_QUANTA.SCONN60_ASP21410801(CHIPS)':
 '10': CDS_PINID='\10\';
NET_NAME
'JTAG_DBP_PREQ_R_N'
 '@S9S_MB_2U_LIB.S9S_MB_2U(SCH_1):JTAG_DBP_PREQ_R_N':
 C_SIGNAL='@s9s_mb_2u_lib.s9s_mb_2u(sch_1):jtag_dbp_preq_r_n';
NODE_NAME     U84 2
 '@S9S_MB_2U_LIB.S9S_MB_2U(SCH_1):PAGE226_I18@PURE_QUANTA.GTL2014PW(CHIPS)':
 'B0': CDS_PINID='B0';
NODE_NAME     R482 2
 '@S9S_MB_2U_LIB.S9S_MB_2U(SCH_1):PAGE226_I57@PURE_QUANTA.Q_RES(CHIPS)':
 'B': CDS_PINID='B';
NET_NAME
'JTAG_DBP_PRESENT_R_N'
 '@S9S_MB_2U_LIB.S9S_MB_2U(SCH_1):JTAG_DBP_PRESENT_R_N':
 C_SIGNAL='@s9s_mb_2u_lib.s9s_mb_2u(sch_1):jtag_dbp_present_r_n';
NODE_NAME     J42 17
 '@S9S_MB_2U_LIB.S9S_MB_2U(SCH_1):PAGE133_I44@PURE_QUANTA.SCONN60_ASP21410801(CHIPS)':
 '17': CDS_PINID='\17\';
NODE_NAME     R768 2
 '@S9S_MB_2U_LIB.S9S_MB_2U(SCH_1):PAGE133_I112@PURE_QUANTA.Q_RES(CHIPS)':
 'B': CDS_PINID='B';
NODE_NAME     R1472 1
 '@S9S_MB_2U_LIB.S9S_MB_2U(SCH_1):PAGE133_I144@PURE_QUANTA.Q_RES(CHIPS)':
 'A': CDS_PINID='A';
NET_NAME
'JTAG_DBP_TCK_PCH'
 '@S9S_MB_2U_LIB.S9S_MB_2U(SCH_1):JTAG_DBP_TCK_PCH':
 C_SIGNAL='@s9s_mb_2u_lib.s9s_mb_2u(sch_1):jtag_dbp_tck_pch';
NODE_NAME     R765 1
 '@S9S_MB_2U_LIB.S9S_MB_2U(SCH_1):PAGE133_I74@PURE_QUANTA.Q_RES(CHIPS)':
 'A': CDS_PINID='A';
NODE_NAME     R1349 2
 '@S9S_MB_2U_LIB.S9S_MB_2U(SCH_1):PAGE137_I87@PURE_QUANTA.Q_RES(CHIPS)':
 'B': CDS_PINID='B';
NODE_NAME     U4 BF35
 '@S9S_MB_2U_LIB.S9S_MB_2U(SCH_1):PAGE174_I36@PURE_QUANTA.EMMITSBURG_REV0P9(CHIPS)':
 'JTAG_TCK': CDS_PINID='JTAG_TCK';
NODE_NAME     R1024 1
 '@S9S_MB_2U_LIB.S9S_MB_2U(SCH_1):PAGE174_I41@PURE_QUANTA.Q_RES(CHIPS)':
 'A': CDS_PINID='A';
NET_NAME
'JTAG_DBP_TCK_PCH_R'
 '@S9S_MB_2U_LIB.S9S_MB_2U(SCH_1):JTAG_DBP_TCK_PCH_R':
 C_SIGNAL='@s9s_mb_2u_lib.s9s_mb_2u(sch_1):jtag_dbp_tck_pch_r';
NODE_NAME     U86 8
 '@S9S_MB_2U_LIB.S9S_MB_2U(SCH_1):PAGE137_I84@PURE_QUANTA.74CBTLV3126PW(CHIPS)':
 '3B': CDS_PINID='\3b\';
NODE_NAME     R1349 1
 '@S9S_MB_2U_LIB.S9S_MB_2U(SCH_1):PAGE137_I87@PURE_QUANTA.Q_RES(CHIPS)':
 'A': CDS_PINID='A';
NET_NAME
'JTAG_DBP_TCK_R_TCK'
 '@S9S_MB_2U_LIB.S9S_MB_2U(SCH_1):JTAG_DBP_TCK_R_TCK':
 C_SIGNAL='@s9s_mb_2u_lib.s9s_mb_2u(sch_1):jtag_dbp_tck_r_tck';
NODE_NAME     J42 51
 '@S9S_MB_2U_LIB.S9S_MB_2U(SCH_1):PAGE133_I44@PURE_QUANTA.SCONN60_ASP21410801(CHIPS)':
 '51': CDS_PINID='\51\';
NODE_NAME     R765 2
 '@S9S_MB_2U_LIB.S9S_MB_2U(SCH_1):PAGE133_I74@PURE_QUANTA.Q_RES(CHIPS)':
 'B': CDS_PINID='B';
NET_NAME
'JTAG_DBP_TDI'
 '@S9S_MB_2U_LIB.S9S_MB_2U(SCH_1):JTAG_DBP_TDI':
 C_SIGNAL='@s9s_mb_2u_lib.s9s_mb_2u(sch_1):jtag_dbp_tdi';
NODE_NAME     R763 1
 '@S9S_MB_2U_LIB.S9S_MB_2U(SCH_1):PAGE133_I70@PURE_QUANTA.Q_RES(CHIPS)':
 'A': CDS_PINID='A';
NODE_NAME     U17 5
 '@S9S_MB_2U_LIB.S9S_MB_2U(SCH_1):PAGE134_I80@PURE_QUANTA.74CBTLV3126PW(CHIPS)':
 '2A': CDS_PINID='\2a\';
NODE_NAME     R753 1
 '@S9S_MB_2U_LIB.S9S_MB_2U(SCH_1):PAGE134_I128@PURE_QUANTA.Q_RES(CHIPS)':
 'A': CDS_PINID='A';
NODE_NAME     R481 1
 '@S9S_MB_2U_LIB.S9S_MB_2U(SCH_1):PAGE226_I58@PURE_QUANTA.Q_RES(CHIPS)':
 'A': CDS_PINID='A';
NET_NAME
'JTAG_DBP_TDI_PCH'
 '@S9S_MB_2U_LIB.S9S_MB_2U(SCH_1):JTAG_DBP_TDI_PCH':
 C_SIGNAL='@s9s_mb_2u_lib.s9s_mb_2u(sch_1):jtag_dbp_tdi_pch';
NODE_NAME     R753 2
 '@S9S_MB_2U_LIB.S9S_MB_2U(SCH_1):PAGE134_I128@PURE_QUANTA.Q_RES(CHIPS)':
 'B': CDS_PINID='B';
NODE_NAME     R748 2
 '@S9S_MB_2U_LIB.S9S_MB_2U(SCH_1):PAGE134_I180@PURE_QUANTA.Q_RES(CHIPS)':
 'B': CDS_PINID='B';
NODE_NAME     U4 BE38
 '@S9S_MB_2U_LIB.S9S_MB_2U(SCH_1):PAGE174_I36@PURE_QUANTA.EMMITSBURG_REV0P9(CHIPS)':
 'JTAG_TDI': CDS_PINID='JTAG_TDI';
NET_NAME
'JTAG_DBP_TDI_R'
 '@S9S_MB_2U_LIB.S9S_MB_2U(SCH_1):JTAG_DBP_TDI_R':
 C_SIGNAL='@s9s_mb_2u_lib.s9s_mb_2u(sch_1):jtag_dbp_tdi_r';
NODE_NAME     J42 5
 '@S9S_MB_2U_LIB.S9S_MB_2U(SCH_1):PAGE133_I44@PURE_QUANTA.SCONN60_ASP21410801(CHIPS)':
 '5': CDS_PINID='\5\';
NODE_NAME     R763 2
 '@S9S_MB_2U_LIB.S9S_MB_2U(SCH_1):PAGE133_I70@PURE_QUANTA.Q_RES(CHIPS)':
 'B': CDS_PINID='B';
NET_NAME
'JTAG_DBP_TDO'
 '@S9S_MB_2U_LIB.S9S_MB_2U(SCH_1):JTAG_DBP_TDO':
 C_SIGNAL='@s9s_mb_2u_lib.s9s_mb_2u(sch_1):jtag_dbp_tdo';
NODE_NAME     R776 2
 '@S9S_MB_2U_LIB.S9S_MB_2U(SCH_1):PAGE133_I7@PURE_QUANTA.Q_RES(CHIPS)':
 'B': CDS_PINID='B';
NODE_NAME     U17 12
 '@S9S_MB_2U_LIB.S9S_MB_2U(SCH_1):PAGE134_I80@PURE_QUANTA.74CBTLV3126PW(CHIPS)':
 '4A': CDS_PINID='\4a\';
NODE_NAME     R752 1
 '@S9S_MB_2U_LIB.S9S_MB_2U(SCH_1):PAGE134_I127@PURE_QUANTA.Q_RES(CHIPS)':
 'A': CDS_PINID='A';
NODE_NAME     R1366 1
 '@S9S_MB_2U_LIB.S9S_MB_2U(SCH_1):PAGE226_I64@PURE_QUANTA.Q_RES(CHIPS)':
 'A': CDS_PINID='A';
NET_NAME
'JTAG_DBP_TDO_PCH'
 '@S9S_MB_2U_LIB.S9S_MB_2U(SCH_1):JTAG_DBP_TDO_PCH':
 C_SIGNAL='@s9s_mb_2u_lib.s9s_mb_2u(sch_1):jtag_dbp_tdo_pch';
NODE_NAME     R752 2
 '@S9S_MB_2U_LIB.S9S_MB_2U(SCH_1):PAGE134_I127@PURE_QUANTA.Q_RES(CHIPS)':
 'B': CDS_PINID='B';
NODE_NAME     R747 2
 '@S9S_MB_2U_LIB.S9S_MB_2U(SCH_1):PAGE134_I176@PURE_QUANTA.Q_RES(CHIPS)':
 'B': CDS_PINID='B';
NODE_NAME     U4 BE36
 '@S9S_MB_2U_LIB.S9S_MB_2U(SCH_1):PAGE174_I36@PURE_QUANTA.EMMITSBURG_REV0P9(CHIPS)':
 'JTAG_TDO': CDS_PINID='JTAG_TDO';
NET_NAME
'JTAG_DBP_TDO_R'
 '@S9S_MB_2U_LIB.S9S_MB_2U(SCH_1):JTAG_DBP_TDO_R':
 C_SIGNAL='@s9s_mb_2u_lib.s9s_mb_2u(sch_1):jtag_dbp_tdo_r';
NODE_NAME     R776 1
 '@S9S_MB_2U_LIB.S9S_MB_2U(SCH_1):PAGE133_I7@PURE_QUANTA.Q_RES(CHIPS)':
 'A': CDS_PINID='A';
NODE_NAME     J42 4
 '@S9S_MB_2U_LIB.S9S_MB_2U(SCH_1):PAGE133_I44@PURE_QUANTA.SCONN60_ASP21410801(CHIPS)':
 '4': CDS_PINID='\4\';
NET_NAME
'JTAG_DBP_TMS'
 '@S9S_MB_2U_LIB.S9S_MB_2U(SCH_1):JTAG_DBP_TMS':
 C_SIGNAL='@s9s_mb_2u_lib.s9s_mb_2u(sch_1):jtag_dbp_tms';
NODE_NAME     R775 2
 '@S9S_MB_2U_LIB.S9S_MB_2U(SCH_1):PAGE133_I5@PURE_QUANTA.Q_RES(CHIPS)':
 'B': CDS_PINID='B';
NODE_NAME     U17 2
 '@S9S_MB_2U_LIB.S9S_MB_2U(SCH_1):PAGE134_I80@PURE_QUANTA.74CBTLV3126PW(CHIPS)':
 '1A': CDS_PINID='\1a\';
NODE_NAME     R754 1
 '@S9S_MB_2U_LIB.S9S_MB_2U(SCH_1):PAGE134_I126@PURE_QUANTA.Q_RES(CHIPS)':
 'A': CDS_PINID='A';
NODE_NAME     R480 1
 '@S9S_MB_2U_LIB.S9S_MB_2U(SCH_1):PAGE226_I59@PURE_QUANTA.Q_RES(CHIPS)':
 'A': CDS_PINID='A';
NET_NAME
'JTAG_DBP_TMS_PCH'
 '@S9S_MB_2U_LIB.S9S_MB_2U(SCH_1):JTAG_DBP_TMS_PCH':
 C_SIGNAL='@s9s_mb_2u_lib.s9s_mb_2u(sch_1):jtag_dbp_tms_pch';
NODE_NAME     R754 2
 '@S9S_MB_2U_LIB.S9S_MB_2U(SCH_1):PAGE134_I126@PURE_QUANTA.Q_RES(CHIPS)':
 'B': CDS_PINID='B';
NODE_NAME     R749 2
 '@S9S_MB_2U_LIB.S9S_MB_2U(SCH_1):PAGE134_I179@PURE_QUANTA.Q_RES(CHIPS)':
 'B': CDS_PINID='B';
NODE_NAME     U4 BD37
 '@S9S_MB_2U_LIB.S9S_MB_2U(SCH_1):PAGE174_I36@PURE_QUANTA.EMMITSBURG_REV0P9(CHIPS)':
 'JTAG_TMS': CDS_PINID='JTAG_TMS';
NET_NAME
'JTAG_DBP_TMS_R'
 '@S9S_MB_2U_LIB.S9S_MB_2U(SCH_1):JTAG_DBP_TMS_R':
 C_SIGNAL='@s9s_mb_2u_lib.s9s_mb_2u(sch_1):jtag_dbp_tms_r';
NODE_NAME     R775 1
 '@S9S_MB_2U_LIB.S9S_MB_2U(SCH_1):PAGE133_I5@PURE_QUANTA.Q_RES(CHIPS)':
 'A': CDS_PINID='A';
NODE_NAME     J42 2
 '@S9S_MB_2U_LIB.S9S_MB_2U(SCH_1):PAGE133_I44@PURE_QUANTA.SCONN60_ASP21410801(CHIPS)':
 '2': CDS_PINID='\2\';
NET_NAME
'JTAG_MUX_CPU0_GTL_TDI'
 '@S9S_MB_2U_LIB.S9S_MB_2U(SCH_1):JTAG_MUX_CPU0_GTL_TDI':
 C_SIGNAL='@s9s_mb_2u_lib.s9s_mb_2u(sch_1):jtag_mux_cpu0_gtl_tdi';
NODE_NAME     R4 1
 '@S9S_MB_2U_LIB.S9S_MB_2U(SCH_1):PAGE13_I29@PURE_QUANTA.Q_RES(CHIPS)':
 'A': CDS_PINID='A';
NODE_NAME     U21 3
 '@S9S_MB_2U_LIB.S9S_MB_2U(SCH_1):PAGE135_I58@PURE_QUANTA.NC7SB3157(CHIPS)':
 'B0': CDS_PINID='B0';
NODE_NAME     R741 2
 '@S9S_MB_2U_LIB.S9S_MB_2U(SCH_1):PAGE135_I66@PURE_QUANTA.Q_RES(CHIPS)':
 'B': CDS_PINID='B';
NET_NAME
'JTAG_MUX_CPU1_GTL_TDI'
 '@S9S_MB_2U_LIB.S9S_MB_2U(SCH_1):JTAG_MUX_CPU1_GTL_TDI':
 C_SIGNAL='@s9s_mb_2u_lib.s9s_mb_2u(sch_1):jtag_mux_cpu1_gtl_tdi';
NODE_NAME     R64 1
 '@S9S_MB_2U_LIB.S9S_MB_2U(SCH_1):PAGE44_I9@PURE_QUANTA.Q_RES(CHIPS)':
 'A': CDS_PINID='A';
NODE_NAME     U21 1
 '@S9S_MB_2U_LIB.S9S_MB_2U(SCH_1):PAGE135_I58@PURE_QUANTA.NC7SB3157(CHIPS)':
 'B1': CDS_PINID='B1';
NODE_NAME     R743 2
 '@S9S_MB_2U_LIB.S9S_MB_2U(SCH_1):PAGE135_I65@PURE_QUANTA.Q_RES(CHIPS)':
 'B': CDS_PINID='B';
NODE_NAME     U16 2
 '@S9S_MB_2U_LIB.S9S_MB_2U(SCH_1):PAGE135_I115@PURE_QUANTA.74LVC1G66GV(CHIPS)':
 'Z': CDS_PINID='Z';
NET_NAME
'JTAG_MUX_QS_GTL_TDO'
 '@S9S_MB_2U_LIB.S9S_MB_2U(SCH_1):JTAG_MUX_QS_GTL_TDO':
 C_SIGNAL='@s9s_mb_2u_lib.s9s_mb_2u(sch_1):jtag_mux_qs_gtl_tdo';
NODE_NAME     U17 11
 '@S9S_MB_2U_LIB.S9S_MB_2U(SCH_1):PAGE134_I80@PURE_QUANTA.74CBTLV3126PW(CHIPS)':
 '4B': CDS_PINID='\4b\';
NODE_NAME     U22 4
 '@S9S_MB_2U_LIB.S9S_MB_2U(SCH_1):PAGE135_I71@PURE_QUANTA.NC7SB3157(CHIPS)':
 'A': CDS_PINID='A';
NET_NAME
'JTAG_PLD_JTAGEN'
 '@S9S_MB_2U_LIB.S9S_MB_2U(SCH_1):JTAG_PLD_JTAGEN':
 C_SIGNAL='@s9s_mb_2u_lib.s9s_mb_2u(sch_1):jtag_pld_jtagen';
NODE_NAME     R919 2
 '@S9S_MB_2U_LIB.S9S_MB_2U(SCH_1):PAGE210_I75@PURE_QUANTA.Q_RES(CHIPS)':
 'B': CDS_PINID='B';
NODE_NAME     R920 1
 '@S9S_MB_2U_LIB.S9S_MB_2U(SCH_1):PAGE210_I76@PURE_QUANTA.Q_RES(CHIPS)':
 'A': CDS_PINID='A';
NODE_NAME     U249 E14
 '@S9S_MB_2U_LIB.S9S_MB_2U(SCH_1):PAGE311_I70@PURE_QUANTA.LCMXO3LF9400C5BG484C(CHIPS)':
 'PT31C||JTAGENB': CDS_PINID='\pt31c||jtagenb\';
NET_NAME
'JTAG_PLD_TCK_R'
 '@S9S_MB_2U_LIB.S9S_MB_2U(SCH_1):JTAG_PLD_TCK_R':
 C_SIGNAL='@s9s_mb_2u_lib.s9s_mb_2u(sch_1):jtag_pld_tck_r';
NODE_NAME     R806 1
 '@S9S_MB_2U_LIB.S9S_MB_2U(SCH_1):PAGE210_I54@PURE_QUANTA.Q_RES(CHIPS)':
 'A': CDS_PINID='A';
NODE_NAME     U249 D10
 '@S9S_MB_2U_LIB.S9S_MB_2U(SCH_1):PAGE311_I70@PURE_QUANTA.LCMXO3LF9400C5BG484C(CHIPS)':
 'PT22C||TCK': CDS_PINID='\pt22c||tck\';
NET_NAME
'JTAG_PLD_TDI_R'
 '@S9S_MB_2U_LIB.S9S_MB_2U(SCH_1):JTAG_PLD_TDI_R':
 C_SIGNAL='@s9s_mb_2u_lib.s9s_mb_2u(sch_1):jtag_pld_tdi_r';
NODE_NAME     R803 1
 '@S9S_MB_2U_LIB.S9S_MB_2U(SCH_1):PAGE210_I19@PURE_QUANTA.Q_RES(CHIPS)':
 'A': CDS_PINID='A';
NODE_NAME     U249 E9
 '@S9S_MB_2U_LIB.S9S_MB_2U(SCH_1):PAGE311_I70@PURE_QUANTA.LCMXO3LF9400C5BG484C(CHIPS)':
 'PT15D||TDI': CDS_PINID='\pt15d||tdi\';
NET_NAME
'JTAG_PLD_TDO_R'
 '@S9S_MB_2U_LIB.S9S_MB_2U(SCH_1):JTAG_PLD_TDO_R':
 C_SIGNAL='@s9s_mb_2u_lib.s9s_mb_2u(sch_1):jtag_pld_tdo_r';
NODE_NAME     R804 1
 '@S9S_MB_2U_LIB.S9S_MB_2U(SCH_1):PAGE210_I20@PURE_QUANTA.Q_RES(CHIPS)':
 'A': CDS_PINID='A';
NODE_NAME     U249 E8
 '@S9S_MB_2U_LIB.S9S_MB_2U(SCH_1):PAGE311_I70@PURE_QUANTA.LCMXO3LF9400C5BG484C(CHIPS)':
 'PT15C||TDO': CDS_PINID='\pt15c||tdo\';
NODE_NAME     R1440 1
 '@S9S_MB_2U_LIB.S9S_MB_2U(SCH_1):PAGE209_I41@PURE_QUANTA.Q_RES(CHIPS)':
 'A': CDS_PINID='A';
NET_NAME
'JTAG_PLD_TMS_R'
 '@S9S_MB_2U_LIB.S9S_MB_2U(SCH_1):JTAG_PLD_TMS_R':
 C_SIGNAL='@s9s_mb_2u_lib.s9s_mb_2u(sch_1):jtag_pld_tms_r';
NODE_NAME     R805 1
 '@S9S_MB_2U_LIB.S9S_MB_2U(SCH_1):PAGE210_I25@PURE_QUANTA.Q_RES(CHIPS)':
 'A': CDS_PINID='A';
NODE_NAME     U249 C10
 '@S9S_MB_2U_LIB.S9S_MB_2U(SCH_1):PAGE311_I70@PURE_QUANTA.LCMXO3LF9400C5BG484C(CHIPS)':
 'PT22D||TMS': CDS_PINID='\pt22d||tms\';
NET_NAME
'JTAG_QS_MUX_GTL_TDI'
 '@S9S_MB_2U_LIB.S9S_MB_2U(SCH_1):JTAG_QS_MUX_GTL_TDI':
 C_SIGNAL='@s9s_mb_2u_lib.s9s_mb_2u(sch_1):jtag_qs_mux_gtl_tdi';
NODE_NAME     U17 6
 '@S9S_MB_2U_LIB.S9S_MB_2U(SCH_1):PAGE134_I80@PURE_QUANTA.74CBTLV3126PW(CHIPS)':
 '2B': CDS_PINID='\2b\';
NODE_NAME     U21 4
 '@S9S_MB_2U_LIB.S9S_MB_2U(SCH_1):PAGE135_I58@PURE_QUANTA.NC7SB3157(CHIPS)':
 'A': CDS_PINID='A';
NET_NAME
'JTAG_RST_DBP_RSMRST_N'
 '@S9S_MB_2U_LIB.S9S_MB_2U(SCH_1):JTAG_RST_DBP_RSMRST_N':
 C_SIGNAL='@s9s_mb_2u_lib.s9s_mb_2u(sch_1):jtag_rst_dbp_rsmrst_n';
NODE_NAME     J42 42
 '@S9S_MB_2U_LIB.S9S_MB_2U(SCH_1):PAGE133_I44@PURE_QUANTA.SCONN60_ASP21410801(CHIPS)':
 '42': CDS_PINID='\42\';
NODE_NAME     R772 1
 '@S9S_MB_2U_LIB.S9S_MB_2U(SCH_1):PAGE133_I118@PURE_QUANTA.Q_RES(CHIPS)':
 'A': CDS_PINID='A';
NET_NAME
'JTAG_RST_DBP_RST_CO_N'
 '@S9S_MB_2U_LIB.S9S_MB_2U(SCH_1):JTAG_RST_DBP_RST_CO_N':
 C_SIGNAL='@s9s_mb_2u_lib.s9s_mb_2u(sch_1):jtag_rst_dbp_rst_co_n';
NODE_NAME     J42 6
 '@S9S_MB_2U_LIB.S9S_MB_2U(SCH_1):PAGE133_I44@PURE_QUANTA.SCONN60_ASP21410801(CHIPS)':
 '6': CDS_PINID='\6\';
NODE_NAME     R767 2
 '@S9S_MB_2U_LIB.S9S_MB_2U(SCH_1):PAGE133_I113@PURE_QUANTA.Q_RES(CHIPS)':
 'B': CDS_PINID='B';
NODE_NAME     C549 1
 '@S9S_MB_2U_LIB.S9S_MB_2U(SCH_1):PAGE133_I129@PURE_QUANTA.Q_CAP(CHIPS)':
 'A': CDS_PINID='A';
NET_NAME
'JTAG_TRC_PCH_PTI0_CLK'
 '@S9S_MB_2U_LIB.S9S_MB_2U(SCH_1):JTAG_TRC_PCH_PTI0_CLK':
 C_SIGNAL='@s9s_mb_2u_lib.s9s_mb_2u(sch_1):jtag_trc_pch_pti0_clk';
NODE_NAME     J42 13
 '@S9S_MB_2U_LIB.S9S_MB_2U(SCH_1):PAGE133_I44@PURE_QUANTA.SCONN60_ASP21410801(CHIPS)':
 '13': CDS_PINID='\13\';
NODE_NAME     U4 BD33
 '@S9S_MB_2U_LIB.S9S_MB_2U(SCH_1):PAGE175_I93@PURE_QUANTA.EMMITSBURG_REV0P9(CHIPS)':
 'GPPC_B_0_GSXDOUT': CDS_PINID='GPPC_B_0_GSXDOUT';
NET_NAME
'JTAG_TRC_PCH_PTI1_CLK'
 '@S9S_MB_2U_LIB.S9S_MB_2U(SCH_1):JTAG_TRC_PCH_PTI1_CLK':
 C_SIGNAL='@s9s_mb_2u_lib.s9s_mb_2u(sch_1):jtag_trc_pch_pti1_clk';
NODE_NAME     J42 59
 '@S9S_MB_2U_LIB.S9S_MB_2U(SCH_1):PAGE133_I44@PURE_QUANTA.SCONN60_ASP21410801(CHIPS)':
 '59': CDS_PINID='\59\';
NODE_NAME     U4 BD23
 '@S9S_MB_2U_LIB.S9S_MB_2U(SCH_1):PAGE175_I93@PURE_QUANTA.EMMITSBURG_REV0P9(CHIPS)':
 'GPPC_B_23': CDS_PINID='GPPC_B_23';
NET_NAME
'JTAG_TRC_PCH_PTI<0>'
 '@S9S_MB_2U_LIB.S9S_MB_2U(SCH_1):JTAG_TRC_PCH_PTI'<0>:
 C_SIGNAL='@s9s_mb_2u_lib.s9s_mb_2u(sch_1):jtag_trc_pch_pti(0)';
NODE_NAME     J42 19
 '@S9S_MB_2U_LIB.S9S_MB_2U(SCH_1):PAGE133_I44@PURE_QUANTA.SCONN60_ASP21410801(CHIPS)':
 '19': CDS_PINID='\19\';
NODE_NAME     U4 BE32
 '@S9S_MB_2U_LIB.S9S_MB_2U(SCH_1):PAGE175_I93@PURE_QUANTA.EMMITSBURG_REV0P9(CHIPS)':
 'GPPC_B_1_GSXSLOAD': CDS_PINID='GPPC_B_1_GSXSLOAD';
NET_NAME
'JTAG_TRC_PCH_PTI<10>'
 '@S9S_MB_2U_LIB.S9S_MB_2U(SCH_1):JTAG_TRC_PCH_PTI'<10>:
 C_SIGNAL='@s9s_mb_2u_lib.s9s_mb_2u(sch_1):jtag_trc_pch_pti(10)';
NODE_NAME     J42 39
 '@S9S_MB_2U_LIB.S9S_MB_2U(SCH_1):PAGE133_I44@PURE_QUANTA.SCONN60_ASP21410801(CHIPS)':
 '39': CDS_PINID='\39\';
NODE_NAME     U4 BF27
 '@S9S_MB_2U_LIB.S9S_MB_2U(SCH_1):PAGE175_I93@PURE_QUANTA.EMMITSBURG_REV0P9(CHIPS)':
 'GPPC_B_17_HS_UART1_TXD': CDS_PINID='GPPC_B_17_HS_UART1_TXD';
NET_NAME
'JTAG_TRC_PCH_PTI<11>'
 '@S9S_MB_2U_LIB.S9S_MB_2U(SCH_1):JTAG_TRC_PCH_PTI'<11>:
 C_SIGNAL='@s9s_mb_2u_lib.s9s_mb_2u(sch_1):jtag_trc_pch_pti(11)';
NODE_NAME     J42 41
 '@S9S_MB_2U_LIB.S9S_MB_2U(SCH_1):PAGE133_I44@PURE_QUANTA.SCONN60_ASP21410801(CHIPS)':
 '41': CDS_PINID='\41\';
NODE_NAME     U4 BD25
 '@S9S_MB_2U_LIB.S9S_MB_2U(SCH_1):PAGE175_I93@PURE_QUANTA.EMMITSBURG_REV0P9(CHIPS)':
 'GPPC_B_18_HS_UART1_RTS_N': CDS_PINID='GPPC_B_18_HS_UART1_RTS_N';
NET_NAME
'JTAG_TRC_PCH_PTI<12>'
 '@S9S_MB_2U_LIB.S9S_MB_2U(SCH_1):JTAG_TRC_PCH_PTI'<12>:
 C_SIGNAL='@s9s_mb_2u_lib.s9s_mb_2u(sch_1):jtag_trc_pch_pti(12)';
NODE_NAME     J42 43
 '@S9S_MB_2U_LIB.S9S_MB_2U(SCH_1):PAGE133_I44@PURE_QUANTA.SCONN60_ASP21410801(CHIPS)':
 '43': CDS_PINID='\43\';
NODE_NAME     U4 BF25
 '@S9S_MB_2U_LIB.S9S_MB_2U(SCH_1):PAGE175_I93@PURE_QUANTA.EMMITSBURG_REV0P9(CHIPS)':
 'GPPC_B_19_HS_UART1_CTS_N': CDS_PINID='GPPC_B_19_HS_UART1_CTS_N';
NET_NAME
'JTAG_TRC_PCH_PTI<13>'
 '@S9S_MB_2U_LIB.S9S_MB_2U(SCH_1):JTAG_TRC_PCH_PTI'<13>:
 C_SIGNAL='@s9s_mb_2u_lib.s9s_mb_2u(sch_1):jtag_trc_pch_pti(13)';
NODE_NAME     J42 45
 '@S9S_MB_2U_LIB.S9S_MB_2U(SCH_1):PAGE133_I44@PURE_QUANTA.SCONN60_ASP21410801(CHIPS)':
 '45': CDS_PINID='\45\';
NODE_NAME     U4 BE24
 '@S9S_MB_2U_LIB.S9S_MB_2U(SCH_1):PAGE175_I93@PURE_QUANTA.EMMITSBURG_REV0P9(CHIPS)':
 'GPPC_B_20': CDS_PINID='GPPC_B_20';
NET_NAME
'JTAG_TRC_PCH_PTI<14>'
 '@S9S_MB_2U_LIB.S9S_MB_2U(SCH_1):JTAG_TRC_PCH_PTI'<14>:
 C_SIGNAL='@s9s_mb_2u_lib.s9s_mb_2u(sch_1):jtag_trc_pch_pti(14)';
NODE_NAME     J42 47
 '@S9S_MB_2U_LIB.S9S_MB_2U(SCH_1):PAGE133_I44@PURE_QUANTA.SCONN60_ASP21410801(CHIPS)':
 '47': CDS_PINID='\47\';
NODE_NAME     U4 BF23
 '@S9S_MB_2U_LIB.S9S_MB_2U(SCH_1):PAGE175_I93@PURE_QUANTA.EMMITSBURG_REV0P9(CHIPS)':
 'GPPC_B_21': CDS_PINID='GPPC_B_21';
NET_NAME
'JTAG_TRC_PCH_PTI<15>'
 '@S9S_MB_2U_LIB.S9S_MB_2U(SCH_1):JTAG_TRC_PCH_PTI'<15>:
 C_SIGNAL='@s9s_mb_2u_lib.s9s_mb_2u(sch_1):jtag_trc_pch_pti(15)';
NODE_NAME     J42 49
 '@S9S_MB_2U_LIB.S9S_MB_2U(SCH_1):PAGE133_I44@PURE_QUANTA.SCONN60_ASP21410801(CHIPS)':
 '49': CDS_PINID='\49\';
NODE_NAME     U4 BE22
 '@S9S_MB_2U_LIB.S9S_MB_2U(SCH_1):PAGE175_I93@PURE_QUANTA.EMMITSBURG_REV0P9(CHIPS)':
 'GPPC_B_22': CDS_PINID='GPPC_B_22';
NET_NAME
'JTAG_TRC_PCH_PTI<1>'
 '@S9S_MB_2U_LIB.S9S_MB_2U(SCH_1):JTAG_TRC_PCH_PTI'<1>:
 C_SIGNAL='@s9s_mb_2u_lib.s9s_mb_2u(sch_1):jtag_trc_pch_pti(1)';
NODE_NAME     J42 21
 '@S9S_MB_2U_LIB.S9S_MB_2U(SCH_1):PAGE133_I44@PURE_QUANTA.SCONN60_ASP21410801(CHIPS)':
 '21': CDS_PINID='\21\';
NODE_NAME     U4 BF33
 '@S9S_MB_2U_LIB.S9S_MB_2U(SCH_1):PAGE175_I93@PURE_QUANTA.EMMITSBURG_REV0P9(CHIPS)':
 'GPPC_B_2_GSXDIN': CDS_PINID='GPPC_B_2_GSXDIN';
NET_NAME
'JTAG_TRC_PCH_PTI<2>'
 '@S9S_MB_2U_LIB.S9S_MB_2U(SCH_1):JTAG_TRC_PCH_PTI'<2>:
 C_SIGNAL='@s9s_mb_2u_lib.s9s_mb_2u(sch_1):jtag_trc_pch_pti(2)';
NODE_NAME     J42 23
 '@S9S_MB_2U_LIB.S9S_MB_2U(SCH_1):PAGE133_I44@PURE_QUANTA.SCONN60_ASP21410801(CHIPS)':
 '23': CDS_PINID='\23\';
NODE_NAME     U4 BD31
 '@S9S_MB_2U_LIB.S9S_MB_2U(SCH_1):PAGE175_I93@PURE_QUANTA.EMMITSBURG_REV0P9(CHIPS)':
 'GPPC_B_3_GSXRESET_N': CDS_PINID='GPPC_B_3_GSXRESET_N';
NET_NAME
'JTAG_TRC_PCH_PTI<3>'
 '@S9S_MB_2U_LIB.S9S_MB_2U(SCH_1):JTAG_TRC_PCH_PTI'<3>:
 C_SIGNAL='@s9s_mb_2u_lib.s9s_mb_2u(sch_1):jtag_trc_pch_pti(3)';
NODE_NAME     J42 25
 '@S9S_MB_2U_LIB.S9S_MB_2U(SCH_1):PAGE133_I44@PURE_QUANTA.SCONN60_ASP21410801(CHIPS)':
 '25': CDS_PINID='\25\';
NODE_NAME     U4 BE30
 '@S9S_MB_2U_LIB.S9S_MB_2U(SCH_1):PAGE175_I93@PURE_QUANTA.EMMITSBURG_REV0P9(CHIPS)':
 'GPPC_B_4_GSXCLK': CDS_PINID='GPPC_B_4_GSXCLK';
NET_NAME
'JTAG_TRC_PCH_PTI<4>'
 '@S9S_MB_2U_LIB.S9S_MB_2U(SCH_1):JTAG_TRC_PCH_PTI'<4>:
 C_SIGNAL='@s9s_mb_2u_lib.s9s_mb_2u(sch_1):jtag_trc_pch_pti(4)';
NODE_NAME     J42 27
 '@S9S_MB_2U_LIB.S9S_MB_2U(SCH_1):PAGE133_I44@PURE_QUANTA.SCONN60_ASP21410801(CHIPS)':
 '27': CDS_PINID='\27\';
NODE_NAME     U4 BF31
 '@S9S_MB_2U_LIB.S9S_MB_2U(SCH_1):PAGE175_I93@PURE_QUANTA.EMMITSBURG_REV0P9(CHIPS)':
 'GPPC_B_5_USB2_OCB_0': CDS_PINID='GPPC_B_5_USB2_OCB_0';
NET_NAME
'JTAG_TRC_PCH_PTI<5>'
 '@S9S_MB_2U_LIB.S9S_MB_2U(SCH_1):JTAG_TRC_PCH_PTI'<5>:
 C_SIGNAL='@s9s_mb_2u_lib.s9s_mb_2u(sch_1):jtag_trc_pch_pti(5)';
NODE_NAME     J42 29
 '@S9S_MB_2U_LIB.S9S_MB_2U(SCH_1):PAGE133_I44@PURE_QUANTA.SCONN60_ASP21410801(CHIPS)':
 '29': CDS_PINID='\29\';
NODE_NAME     U4 BD29
 '@S9S_MB_2U_LIB.S9S_MB_2U(SCH_1):PAGE175_I93@PURE_QUANTA.EMMITSBURG_REV0P9(CHIPS)':
 'GPPC_B_12_HS_UART0_RXD': CDS_PINID='GPPC_B_12_HS_UART0_RXD';
NET_NAME
'JTAG_TRC_PCH_PTI<6>'
 '@S9S_MB_2U_LIB.S9S_MB_2U(SCH_1):JTAG_TRC_PCH_PTI'<6>:
 C_SIGNAL='@s9s_mb_2u_lib.s9s_mb_2u(sch_1):jtag_trc_pch_pti(6)';
NODE_NAME     J42 31
 '@S9S_MB_2U_LIB.S9S_MB_2U(SCH_1):PAGE133_I44@PURE_QUANTA.SCONN60_ASP21410801(CHIPS)':
 '31': CDS_PINID='\31\';
NODE_NAME     U4 BE28
 '@S9S_MB_2U_LIB.S9S_MB_2U(SCH_1):PAGE175_I93@PURE_QUANTA.EMMITSBURG_REV0P9(CHIPS)':
 'GPPC_B_13_HS_UART0_TXD': CDS_PINID='GPPC_B_13_HS_UART0_TXD';
NODE_NAME     R2132 1
 '@S9S_MB_2U_LIB.S9S_MB_2U(SCH_1):PAGE190_I91@PURE_QUANTA.Q_RES(CHIPS)':
 'A': CDS_PINID='A';
NODE_NAME     R2134 1
 '@S9S_MB_2U_LIB.S9S_MB_2U(SCH_1):PAGE189_I109@PURE_QUANTA.Q_RES(CHIPS)':
 'A': CDS_PINID='A';
NODE_NAME     J104 2
 '@S9S_MB_2U_LIB.S9S_MB_2U(SCH_1):PAGE189_I134@PURE_QUANTA.CONN14_210HP207GBR1(CHIPS)':
 '2': CDS_PINID='\2\';
NET_NAME
'JTAG_TRC_PCH_PTI<7>'
 '@S9S_MB_2U_LIB.S9S_MB_2U(SCH_1):JTAG_TRC_PCH_PTI'<7>:
 C_SIGNAL='@s9s_mb_2u_lib.s9s_mb_2u(sch_1):jtag_trc_pch_pti(7)';
NODE_NAME     J42 33
 '@S9S_MB_2U_LIB.S9S_MB_2U(SCH_1):PAGE133_I44@PURE_QUANTA.SCONN60_ASP21410801(CHIPS)':
 '33': CDS_PINID='\33\';
NODE_NAME     U4 BF29
 '@S9S_MB_2U_LIB.S9S_MB_2U(SCH_1):PAGE175_I93@PURE_QUANTA.EMMITSBURG_REV0P9(CHIPS)':
 'GPPC_B_14_HS_UART0_RTS_N': CDS_PINID='GPPC_B_14_HS_UART0_RTS_N';
NET_NAME
'JTAG_TRC_PCH_PTI<8>'
 '@S9S_MB_2U_LIB.S9S_MB_2U(SCH_1):JTAG_TRC_PCH_PTI'<8>:
 C_SIGNAL='@s9s_mb_2u_lib.s9s_mb_2u(sch_1):jtag_trc_pch_pti(8)';
NODE_NAME     J42 35
 '@S9S_MB_2U_LIB.S9S_MB_2U(SCH_1):PAGE133_I44@PURE_QUANTA.SCONN60_ASP21410801(CHIPS)':
 '35': CDS_PINID='\35\';
NODE_NAME     U4 BD27
 '@S9S_MB_2U_LIB.S9S_MB_2U(SCH_1):PAGE175_I93@PURE_QUANTA.EMMITSBURG_REV0P9(CHIPS)':
 'GPPC_B_15_HS_UART0_CTS_N': CDS_PINID='GPPC_B_15_HS_UART0_CTS_N';
NET_NAME
'JTAG_TRC_PCH_PTI<9>'
 '@S9S_MB_2U_LIB.S9S_MB_2U(SCH_1):JTAG_TRC_PCH_PTI'<9>:
 C_SIGNAL='@s9s_mb_2u_lib.s9s_mb_2u(sch_1):jtag_trc_pch_pti(9)';
NODE_NAME     J42 37
 '@S9S_MB_2U_LIB.S9S_MB_2U(SCH_1):PAGE133_I44@PURE_QUANTA.SCONN60_ASP21410801(CHIPS)':
 '37': CDS_PINID='\37\';
NODE_NAME     U4 BE26
 '@S9S_MB_2U_LIB.S9S_MB_2U(SCH_1):PAGE175_I93@PURE_QUANTA.EMMITSBURG_REV0P9(CHIPS)':
 'GPPC_B_16_HS_UART1_RXD': CDS_PINID='GPPC_B_16_HS_UART1_RXD';
NET_NAME
'LED_CPU_RMCA_CATERR'
 '@S9S_MB_2U_LIB.S9S_MB_2U(SCH_1):LED_CPU_RMCA_CATERR':
 C_SIGNAL='@s9s_mb_2u_lib.s9s_mb_2u(sch_1):led_cpu_rmca_caterr';
NODE_NAME     Q33 D
 '@S9S_MB_2U_LIB.S9S_MB_2U(SCH_1):PAGE207_I272@PURE_QUANTA.MOSFET_NCH_GDS_ESD_PROTECTED(CHIPS)':
 'D': CDS_PINID='D';
NODE_NAME     D6 A
 '@S9S_MB_2U_LIB.S9S_MB_2U(SCH_1):PAGE207_I279@PURE_QUANTA.Q_LED(CHIPS)':
 'A': CDS_PINID='A';
NODE_NAME     R366 2
 '@S9S_MB_2U_LIB.S9S_MB_2U(SCH_1):PAGE207_I280@PURE_QUANTA.Q_RES(CHIPS)':
 'B': CDS_PINID='B';
NET_NAME
'LED_CPU_RMCA_CATERR_R'
 '@S9S_MB_2U_LIB.S9S_MB_2U(SCH_1):LED_CPU_RMCA_CATERR_R':
 C_SIGNAL='@s9s_mb_2u_lib.s9s_mb_2u(sch_1):led_cpu_rmca_caterr_r';
NODE_NAME     R2339 1
 '@S9S_MB_2U_LIB.S9S_MB_2U(SCH_1):PAGE207_I268@PURE_QUANTA.Q_RES(CHIPS)':
 'A': CDS_PINID='A';
NODE_NAME     Q33 S
 '@S9S_MB_2U_LIB.S9S_MB_2U(SCH_1):PAGE207_I272@PURE_QUANTA.MOSFET_NCH_GDS_ESD_PROTECTED(CHIPS)':
 'S': CDS_PINID='S';
NET_NAME
'LED_FM_PCH_SLP_S3_N'
 '@S9S_MB_2U_LIB.S9S_MB_2U(SCH_1):LED_FM_PCH_SLP_S3_N':
 C_SIGNAL='@s9s_mb_2u_lib.s9s_mb_2u(sch_1):led_fm_pch_slp_s3_n';
NODE_NAME     D95 A
 '@S9S_MB_2U_LIB.S9S_MB_2U(SCH_1):PAGE242_I35@PURE_QUANTA.Q_LED(CHIPS)':
 'A': CDS_PINID='A';
NODE_NAME     R3078 1
 '@S9S_MB_2U_LIB.S9S_MB_2U(SCH_1):PAGE242_I41@PURE_QUANTA.Q_RES(CHIPS)':
 'A': CDS_PINID='A';
NET_NAME
'LED_FM_PCH_SLP_S3_N_D'
 '@S9S_MB_2U_LIB.S9S_MB_2U(SCH_1):LED_FM_PCH_SLP_S3_N_D':
 C_SIGNAL='@s9s_mb_2u_lib.s9s_mb_2u(sch_1):led_fm_pch_slp_s3_n_d';
NODE_NAME     Q78 6
 '@S9S_MB_2U_LIB.S9S_MB_2U(SCH_1):PAGE242_I34@PURE_QUANTA.MOSFET_NCH_DUAL(CHIPS)':
 'D1': CDS_PINID='D1';
NODE_NAME     D95 C
 '@S9S_MB_2U_LIB.S9S_MB_2U(SCH_1):PAGE242_I35@PURE_QUANTA.Q_LED(CHIPS)':
 'C': CDS_PINID='C';
NET_NAME
'LED_FM_PCH_SLP_S4_N'
 '@S9S_MB_2U_LIB.S9S_MB_2U(SCH_1):LED_FM_PCH_SLP_S4_N':
 C_SIGNAL='@s9s_mb_2u_lib.s9s_mb_2u(sch_1):led_fm_pch_slp_s4_n';
NODE_NAME     D94 A
 '@S9S_MB_2U_LIB.S9S_MB_2U(SCH_1):PAGE242_I11@PURE_QUANTA.Q_LED(CHIPS)':
 'A': CDS_PINID='A';
NODE_NAME     R3073 1
 '@S9S_MB_2U_LIB.S9S_MB_2U(SCH_1):PAGE242_I12@PURE_QUANTA.Q_RES(CHIPS)':
 'A': CDS_PINID='A';
NET_NAME
'LED_FM_PCH_SLP_S4_N_D'
 '@S9S_MB_2U_LIB.S9S_MB_2U(SCH_1):LED_FM_PCH_SLP_S4_N_D':
 C_SIGNAL='@s9s_mb_2u_lib.s9s_mb_2u(sch_1):led_fm_pch_slp_s4_n_d';
NODE_NAME     Q77 3
 '@S9S_MB_2U_LIB.S9S_MB_2U(SCH_1):PAGE242_I3@PURE_QUANTA.MOSFET_NCH_DUAL(CHIPS)':
 'D2': CDS_PINID='D2';
NODE_NAME     D94 C
 '@S9S_MB_2U_LIB.S9S_MB_2U(SCH_1):PAGE242_I11@PURE_QUANTA.Q_LED(CHIPS)':
 'C': CDS_PINID='C';
NET_NAME
'LED_HDD_ACTIVITY_B_N'
 '@S9S_MB_2U_LIB.S9S_MB_2U(SCH_1):LED_HDD_ACTIVITY_B_N':
 C_SIGNAL='@s9s_mb_2u_lib.s9s_mb_2u(sch_1):led_hdd_activity_b_n';
NODE_NAME     R3297 1
 '@S9S_MB_2U_LIB.S9S_MB_2U(SCH_1):PAGE182_I303@PURE_QUANTA.Q_RES(CHIPS)':
 'A': CDS_PINID='A';
NODE_NAME     U239 4
 '@S9S_MB_2U_LIB.S9S_MB_2U(SCH_1):PAGE182_I315@PURE_QUANTA.74LVC1G126SE7(CHIPS)':
 'Y': CDS_PINID='Y';
NODE_NAME     R4607 1
 '@S9S_MB_2U_LIB.S9S_MB_2U(SCH_1):PAGE313_I183@PURE_QUANTA.Q_RES(CHIPS)':
 'A': CDS_PINID='A';
NODE_NAME     R3254 2
 '@S9S_MB_2U_LIB.S9S_MB_2U(SCH_1):PAGE227_I49@PURE_QUANTA.Q_RES(CHIPS)':
 'B': CDS_PINID='B';
NET_NAME
'LED_HDD_ACTIVITY_B_PLD_N'
 '@S9S_MB_2U_LIB.S9S_MB_2U(SCH_1):LED_HDD_ACTIVITY_B_PLD_N':
 C_SIGNAL='@s9s_mb_2u_lib.s9s_mb_2u(sch_1):led_hdd_activity_b_pld_n';
NODE_NAME     U249 AA22
 '@S9S_MB_2U_LIB.S9S_MB_2U(SCH_1):PAGE313_I1@PURE_QUANTA.LCMXO3LF9400C5BG484C(CHIPS)':
 'PR29A': CDS_PINID='PR29A';
NODE_NAME     R4607 2
 '@S9S_MB_2U_LIB.S9S_MB_2U(SCH_1):PAGE313_I183@PURE_QUANTA.Q_RES(CHIPS)':
 'B': CDS_PINID='B';
NET_NAME
'LED_HDD_ACTIVITY_N'
 '@S9S_MB_2U_LIB.S9S_MB_2U(SCH_1):LED_HDD_ACTIVITY_N':
 C_SIGNAL='@s9s_mb_2u_lib.s9s_mb_2u(sch_1):led_hdd_activity_n';
NODE_NAME     U239 2
 '@S9S_MB_2U_LIB.S9S_MB_2U(SCH_1):PAGE182_I315@PURE_QUANTA.74LVC1G126SE7(CHIPS)':
 'A': CDS_PINID='A';
NODE_NAME     R3295 2
 '@S9S_MB_2U_LIB.S9S_MB_2U(SCH_1):PAGE182_I317@PURE_QUANTA.Q_RES(CHIPS)':
 'B': CDS_PINID='B';
NODE_NAME     R3294 2
 '@S9S_MB_2U_LIB.S9S_MB_2U(SCH_1):PAGE182_I320@PURE_QUANTA.Q_RES(CHIPS)':
 'B': CDS_PINID='B';
NET_NAME
'LED_M2_SSD_0_ACT_N'
 '@S9S_MB_2U_LIB.S9S_MB_2U(SCH_1):LED_M2_SSD_0_ACT_N':
 C_SIGNAL='@s9s_mb_2u_lib.s9s_mb_2u(sch_1):led_m2_ssd_0_act_n';
NODE_NAME     J59 10
 '@S9S_MB_2U_LIB.S9S_MB_2U(SCH_1):PAGE182_I178@PURE_QUANTA.SCONN75K_APCI0155P004A(CHIPS)':
 'DAS_DSS#||LED1#': CDS_PINID='\das_dss#||led1#\';
NODE_NAME     R3294 1
 '@S9S_MB_2U_LIB.S9S_MB_2U(SCH_1):PAGE182_I320@PURE_QUANTA.Q_RES(CHIPS)':
 'A': CDS_PINID='A';
NET_NAME
'LED_P12V_AUX_R1'
 '@S9S_MB_2U_LIB.S9S_MB_2U(SCH_1):LED_P12V_AUX_R1':
 C_SIGNAL='@s9s_mb_2u_lib.s9s_mb_2u(sch_1):led_p12v_aux_r1';
NODE_NAME     D142 A
 '@S9S_MB_2U_LIB.S9S_MB_2U(SCH_1):PAGE241_I58@PURE_QUANTA.Q_LED(CHIPS)':
 'A': CDS_PINID='A';
NODE_NAME     R4702 1
 '@S9S_MB_2U_LIB.S9S_MB_2U(SCH_1):PAGE241_I64@PURE_QUANTA.Q_RES(CHIPS)':
 'A': CDS_PINID='A';
NET_NAME
'LED_P12V_AUX_R2'
 '@S9S_MB_2U_LIB.S9S_MB_2U(SCH_1):LED_P12V_AUX_R2':
 C_SIGNAL='@s9s_mb_2u_lib.s9s_mb_2u(sch_1):led_p12v_aux_r2';
NODE_NAME     R4702 2
 '@S9S_MB_2U_LIB.S9S_MB_2U(SCH_1):PAGE241_I64@PURE_QUANTA.Q_RES(CHIPS)':
 'B': CDS_PINID='B';
NODE_NAME     R4704 1
 '@S9S_MB_2U_LIB.S9S_MB_2U(SCH_1):PAGE241_I65@PURE_QUANTA.Q_RES(CHIPS)':
 'A': CDS_PINID='A';
NET_NAME
'LED_P12V_AUX_R3'
 '@S9S_MB_2U_LIB.S9S_MB_2U(SCH_1):LED_P12V_AUX_R3':
 C_SIGNAL='@s9s_mb_2u_lib.s9s_mb_2u(sch_1):led_p12v_aux_r3';
NODE_NAME     R4704 2
 '@S9S_MB_2U_LIB.S9S_MB_2U(SCH_1):PAGE241_I65@PURE_QUANTA.Q_RES(CHIPS)':
 'B': CDS_PINID='B';
NODE_NAME     R4706 1
 '@S9S_MB_2U_LIB.S9S_MB_2U(SCH_1):PAGE241_I66@PURE_QUANTA.Q_RES(CHIPS)':
 'A': CDS_PINID='A';
NET_NAME
'LED_P12V_PSU_R1'
 '@S9S_MB_2U_LIB.S9S_MB_2U(SCH_1):LED_P12V_PSU_R1':
 C_SIGNAL='@s9s_mb_2u_lib.s9s_mb_2u(sch_1):led_p12v_psu_r1';
NODE_NAME     D143 A
 '@S9S_MB_2U_LIB.S9S_MB_2U(SCH_1):PAGE241_I49@PURE_QUANTA.Q_LED(CHIPS)':
 'A': CDS_PINID='A';
NODE_NAME     R4703 1
 '@S9S_MB_2U_LIB.S9S_MB_2U(SCH_1):PAGE241_I61@PURE_QUANTA.Q_RES(CHIPS)':
 'A': CDS_PINID='A';
NET_NAME
'LED_P12V_PSU_R2'
 '@S9S_MB_2U_LIB.S9S_MB_2U(SCH_1):LED_P12V_PSU_R2':
 C_SIGNAL='@s9s_mb_2u_lib.s9s_mb_2u(sch_1):led_p12v_psu_r2';
NODE_NAME     R4703 2
 '@S9S_MB_2U_LIB.S9S_MB_2U(SCH_1):PAGE241_I61@PURE_QUANTA.Q_RES(CHIPS)':
 'B': CDS_PINID='B';
NODE_NAME     R4705 1
 '@S9S_MB_2U_LIB.S9S_MB_2U(SCH_1):PAGE241_I62@PURE_QUANTA.Q_RES(CHIPS)':
 'A': CDS_PINID='A';
NET_NAME
'LED_P12V_PSU_R3'
 '@S9S_MB_2U_LIB.S9S_MB_2U(SCH_1):LED_P12V_PSU_R3':
 C_SIGNAL='@s9s_mb_2u_lib.s9s_mb_2u(sch_1):led_p12v_psu_r3';
NODE_NAME     R4705 2
 '@S9S_MB_2U_LIB.S9S_MB_2U(SCH_1):PAGE241_I62@PURE_QUANTA.Q_RES(CHIPS)':
 'B': CDS_PINID='B';
NODE_NAME     R4707 1
 '@S9S_MB_2U_LIB.S9S_MB_2U(SCH_1):PAGE241_I63@PURE_QUANTA.Q_RES(CHIPS)':
 'A': CDS_PINID='A';
NET_NAME
'LED_P12V_SCM_FAULT'
 '@S9S_MB_2U_LIB.S9S_MB_2U(SCH_1):LED_P12V_SCM_FAULT':
 C_SIGNAL='@s9s_mb_2u_lib.s9s_mb_2u(sch_1):led_p12v_scm_fault';
NODE_NAME     D144 A
 '@S9S_MB_2U_LIB.S9S_MB_2U(SCH_1):PAGE241_I67@PURE_QUANTA.Q_LED(CHIPS)':
 'A': CDS_PINID='A';
NODE_NAME     R4711 1
 '@S9S_MB_2U_LIB.S9S_MB_2U(SCH_1):PAGE241_I68@PURE_QUANTA.Q_RES(CHIPS)':
 'A': CDS_PINID='A';
NET_NAME
'LED_P12V_SCM_FAULT_D1'
 '@S9S_MB_2U_LIB.S9S_MB_2U(SCH_1):LED_P12V_SCM_FAULT_D1':
 C_SIGNAL='@s9s_mb_2u_lib.s9s_mb_2u(sch_1):led_p12v_scm_fault_d1';
NODE_NAME     Q150 6
 '@S9S_MB_2U_LIB.S9S_MB_2U(SCH_1):PAGE241_I69@PURE_QUANTA.MOSFET_NCH_DUAL(CHIPS)':
 'D1': CDS_PINID='D1';
NODE_NAME     Q150 5
 '@S9S_MB_2U_LIB.S9S_MB_2U(SCH_1):PAGE241_I72@PURE_QUANTA.MOSFET_NCH_DUAL(CHIPS)':
 'G2': CDS_PINID='G2';
NODE_NAME     R4710 2
 '@S9S_MB_2U_LIB.S9S_MB_2U(SCH_1):PAGE241_I74@PURE_QUANTA.Q_RES(CHIPS)':
 'B': CDS_PINID='B';
NET_NAME
'LED_P12V_SCM_FAULT_D2'
 '@S9S_MB_2U_LIB.S9S_MB_2U(SCH_1):LED_P12V_SCM_FAULT_D2':
 C_SIGNAL='@s9s_mb_2u_lib.s9s_mb_2u(sch_1):led_p12v_scm_fault_d2';
NODE_NAME     D144 C
 '@S9S_MB_2U_LIB.S9S_MB_2U(SCH_1):PAGE241_I67@PURE_QUANTA.Q_LED(CHIPS)':
 'C': CDS_PINID='C';
NODE_NAME     Q150 3
 '@S9S_MB_2U_LIB.S9S_MB_2U(SCH_1):PAGE241_I72@PURE_QUANTA.MOSFET_NCH_DUAL(CHIPS)':
 'D2': CDS_PINID='D2';
NET_NAME
'LED_P3V3'
 '@S9S_MB_2U_LIB.S9S_MB_2U(SCH_1):LED_P3V3':
 C_SIGNAL='@s9s_mb_2u_lib.s9s_mb_2u(sch_1):led_p3v3';
NODE_NAME     D99 A
 '@S9S_MB_2U_LIB.S9S_MB_2U(SCH_1):PAGE242_I60@PURE_QUANTA.Q_LED(CHIPS)':
 'A': CDS_PINID='A';
NODE_NAME     R3100 1
 '@S9S_MB_2U_LIB.S9S_MB_2U(SCH_1):PAGE242_I64@PURE_QUANTA.Q_RES(CHIPS)':
 'A': CDS_PINID='A';
NET_NAME
'LED_P5V'
 '@S9S_MB_2U_LIB.S9S_MB_2U(SCH_1):LED_P5V':
 C_SIGNAL='@s9s_mb_2u_lib.s9s_mb_2u(sch_1):led_p5v';
NODE_NAME     D98 A
 '@S9S_MB_2U_LIB.S9S_MB_2U(SCH_1):PAGE242_I53@PURE_QUANTA.Q_LED(CHIPS)':
 'A': CDS_PINID='A';
NODE_NAME     R3102 1
 '@S9S_MB_2U_LIB.S9S_MB_2U(SCH_1):PAGE242_I61@PURE_QUANTA.Q_RES(CHIPS)':
 'A': CDS_PINID='A';
NET_NAME
'LED_P5V_AUX'
 '@S9S_MB_2U_LIB.S9S_MB_2U(SCH_1):LED_P5V_AUX':
 C_SIGNAL='@s9s_mb_2u_lib.s9s_mb_2u(sch_1):led_p5v_aux';
NODE_NAME     D97 A
 '@S9S_MB_2U_LIB.S9S_MB_2U(SCH_1):PAGE242_I52@PURE_QUANTA.Q_LED(CHIPS)':
 'A': CDS_PINID='A';
NODE_NAME     R3101 1
 '@S9S_MB_2U_LIB.S9S_MB_2U(SCH_1):PAGE242_I62@PURE_QUANTA.Q_RES(CHIPS)':
 'A': CDS_PINID='A';
NET_NAME
'LED_PWRGD_CPUPWRGD_GTL'
 '@S9S_MB_2U_LIB.S9S_MB_2U(SCH_1):LED_PWRGD_CPUPWRGD_GTL':
 C_SIGNAL='@s9s_mb_2u_lib.s9s_mb_2u(sch_1):led_pwrgd_cpupwrgd_gtl';
NODE_NAME     D89 A
 '@S9S_MB_2U_LIB.S9S_MB_2U(SCH_1):PAGE241_I11@PURE_QUANTA.Q_LED(CHIPS)':
 'A': CDS_PINID='A';
NODE_NAME     R1044 1
 '@S9S_MB_2U_LIB.S9S_MB_2U(SCH_1):PAGE241_I40@PURE_QUANTA.Q_RES(CHIPS)':
 'A': CDS_PINID='A';
NET_NAME
'LED_PWRGD_CPUPWRGD_GTL_D'
 '@S9S_MB_2U_LIB.S9S_MB_2U(SCH_1):LED_PWRGD_CPUPWRGD_GTL_D':
 C_SIGNAL='@s9s_mb_2u_lib.s9s_mb_2u(sch_1):led_pwrgd_cpupwrgd_gtl_d';
NODE_NAME     Q88 6
 '@S9S_MB_2U_LIB.S9S_MB_2U(SCH_1):PAGE241_I8@PURE_QUANTA.MOSFET_NCH_DUAL(CHIPS)':
 'D1': CDS_PINID='D1';
NODE_NAME     D89 C
 '@S9S_MB_2U_LIB.S9S_MB_2U(SCH_1):PAGE241_I11@PURE_QUANTA.Q_LED(CHIPS)':
 'C': CDS_PINID='C';
NET_NAME
'LED_PWRGD_P1V05_PCH_AUX'
 '@S9S_MB_2U_LIB.S9S_MB_2U(SCH_1):LED_PWRGD_P1V05_PCH_AUX':
 C_SIGNAL='@s9s_mb_2u_lib.s9s_mb_2u(sch_1):led_pwrgd_p1v05_pch_aux';
NODE_NAME     R3072 1
 '@S9S_MB_2U_LIB.S9S_MB_2U(SCH_1):PAGE242_I15@PURE_QUANTA.Q_RES(CHIPS)':
 'A': CDS_PINID='A';
NODE_NAME     D92 A
 '@S9S_MB_2U_LIB.S9S_MB_2U(SCH_1):PAGE242_I42@PURE_QUANTA.Q_LED(CHIPS)':
 'A': CDS_PINID='A';
NET_NAME
'LED_PWRGD_P1V05_PCH_AUX_D'
 '@S9S_MB_2U_LIB.S9S_MB_2U(SCH_1):LED_PWRGD_P1V05_PCH_AUX_D':
 C_SIGNAL='@s9s_mb_2u_lib.s9s_mb_2u(sch_1):led_pwrgd_p1v05_pch_aux_d';
NODE_NAME     Q76 3
 '@S9S_MB_2U_LIB.S9S_MB_2U(SCH_1):PAGE242_I8@PURE_QUANTA.MOSFET_NCH_DUAL(CHIPS)':
 'D2': CDS_PINID='D2';
NODE_NAME     D92 C
 '@S9S_MB_2U_LIB.S9S_MB_2U(SCH_1):PAGE242_I42@PURE_QUANTA.Q_LED(CHIPS)':
 'C': CDS_PINID='C';
NET_NAME
'LED_PWRGD_P1V8_PCH_AUX'
 '@S9S_MB_2U_LIB.S9S_MB_2U(SCH_1):LED_PWRGD_P1V8_PCH_AUX':
 C_SIGNAL='@s9s_mb_2u_lib.s9s_mb_2u(sch_1):led_pwrgd_p1v8_pch_aux';
NODE_NAME     D91 A
 '@S9S_MB_2U_LIB.S9S_MB_2U(SCH_1):PAGE242_I18@PURE_QUANTA.Q_LED(CHIPS)':
 'A': CDS_PINID='A';
NODE_NAME     R3071 1
 '@S9S_MB_2U_LIB.S9S_MB_2U(SCH_1):PAGE242_I19@PURE_QUANTA.Q_RES(CHIPS)':
 'A': CDS_PINID='A';
NET_NAME
'LED_PWRGD_P1V8_PCH_AUX_D'
 '@S9S_MB_2U_LIB.S9S_MB_2U(SCH_1):LED_PWRGD_P1V8_PCH_AUX_D':
 C_SIGNAL='@s9s_mb_2u_lib.s9s_mb_2u(sch_1):led_pwrgd_p1v8_pch_aux_d';
NODE_NAME     Q76 6
 '@S9S_MB_2U_LIB.S9S_MB_2U(SCH_1):PAGE242_I17@PURE_QUANTA.MOSFET_NCH_DUAL(CHIPS)':
 'D1': CDS_PINID='D1';
NODE_NAME     D91 C
 '@S9S_MB_2U_LIB.S9S_MB_2U(SCH_1):PAGE242_I18@PURE_QUANTA.Q_LED(CHIPS)':
 'C': CDS_PINID='C';
NET_NAME
'LED_PWRGD_PCH_PWROK_R'
 '@S9S_MB_2U_LIB.S9S_MB_2U(SCH_1):LED_PWRGD_PCH_PWROK_R':
 C_SIGNAL='@s9s_mb_2u_lib.s9s_mb_2u(sch_1):led_pwrgd_pch_pwrok_r';
NODE_NAME     D87 A
 '@S9S_MB_2U_LIB.S9S_MB_2U(SCH_1):PAGE241_I20@PURE_QUANTA.Q_LED(CHIPS)':
 'A': CDS_PINID='A';
NODE_NAME     R3068 1
 '@S9S_MB_2U_LIB.S9S_MB_2U(SCH_1):PAGE241_I38@PURE_QUANTA.Q_RES(CHIPS)':
 'A': CDS_PINID='A';
NET_NAME
'LED_PWRGD_PCH_PWROK_R_D'
 '@S9S_MB_2U_LIB.S9S_MB_2U(SCH_1):LED_PWRGD_PCH_PWROK_R_D':
 C_SIGNAL='@s9s_mb_2u_lib.s9s_mb_2u(sch_1):led_pwrgd_pch_pwrok_r_d';
NODE_NAME     Q87 6
 '@S9S_MB_2U_LIB.S9S_MB_2U(SCH_1):PAGE241_I17@PURE_QUANTA.MOSFET_NCH_DUAL(CHIPS)':
 'D1': CDS_PINID='D1';
NODE_NAME     D87 C
 '@S9S_MB_2U_LIB.S9S_MB_2U(SCH_1):PAGE241_I20@PURE_QUANTA.Q_LED(CHIPS)':
 'C': CDS_PINID='C';
NET_NAME
'LED_PWRGD_PS_PWROK_PLD'
 '@S9S_MB_2U_LIB.S9S_MB_2U(SCH_1):LED_PWRGD_PS_PWROK_PLD':
 C_SIGNAL='@s9s_mb_2u_lib.s9s_mb_2u(sch_1):led_pwrgd_ps_pwrok_pld';
NODE_NAME     D96 A
 '@S9S_MB_2U_LIB.S9S_MB_2U(SCH_1):PAGE242_I31@PURE_QUANTA.Q_LED(CHIPS)':
 'A': CDS_PINID='A';
NODE_NAME     R3075 1
 '@S9S_MB_2U_LIB.S9S_MB_2U(SCH_1):PAGE242_I37@PURE_QUANTA.Q_RES(CHIPS)':
 'A': CDS_PINID='A';
NET_NAME
'LED_PWRGD_PS_PWROK_PLD_D'
 '@S9S_MB_2U_LIB.S9S_MB_2U(SCH_1):LED_PWRGD_PS_PWROK_PLD_D':
 C_SIGNAL='@s9s_mb_2u_lib.s9s_mb_2u(sch_1):led_pwrgd_ps_pwrok_pld_d';
NODE_NAME     Q78 3
 '@S9S_MB_2U_LIB.S9S_MB_2U(SCH_1):PAGE242_I26@PURE_QUANTA.MOSFET_NCH_DUAL(CHIPS)':
 'D2': CDS_PINID='D2';
NODE_NAME     D96 C
 '@S9S_MB_2U_LIB.S9S_MB_2U(SCH_1):PAGE242_I31@PURE_QUANTA.Q_LED(CHIPS)':
 'C': CDS_PINID='C';
NET_NAME
'LED_PWRGD_PVCCD_HV_CPU0'
 '@S9S_MB_2U_LIB.S9S_MB_2U(SCH_1):LED_PWRGD_PVCCD_HV_CPU0':
 C_SIGNAL='@s9s_mb_2u_lib.s9s_mb_2u(sch_1):led_pwrgd_pvccd_hv_cpu0';
NODE_NAME     D73 A
 '@S9S_MB_2U_LIB.S9S_MB_2U(SCH_1):PAGE305_I22@PURE_QUANTA.Q_LED(CHIPS)':
 'A': CDS_PINID='A';
NODE_NAME     R3086 1
 '@S9S_MB_2U_LIB.S9S_MB_2U(SCH_1):PAGE305_I49@PURE_QUANTA.Q_RES(CHIPS)':
 'A': CDS_PINID='A';
NET_NAME
'LED_PWRGD_PVCCD_HV_CPU0_D'
 '@S9S_MB_2U_LIB.S9S_MB_2U(SCH_1):LED_PWRGD_PVCCD_HV_CPU0_D':
 C_SIGNAL='@s9s_mb_2u_lib.s9s_mb_2u(sch_1):led_pwrgd_pvccd_hv_cpu0_d';
NODE_NAME     Q79 6
 '@S9S_MB_2U_LIB.S9S_MB_2U(SCH_1):PAGE305_I8@PURE_QUANTA.MOSFET_NCH_DUAL(CHIPS)':
 'D1': CDS_PINID='D1';
NODE_NAME     D73 C
 '@S9S_MB_2U_LIB.S9S_MB_2U(SCH_1):PAGE305_I22@PURE_QUANTA.Q_LED(CHIPS)':
 'C': CDS_PINID='C';
NET_NAME
'LED_PWRGD_PVCCD_HV_CPU1'
 '@S9S_MB_2U_LIB.S9S_MB_2U(SCH_1):LED_PWRGD_PVCCD_HV_CPU1':
 C_SIGNAL='@s9s_mb_2u_lib.s9s_mb_2u(sch_1):led_pwrgd_pvccd_hv_cpu1';
NODE_NAME     D80 A
 '@S9S_MB_2U_LIB.S9S_MB_2U(SCH_1):PAGE306_I19@PURE_QUANTA.Q_LED(CHIPS)':
 'A': CDS_PINID='A';
NODE_NAME     R3093 1
 '@S9S_MB_2U_LIB.S9S_MB_2U(SCH_1):PAGE306_I20@PURE_QUANTA.Q_RES(CHIPS)':
 'A': CDS_PINID='A';
NET_NAME
'LED_PWRGD_PVCCD_HV_CPU1_D'
 '@S9S_MB_2U_LIB.S9S_MB_2U(SCH_1):LED_PWRGD_PVCCD_HV_CPU1_D':
 C_SIGNAL='@s9s_mb_2u_lib.s9s_mb_2u(sch_1):led_pwrgd_pvccd_hv_cpu1_d';
NODE_NAME     Q84 6
 '@S9S_MB_2U_LIB.S9S_MB_2U(SCH_1):PAGE306_I18@PURE_QUANTA.MOSFET_NCH_DUAL(CHIPS)':
 'D1': CDS_PINID='D1';
NODE_NAME     D80 C
 '@S9S_MB_2U_LIB.S9S_MB_2U(SCH_1):PAGE306_I19@PURE_QUANTA.Q_LED(CHIPS)':
 'C': CDS_PINID='C';
NET_NAME
'LED_PWRGD_PVCCFA_EHV_CPU0'
 '@S9S_MB_2U_LIB.S9S_MB_2U(SCH_1):LED_PWRGD_PVCCFA_EHV_CPU0':
 C_SIGNAL='@s9s_mb_2u_lib.s9s_mb_2u(sch_1):led_pwrgd_pvccfa_ehv_cpu0';
NODE_NAME     D75 A
 '@S9S_MB_2U_LIB.S9S_MB_2U(SCH_1):PAGE305_I13@PURE_QUANTA.Q_LED(CHIPS)':
 'A': CDS_PINID='A';
NODE_NAME     R3089 1
 '@S9S_MB_2U_LIB.S9S_MB_2U(SCH_1):PAGE305_I51@PURE_QUANTA.Q_RES(CHIPS)':
 'A': CDS_PINID='A';
NET_NAME
'LED_PWRGD_PVCCFA_EHV_CPU0_D'
 '@S9S_MB_2U_LIB.S9S_MB_2U(SCH_1):LED_PWRGD_PVCCFA_EHV_CPU0_D':
 C_SIGNAL='@s9s_mb_2u_lib.s9s_mb_2u(sch_1):led_pwrgd_pvccfa_ehv_cpu0_d';
NODE_NAME     Q80 6
 '@S9S_MB_2U_LIB.S9S_MB_2U(SCH_1):PAGE305_I4@PURE_QUANTA.MOSFET_NCH_DUAL(CHIPS)':
 'D1': CDS_PINID='D1';
NODE_NAME     D75 C
 '@S9S_MB_2U_LIB.S9S_MB_2U(SCH_1):PAGE305_I13@PURE_QUANTA.Q_LED(CHIPS)':
 'C': CDS_PINID='C';
NET_NAME
'LED_PWRGD_PVCCFA_EHV_CPU1'
 '@S9S_MB_2U_LIB.S9S_MB_2U(SCH_1):LED_PWRGD_PVCCFA_EHV_CPU1':
 C_SIGNAL='@s9s_mb_2u_lib.s9s_mb_2u(sch_1):led_pwrgd_pvccfa_ehv_cpu1';
NODE_NAME     D82 A
 '@S9S_MB_2U_LIB.S9S_MB_2U(SCH_1):PAGE306_I13@PURE_QUANTA.Q_LED(CHIPS)':
 'A': CDS_PINID='A';
NODE_NAME     R3096 1
 '@S9S_MB_2U_LIB.S9S_MB_2U(SCH_1):PAGE306_I15@PURE_QUANTA.Q_RES(CHIPS)':
 'A': CDS_PINID='A';
NET_NAME
'LED_PWRGD_PVCCFA_EHV_CPU1_D'
 '@S9S_MB_2U_LIB.S9S_MB_2U(SCH_1):LED_PWRGD_PVCCFA_EHV_CPU1_D':
 C_SIGNAL='@s9s_mb_2u_lib.s9s_mb_2u(sch_1):led_pwrgd_pvccfa_ehv_cpu1_d';
NODE_NAME     Q85 6
 '@S9S_MB_2U_LIB.S9S_MB_2U(SCH_1):PAGE306_I6@PURE_QUANTA.MOSFET_NCH_DUAL(CHIPS)':
 'D1': CDS_PINID='D1';
NODE_NAME     D82 C
 '@S9S_MB_2U_LIB.S9S_MB_2U(SCH_1):PAGE306_I13@PURE_QUANTA.Q_LED(CHIPS)':
 'C': CDS_PINID='C';
NET_NAME
'LED_PWRGD_PVCCFA_EHV_FIVRA_CPU0'
 '@S9S_MB_2U_LIB.S9S_MB_2U(SCH_1):LED_PWRGD_PVCCFA_EHV_FIVRA_CPU0':
 C_SIGNAL='@s9s_mb_2u_lib.s9s_mb_2u(sch_1):led_pwrgd_pvccfa_ehv_fivra_cpu0';
NODE_NAME     D76 A
 '@S9S_MB_2U_LIB.S9S_MB_2U(SCH_1):PAGE305_I10@PURE_QUANTA.Q_LED(CHIPS)':
 'A': CDS_PINID='A';
NODE_NAME     R3088 1
 '@S9S_MB_2U_LIB.S9S_MB_2U(SCH_1):PAGE305_I52@PURE_QUANTA.Q_RES(CHIPS)':
 'A': CDS_PINID='A';
NET_NAME
'LED_PWRGD_PVCCFA_EHV_FIVRA_CPU1'
 '@S9S_MB_2U_LIB.S9S_MB_2U(SCH_1):LED_PWRGD_PVCCFA_EHV_FIVRA_CPU1':
 C_SIGNAL='@s9s_mb_2u_lib.s9s_mb_2u(sch_1):led_pwrgd_pvccfa_ehv_fivra_cpu1';
NODE_NAME     D83 A
 '@S9S_MB_2U_LIB.S9S_MB_2U(SCH_1):PAGE306_I11@PURE_QUANTA.Q_LED(CHIPS)':
 'A': CDS_PINID='A';
NODE_NAME     R3095 1
 '@S9S_MB_2U_LIB.S9S_MB_2U(SCH_1):PAGE306_I12@PURE_QUANTA.Q_RES(CHIPS)':
 'A': CDS_PINID='A';
NET_NAME
'LED_PWRGD_PVCCFA_EHV_FIVRA_CP_1'
 '@S9S_MB_2U_LIB.S9S_MB_2U(SCH_1):LED_PWRGD_PVCCFA_EHV_FIVRA_CPU0_D':
 C_SIGNAL='@s9s_mb_2u_lib.s9s_mb_2u(sch_1):led_pwrgd_pvccfa_ehv_fivra_cpu0_d';
NODE_NAME     Q80 3
 '@S9S_MB_2U_LIB.S9S_MB_2U(SCH_1):PAGE305_I2@PURE_QUANTA.MOSFET_NCH_DUAL(CHIPS)':
 'D2': CDS_PINID='D2';
NODE_NAME     D76 C
 '@S9S_MB_2U_LIB.S9S_MB_2U(SCH_1):PAGE305_I10@PURE_QUANTA.Q_LED(CHIPS)':
 'C': CDS_PINID='C';
NET_NAME
'LED_PWRGD_PVCCFA_EHV_FIVRA_CP_2'
 '@S9S_MB_2U_LIB.S9S_MB_2U(SCH_1):LED_PWRGD_PVCCFA_EHV_FIVRA_CPU1_D':
 C_SIGNAL='@s9s_mb_2u_lib.s9s_mb_2u(sch_1):led_pwrgd_pvccfa_ehv_fivra_cpu1_d';
NODE_NAME     Q85 3
 '@S9S_MB_2U_LIB.S9S_MB_2U(SCH_1):PAGE306_I3@PURE_QUANTA.MOSFET_NCH_DUAL(CHIPS)':
 'D2': CDS_PINID='D2';
NODE_NAME     D83 C
 '@S9S_MB_2U_LIB.S9S_MB_2U(SCH_1):PAGE306_I11@PURE_QUANTA.Q_LED(CHIPS)':
 'C': CDS_PINID='C';
NET_NAME
'LED_PWRGD_PVCCINFAON_CPU0'
 '@S9S_MB_2U_LIB.S9S_MB_2U(SCH_1):LED_PWRGD_PVCCINFAON_CPU0':
 C_SIGNAL='@s9s_mb_2u_lib.s9s_mb_2u(sch_1):led_pwrgd_pvccinfaon_cpu0';
NODE_NAME     D77 A
 '@S9S_MB_2U_LIB.S9S_MB_2U(SCH_1):PAGE305_I44@PURE_QUANTA.Q_LED(CHIPS)':
 'A': CDS_PINID='A';
NODE_NAME     R3092 1
 '@S9S_MB_2U_LIB.S9S_MB_2U(SCH_1):PAGE305_I55@PURE_QUANTA.Q_RES(CHIPS)':
 'A': CDS_PINID='A';
NET_NAME
'LED_PWRGD_PVCCINFAON_CPU0_D'
 '@S9S_MB_2U_LIB.S9S_MB_2U(SCH_1):LED_PWRGD_PVCCINFAON_CPU0_D':
 C_SIGNAL='@s9s_mb_2u_lib.s9s_mb_2u(sch_1):led_pwrgd_pvccinfaon_cpu0_d';
NODE_NAME     Q81 6
 '@S9S_MB_2U_LIB.S9S_MB_2U(SCH_1):PAGE305_I41@PURE_QUANTA.MOSFET_NCH_DUAL(CHIPS)':
 'D1': CDS_PINID='D1';
NODE_NAME     D77 C
 '@S9S_MB_2U_LIB.S9S_MB_2U(SCH_1):PAGE305_I44@PURE_QUANTA.Q_LED(CHIPS)':
 'C': CDS_PINID='C';
NET_NAME
'LED_PWRGD_PVCCINFAON_CPU1'
 '@S9S_MB_2U_LIB.S9S_MB_2U(SCH_1):LED_PWRGD_PVCCINFAON_CPU1':
 C_SIGNAL='@s9s_mb_2u_lib.s9s_mb_2u(sch_1):led_pwrgd_pvccinfaon_cpu1';
NODE_NAME     D84 A
 '@S9S_MB_2U_LIB.S9S_MB_2U(SCH_1):PAGE306_I36@PURE_QUANTA.Q_LED(CHIPS)':
 'A': CDS_PINID='A';
NODE_NAME     R3099 1
 '@S9S_MB_2U_LIB.S9S_MB_2U(SCH_1):PAGE306_I41@PURE_QUANTA.Q_RES(CHIPS)':
 'A': CDS_PINID='A';
NET_NAME
'LED_PWRGD_PVCCINFAON_CPU1_D'
 '@S9S_MB_2U_LIB.S9S_MB_2U(SCH_1):LED_PWRGD_PVCCINFAON_CPU1_D':
 C_SIGNAL='@s9s_mb_2u_lib.s9s_mb_2u(sch_1):led_pwrgd_pvccinfaon_cpu1_d';
NODE_NAME     Q86 6
 '@S9S_MB_2U_LIB.S9S_MB_2U(SCH_1):PAGE306_I35@PURE_QUANTA.MOSFET_NCH_DUAL(CHIPS)':
 'D1': CDS_PINID='D1';
NODE_NAME     D84 C
 '@S9S_MB_2U_LIB.S9S_MB_2U(SCH_1):PAGE306_I36@PURE_QUANTA.Q_LED(CHIPS)':
 'C': CDS_PINID='C';
NET_NAME
'LED_PWRGD_PVCCIN_CPU0'
 '@S9S_MB_2U_LIB.S9S_MB_2U(SCH_1):LED_PWRGD_PVCCIN_CPU0':
 C_SIGNAL='@s9s_mb_2u_lib.s9s_mb_2u(sch_1):led_pwrgd_pvccin_cpu0';
NODE_NAME     D79 A
 '@S9S_MB_2U_LIB.S9S_MB_2U(SCH_1):PAGE305_I35@PURE_QUANTA.Q_LED(CHIPS)':
 'A': CDS_PINID='A';
NODE_NAME     R3091 1
 '@S9S_MB_2U_LIB.S9S_MB_2U(SCH_1):PAGE305_I53@PURE_QUANTA.Q_RES(CHIPS)':
 'A': CDS_PINID='A';
NET_NAME
'LED_PWRGD_PVCCIN_CPU0_D'
 '@S9S_MB_2U_LIB.S9S_MB_2U(SCH_1):LED_PWRGD_PVCCIN_CPU0_D':
 C_SIGNAL='@s9s_mb_2u_lib.s9s_mb_2u(sch_1):led_pwrgd_pvccin_cpu0_d';
NODE_NAME     Q83 6
 '@S9S_MB_2U_LIB.S9S_MB_2U(SCH_1):PAGE305_I32@PURE_QUANTA.MOSFET_NCH_DUAL(CHIPS)':
 'D1': CDS_PINID='D1';
NODE_NAME     D79 C
 '@S9S_MB_2U_LIB.S9S_MB_2U(SCH_1):PAGE305_I35@PURE_QUANTA.Q_LED(CHIPS)':
 'C': CDS_PINID='C';
NET_NAME
'LED_PWRGD_PVCCIN_CPU1'
 '@S9S_MB_2U_LIB.S9S_MB_2U(SCH_1):LED_PWRGD_PVCCIN_CPU1':
 C_SIGNAL='@s9s_mb_2u_lib.s9s_mb_2u(sch_1):led_pwrgd_pvccin_cpu1';
NODE_NAME     D86 A
 '@S9S_MB_2U_LIB.S9S_MB_2U(SCH_1):PAGE306_I30@PURE_QUANTA.Q_LED(CHIPS)':
 'A': CDS_PINID='A';
NODE_NAME     R3098 1
 '@S9S_MB_2U_LIB.S9S_MB_2U(SCH_1):PAGE306_I37@PURE_QUANTA.Q_RES(CHIPS)':
 'A': CDS_PINID='A';
NET_NAME
'LED_PWRGD_PVCCIN_CPU1_D'
 '@S9S_MB_2U_LIB.S9S_MB_2U(SCH_1):LED_PWRGD_PVCCIN_CPU1_D':
 C_SIGNAL='@s9s_mb_2u_lib.s9s_mb_2u(sch_1):led_pwrgd_pvccin_cpu1_d';
NODE_NAME     D86 C
 '@S9S_MB_2U_LIB.S9S_MB_2U(SCH_1):PAGE306_I30@PURE_QUANTA.Q_LED(CHIPS)':
 'C': CDS_PINID='C';
NODE_NAME     Q83 3
 '@S9S_MB_2U_LIB.S9S_MB_2U(SCH_1):PAGE306_I43@PURE_QUANTA.MOSFET_NCH_DUAL(CHIPS)':
 'D2': CDS_PINID='D2';
NET_NAME
'LED_PWRGD_PVNN_MAIN_CPU0'
 '@S9S_MB_2U_LIB.S9S_MB_2U(SCH_1):LED_PWRGD_PVNN_MAIN_CPU0':
 C_SIGNAL='@s9s_mb_2u_lib.s9s_mb_2u(sch_1):led_pwrgd_pvnn_main_cpu0';
NODE_NAME     D78 A
 '@S9S_MB_2U_LIB.S9S_MB_2U(SCH_1):PAGE305_I43@PURE_QUANTA.Q_LED(CHIPS)':
 'A': CDS_PINID='A';
NODE_NAME     R3090 1
 '@S9S_MB_2U_LIB.S9S_MB_2U(SCH_1):PAGE305_I54@PURE_QUANTA.Q_RES(CHIPS)':
 'A': CDS_PINID='A';
NET_NAME
'LED_PWRGD_PVNN_MAIN_CPU0_D'
 '@S9S_MB_2U_LIB.S9S_MB_2U(SCH_1):LED_PWRGD_PVNN_MAIN_CPU0_D':
 C_SIGNAL='@s9s_mb_2u_lib.s9s_mb_2u(sch_1):led_pwrgd_pvnn_main_cpu0_d';
NODE_NAME     Q81 3
 '@S9S_MB_2U_LIB.S9S_MB_2U(SCH_1):PAGE305_I40@PURE_QUANTA.MOSFET_NCH_DUAL(CHIPS)':
 'D2': CDS_PINID='D2';
NODE_NAME     D78 C
 '@S9S_MB_2U_LIB.S9S_MB_2U(SCH_1):PAGE305_I43@PURE_QUANTA.Q_LED(CHIPS)':
 'C': CDS_PINID='C';
NET_NAME
'LED_PWRGD_PVNN_MAIN_CPU1'
 '@S9S_MB_2U_LIB.S9S_MB_2U(SCH_1):LED_PWRGD_PVNN_MAIN_CPU1':
 C_SIGNAL='@s9s_mb_2u_lib.s9s_mb_2u(sch_1):led_pwrgd_pvnn_main_cpu1';
NODE_NAME     D85 A
 '@S9S_MB_2U_LIB.S9S_MB_2U(SCH_1):PAGE306_I32@PURE_QUANTA.Q_LED(CHIPS)':
 'A': CDS_PINID='A';
NODE_NAME     R3097 1
 '@S9S_MB_2U_LIB.S9S_MB_2U(SCH_1):PAGE306_I38@PURE_QUANTA.Q_RES(CHIPS)':
 'A': CDS_PINID='A';
NET_NAME
'LED_PWRGD_PVNN_MAIN_CPU1_D'
 '@S9S_MB_2U_LIB.S9S_MB_2U(SCH_1):LED_PWRGD_PVNN_MAIN_CPU1_D':
 C_SIGNAL='@s9s_mb_2u_lib.s9s_mb_2u(sch_1):led_pwrgd_pvnn_main_cpu1_d';
NODE_NAME     Q86 3
 '@S9S_MB_2U_LIB.S9S_MB_2U(SCH_1):PAGE306_I27@PURE_QUANTA.MOSFET_NCH_DUAL(CHIPS)':
 'D2': CDS_PINID='D2';
NODE_NAME     D85 C
 '@S9S_MB_2U_LIB.S9S_MB_2U(SCH_1):PAGE306_I32@PURE_QUANTA.Q_LED(CHIPS)':
 'C': CDS_PINID='C';
NET_NAME
'LED_PWRGD_PVPP_HBM_CPU0'
 '@S9S_MB_2U_LIB.S9S_MB_2U(SCH_1):LED_PWRGD_PVPP_HBM_CPU0':
 C_SIGNAL='@s9s_mb_2u_lib.s9s_mb_2u(sch_1):led_pwrgd_pvpp_hbm_cpu0';
NODE_NAME     D74 A
 '@S9S_MB_2U_LIB.S9S_MB_2U(SCH_1):PAGE305_I21@PURE_QUANTA.Q_LED(CHIPS)':
 'A': CDS_PINID='A';
NODE_NAME     R3087 1
 '@S9S_MB_2U_LIB.S9S_MB_2U(SCH_1):PAGE305_I50@PURE_QUANTA.Q_RES(CHIPS)':
 'A': CDS_PINID='A';
NET_NAME
'LED_PWRGD_PVPP_HBM_CPU0_D'
 '@S9S_MB_2U_LIB.S9S_MB_2U(SCH_1):LED_PWRGD_PVPP_HBM_CPU0_D':
 C_SIGNAL='@s9s_mb_2u_lib.s9s_mb_2u(sch_1):led_pwrgd_pvpp_hbm_cpu0_d';
NODE_NAME     Q79 3
 '@S9S_MB_2U_LIB.S9S_MB_2U(SCH_1):PAGE305_I7@PURE_QUANTA.MOSFET_NCH_DUAL(CHIPS)':
 'D2': CDS_PINID='D2';
NODE_NAME     D74 C
 '@S9S_MB_2U_LIB.S9S_MB_2U(SCH_1):PAGE305_I21@PURE_QUANTA.Q_LED(CHIPS)':
 'C': CDS_PINID='C';
NET_NAME
'LED_PWRGD_PVPP_HBM_CPU1'
 '@S9S_MB_2U_LIB.S9S_MB_2U(SCH_1):LED_PWRGD_PVPP_HBM_CPU1':
 C_SIGNAL='@s9s_mb_2u_lib.s9s_mb_2u(sch_1):led_pwrgd_pvpp_hbm_cpu1';
NODE_NAME     D81 A
 '@S9S_MB_2U_LIB.S9S_MB_2U(SCH_1):PAGE306_I14@PURE_QUANTA.Q_LED(CHIPS)':
 'A': CDS_PINID='A';
NODE_NAME     R3094 1
 '@S9S_MB_2U_LIB.S9S_MB_2U(SCH_1):PAGE306_I16@PURE_QUANTA.Q_RES(CHIPS)':
 'A': CDS_PINID='A';
NET_NAME
'LED_PWRGD_PVPP_HBM_CPU1_D'
 '@S9S_MB_2U_LIB.S9S_MB_2U(SCH_1):LED_PWRGD_PVPP_HBM_CPU1_D':
 C_SIGNAL='@s9s_mb_2u_lib.s9s_mb_2u(sch_1):led_pwrgd_pvpp_hbm_cpu1_d';
NODE_NAME     Q84 3
 '@S9S_MB_2U_LIB.S9S_MB_2U(SCH_1):PAGE306_I8@PURE_QUANTA.MOSFET_NCH_DUAL(CHIPS)':
 'D2': CDS_PINID='D2';
NODE_NAME     D81 C
 '@S9S_MB_2U_LIB.S9S_MB_2U(SCH_1):PAGE306_I14@PURE_QUANTA.Q_LED(CHIPS)':
 'C': CDS_PINID='C';
NET_NAME
'LED_PWRGD_SYS_PWROK_R'
 '@S9S_MB_2U_LIB.S9S_MB_2U(SCH_1):LED_PWRGD_SYS_PWROK_R':
 C_SIGNAL='@s9s_mb_2u_lib.s9s_mb_2u(sch_1):led_pwrgd_sys_pwrok_r';
NODE_NAME     D88 A
 '@S9S_MB_2U_LIB.S9S_MB_2U(SCH_1):PAGE241_I19@PURE_QUANTA.Q_LED(CHIPS)':
 'A': CDS_PINID='A';
NODE_NAME     R3069 1
 '@S9S_MB_2U_LIB.S9S_MB_2U(SCH_1):PAGE241_I39@PURE_QUANTA.Q_RES(CHIPS)':
 'A': CDS_PINID='A';
NET_NAME
'LED_PWRGD_SYS_PWROK_R_D'
 '@S9S_MB_2U_LIB.S9S_MB_2U(SCH_1):LED_PWRGD_SYS_PWROK_R_D':
 C_SIGNAL='@s9s_mb_2u_lib.s9s_mb_2u(sch_1):led_pwrgd_sys_pwrok_r_d';
NODE_NAME     Q87 3
 '@S9S_MB_2U_LIB.S9S_MB_2U(SCH_1):PAGE241_I16@PURE_QUANTA.MOSFET_NCH_DUAL(CHIPS)':
 'D2': CDS_PINID='D2';
NODE_NAME     D88 C
 '@S9S_MB_2U_LIB.S9S_MB_2U(SCH_1):PAGE241_I19@PURE_QUANTA.Q_LED(CHIPS)':
 'C': CDS_PINID='C';
NET_NAME
'LED_RST_PLD_CPU0_DRAM_AB_N'
 '@S9S_MB_2U_LIB.S9S_MB_2U(SCH_1):LED_RST_PLD_CPU0_DRAM_AB_N':
 C_SIGNAL='@s9s_mb_2u_lib.s9s_mb_2u(sch_1):led_rst_pld_cpu0_dram_ab_n';
NODE_NAME     D65 A
 '@S9S_MB_2U_LIB.S9S_MB_2U(SCH_1):PAGE304_I21@PURE_QUANTA.Q_LED(CHIPS)':
 'A': CDS_PINID='A';
NODE_NAME     R1371 1
 '@S9S_MB_2U_LIB.S9S_MB_2U(SCH_1):PAGE304_I49@PURE_QUANTA.Q_RES(CHIPS)':
 'A': CDS_PINID='A';
NET_NAME
'LED_RST_PLD_CPU0_DRAM_AB_N_D'
 '@S9S_MB_2U_LIB.S9S_MB_2U(SCH_1):LED_RST_PLD_CPU0_DRAM_AB_N_D':
 C_SIGNAL='@s9s_mb_2u_lib.s9s_mb_2u(sch_1):led_rst_pld_cpu0_dram_ab_n_d';
NODE_NAME     D65 C
 '@S9S_MB_2U_LIB.S9S_MB_2U(SCH_1):PAGE304_I21@PURE_QUANTA.Q_LED(CHIPS)':
 'C': CDS_PINID='C';
NODE_NAME     Q98 6
 '@S9S_MB_2U_LIB.S9S_MB_2U(SCH_1):PAGE304_I68@PURE_QUANTA.MOSFET_NCH_DUAL(CHIPS)':
 'D1': CDS_PINID='D1';
NET_NAME
'LED_RST_PLD_CPU0_DRAM_CD_N'
 '@S9S_MB_2U_LIB.S9S_MB_2U(SCH_1):LED_RST_PLD_CPU0_DRAM_CD_N':
 C_SIGNAL='@s9s_mb_2u_lib.s9s_mb_2u(sch_1):led_rst_pld_cpu0_dram_cd_n';
NODE_NAME     D66 A
 '@S9S_MB_2U_LIB.S9S_MB_2U(SCH_1):PAGE304_I20@PURE_QUANTA.Q_LED(CHIPS)':
 'A': CDS_PINID='A';
NODE_NAME     R3080 1
 '@S9S_MB_2U_LIB.S9S_MB_2U(SCH_1):PAGE304_I50@PURE_QUANTA.Q_RES(CHIPS)':
 'A': CDS_PINID='A';
NET_NAME
'LED_RST_PLD_CPU0_DRAM_CD_N_D'
 '@S9S_MB_2U_LIB.S9S_MB_2U(SCH_1):LED_RST_PLD_CPU0_DRAM_CD_N_D':
 C_SIGNAL='@s9s_mb_2u_lib.s9s_mb_2u(sch_1):led_rst_pld_cpu0_dram_cd_n_d';
NODE_NAME     D66 C
 '@S9S_MB_2U_LIB.S9S_MB_2U(SCH_1):PAGE304_I20@PURE_QUANTA.Q_LED(CHIPS)':
 'C': CDS_PINID='C';
NODE_NAME     Q98 3
 '@S9S_MB_2U_LIB.S9S_MB_2U(SCH_1):PAGE304_I69@PURE_QUANTA.MOSFET_NCH_DUAL(CHIPS)':
 'D2': CDS_PINID='D2';
NET_NAME
'LED_RST_PLD_CPU0_DRAM_EF_N'
 '@S9S_MB_2U_LIB.S9S_MB_2U(SCH_1):LED_RST_PLD_CPU0_DRAM_EF_N':
 C_SIGNAL='@s9s_mb_2u_lib.s9s_mb_2u(sch_1):led_rst_pld_cpu0_dram_ef_n';
NODE_NAME     D67 A
 '@S9S_MB_2U_LIB.S9S_MB_2U(SCH_1):PAGE304_I12@PURE_QUANTA.Q_LED(CHIPS)':
 'A': CDS_PINID='A';
NODE_NAME     R3079 1
 '@S9S_MB_2U_LIB.S9S_MB_2U(SCH_1):PAGE304_I51@PURE_QUANTA.Q_RES(CHIPS)':
 'A': CDS_PINID='A';
NET_NAME
'LED_RST_PLD_CPU0_DRAM_EF_N_D'
 '@S9S_MB_2U_LIB.S9S_MB_2U(SCH_1):LED_RST_PLD_CPU0_DRAM_EF_N_D':
 C_SIGNAL='@s9s_mb_2u_lib.s9s_mb_2u(sch_1):led_rst_pld_cpu0_dram_ef_n_d';
NODE_NAME     D67 C
 '@S9S_MB_2U_LIB.S9S_MB_2U(SCH_1):PAGE304_I12@PURE_QUANTA.Q_LED(CHIPS)':
 'C': CDS_PINID='C';
NODE_NAME     Q97 6
 '@S9S_MB_2U_LIB.S9S_MB_2U(SCH_1):PAGE304_I71@PURE_QUANTA.MOSFET_NCH_DUAL(CHIPS)':
 'D1': CDS_PINID='D1';
NET_NAME
'LED_RST_PLD_CPU0_DRAM_GH_N'
 '@S9S_MB_2U_LIB.S9S_MB_2U(SCH_1):LED_RST_PLD_CPU0_DRAM_GH_N':
 C_SIGNAL='@s9s_mb_2u_lib.s9s_mb_2u(sch_1):led_rst_pld_cpu0_dram_gh_n';
NODE_NAME     D68 A
 '@S9S_MB_2U_LIB.S9S_MB_2U(SCH_1):PAGE304_I9@PURE_QUANTA.Q_LED(CHIPS)':
 'A': CDS_PINID='A';
NODE_NAME     R3081 1
 '@S9S_MB_2U_LIB.S9S_MB_2U(SCH_1):PAGE304_I52@PURE_QUANTA.Q_RES(CHIPS)':
 'A': CDS_PINID='A';
NET_NAME
'LED_RST_PLD_CPU0_DRAM_GH_N_D'
 '@S9S_MB_2U_LIB.S9S_MB_2U(SCH_1):LED_RST_PLD_CPU0_DRAM_GH_N_D':
 C_SIGNAL='@s9s_mb_2u_lib.s9s_mb_2u(sch_1):led_rst_pld_cpu0_dram_gh_n_d';
NODE_NAME     D68 C
 '@S9S_MB_2U_LIB.S9S_MB_2U(SCH_1):PAGE304_I9@PURE_QUANTA.Q_LED(CHIPS)':
 'C': CDS_PINID='C';
NODE_NAME     Q97 3
 '@S9S_MB_2U_LIB.S9S_MB_2U(SCH_1):PAGE304_I70@PURE_QUANTA.MOSFET_NCH_DUAL(CHIPS)':
 'D2': CDS_PINID='D2';
NET_NAME
'LED_RST_PLD_CPU1_DRAM_AB_N'
 '@S9S_MB_2U_LIB.S9S_MB_2U(SCH_1):LED_RST_PLD_CPU1_DRAM_AB_N':
 C_SIGNAL='@s9s_mb_2u_lib.s9s_mb_2u(sch_1):led_rst_pld_cpu1_dram_ab_n';
NODE_NAME     D69 A
 '@S9S_MB_2U_LIB.S9S_MB_2U(SCH_1):PAGE304_I32@PURE_QUANTA.Q_LED(CHIPS)':
 'A': CDS_PINID='A';
NODE_NAME     R3082 1
 '@S9S_MB_2U_LIB.S9S_MB_2U(SCH_1):PAGE304_I54@PURE_QUANTA.Q_RES(CHIPS)':
 'A': CDS_PINID='A';
NET_NAME
'LED_RST_PLD_CPU1_DRAM_AB_N_D'
 '@S9S_MB_2U_LIB.S9S_MB_2U(SCH_1):LED_RST_PLD_CPU1_DRAM_AB_N_D':
 C_SIGNAL='@s9s_mb_2u_lib.s9s_mb_2u(sch_1):led_rst_pld_cpu1_dram_ab_n_d';
NODE_NAME     D69 C
 '@S9S_MB_2U_LIB.S9S_MB_2U(SCH_1):PAGE304_I32@PURE_QUANTA.Q_LED(CHIPS)':
 'C': CDS_PINID='C';
NODE_NAME     Q105 6
 '@S9S_MB_2U_LIB.S9S_MB_2U(SCH_1):PAGE304_I76@PURE_QUANTA.MOSFET_NCH_DUAL(CHIPS)':
 'D1': CDS_PINID='D1';
NET_NAME
'LED_RST_PLD_CPU1_DRAM_CD_N'
 '@S9S_MB_2U_LIB.S9S_MB_2U(SCH_1):LED_RST_PLD_CPU1_DRAM_CD_N':
 C_SIGNAL='@s9s_mb_2u_lib.s9s_mb_2u(sch_1):led_rst_pld_cpu1_dram_cd_n';
NODE_NAME     D70 A
 '@S9S_MB_2U_LIB.S9S_MB_2U(SCH_1):PAGE304_I31@PURE_QUANTA.Q_LED(CHIPS)':
 'A': CDS_PINID='A';
NODE_NAME     R3084 1
 '@S9S_MB_2U_LIB.S9S_MB_2U(SCH_1):PAGE304_I53@PURE_QUANTA.Q_RES(CHIPS)':
 'A': CDS_PINID='A';
NET_NAME
'LED_RST_PLD_CPU1_DRAM_CD_N_D'
 '@S9S_MB_2U_LIB.S9S_MB_2U(SCH_1):LED_RST_PLD_CPU1_DRAM_CD_N_D':
 C_SIGNAL='@s9s_mb_2u_lib.s9s_mb_2u(sch_1):led_rst_pld_cpu1_dram_cd_n_d';
NODE_NAME     D70 C
 '@S9S_MB_2U_LIB.S9S_MB_2U(SCH_1):PAGE304_I31@PURE_QUANTA.Q_LED(CHIPS)':
 'C': CDS_PINID='C';
NODE_NAME     Q99 6
 '@S9S_MB_2U_LIB.S9S_MB_2U(SCH_1):PAGE304_I72@PURE_QUANTA.MOSFET_NCH_DUAL(CHIPS)':
 'D1': CDS_PINID='D1';
NET_NAME
'LED_RST_PLD_CPU1_DRAM_EF_N'
 '@S9S_MB_2U_LIB.S9S_MB_2U(SCH_1):LED_RST_PLD_CPU1_DRAM_EF_N':
 C_SIGNAL='@s9s_mb_2u_lib.s9s_mb_2u(sch_1):led_rst_pld_cpu1_dram_ef_n';
NODE_NAME     R3083 1
 '@S9S_MB_2U_LIB.S9S_MB_2U(SCH_1):PAGE304_I57@PURE_QUANTA.Q_RES(CHIPS)':
 'A': CDS_PINID='A';
NODE_NAME     D71 A
 '@S9S_MB_2U_LIB.S9S_MB_2U(SCH_1):PAGE304_I58@PURE_QUANTA.Q_LED(CHIPS)':
 'A': CDS_PINID='A';
NET_NAME
'LED_RST_PLD_CPU1_DRAM_EF_N_D'
 '@S9S_MB_2U_LIB.S9S_MB_2U(SCH_1):LED_RST_PLD_CPU1_DRAM_EF_N_D':
 C_SIGNAL='@s9s_mb_2u_lib.s9s_mb_2u(sch_1):led_rst_pld_cpu1_dram_ef_n_d';
NODE_NAME     D71 C
 '@S9S_MB_2U_LIB.S9S_MB_2U(SCH_1):PAGE304_I58@PURE_QUANTA.Q_LED(CHIPS)':
 'C': CDS_PINID='C';
NODE_NAME     Q100 6
 '@S9S_MB_2U_LIB.S9S_MB_2U(SCH_1):PAGE304_I74@PURE_QUANTA.MOSFET_NCH_DUAL(CHIPS)':
 'D1': CDS_PINID='D1';
NET_NAME
'LED_RST_PLD_CPU1_DRAM_GH_N'
 '@S9S_MB_2U_LIB.S9S_MB_2U(SCH_1):LED_RST_PLD_CPU1_DRAM_GH_N':
 C_SIGNAL='@s9s_mb_2u_lib.s9s_mb_2u(sch_1):led_rst_pld_cpu1_dram_gh_n';
NODE_NAME     R3085 1
 '@S9S_MB_2U_LIB.S9S_MB_2U(SCH_1):PAGE304_I62@PURE_QUANTA.Q_RES(CHIPS)':
 'A': CDS_PINID='A';
NODE_NAME     D72 A
 '@S9S_MB_2U_LIB.S9S_MB_2U(SCH_1):PAGE304_I63@PURE_QUANTA.Q_LED(CHIPS)':
 'A': CDS_PINID='A';
NET_NAME
'LED_RST_PLD_CPU1_DRAM_GH_N_D'
 '@S9S_MB_2U_LIB.S9S_MB_2U(SCH_1):LED_RST_PLD_CPU1_DRAM_GH_N_D':
 C_SIGNAL='@s9s_mb_2u_lib.s9s_mb_2u(sch_1):led_rst_pld_cpu1_dram_gh_n_d';
NODE_NAME     D72 C
 '@S9S_MB_2U_LIB.S9S_MB_2U(SCH_1):PAGE304_I63@PURE_QUANTA.Q_LED(CHIPS)':
 'C': CDS_PINID='C';
NODE_NAME     Q100 3
 '@S9S_MB_2U_LIB.S9S_MB_2U(SCH_1):PAGE304_I75@PURE_QUANTA.MOSFET_NCH_DUAL(CHIPS)':
 'D2': CDS_PINID='D2';
NET_NAME
'LED_RST_PLTRST_N'
 '@S9S_MB_2U_LIB.S9S_MB_2U(SCH_1):LED_RST_PLTRST_N':
 C_SIGNAL='@s9s_mb_2u_lib.s9s_mb_2u(sch_1):led_rst_pltrst_n';
NODE_NAME     D90 A
 '@S9S_MB_2U_LIB.S9S_MB_2U(SCH_1):PAGE241_I33@PURE_QUANTA.Q_LED(CHIPS)':
 'A': CDS_PINID='A';
NODE_NAME     R3070 1
 '@S9S_MB_2U_LIB.S9S_MB_2U(SCH_1):PAGE241_I41@PURE_QUANTA.Q_RES(CHIPS)':
 'A': CDS_PINID='A';
NET_NAME
'LED_RST_PLTRST_N_D'
 '@S9S_MB_2U_LIB.S9S_MB_2U(SCH_1):LED_RST_PLTRST_N_D':
 C_SIGNAL='@s9s_mb_2u_lib.s9s_mb_2u(sch_1):led_rst_pltrst_n_d';
NODE_NAME     D90 C
 '@S9S_MB_2U_LIB.S9S_MB_2U(SCH_1):PAGE241_I33@PURE_QUANTA.Q_LED(CHIPS)':
 'C': CDS_PINID='C';
NODE_NAME     Q88 3
 '@S9S_MB_2U_LIB.S9S_MB_2U(SCH_1):PAGE241_I42@PURE_QUANTA.MOSFET_NCH_DUAL(CHIPS)':
 'D2': CDS_PINID='D2';
NET_NAME
'LED_RST_RSMRST_PLD_R_N'
 '@S9S_MB_2U_LIB.S9S_MB_2U(SCH_1):LED_RST_RSMRST_PLD_R_N':
 C_SIGNAL='@s9s_mb_2u_lib.s9s_mb_2u(sch_1):led_rst_rsmrst_pld_r_n';
NODE_NAME     D93 A
 '@S9S_MB_2U_LIB.S9S_MB_2U(SCH_1):PAGE242_I13@PURE_QUANTA.Q_LED(CHIPS)':
 'A': CDS_PINID='A';
NODE_NAME     R3074 1
 '@S9S_MB_2U_LIB.S9S_MB_2U(SCH_1):PAGE242_I14@PURE_QUANTA.Q_RES(CHIPS)':
 'A': CDS_PINID='A';
NET_NAME
'LED_RST_RSMRST_PLD_R_N_D'
 '@S9S_MB_2U_LIB.S9S_MB_2U(SCH_1):LED_RST_RSMRST_PLD_R_N_D':
 C_SIGNAL='@s9s_mb_2u_lib.s9s_mb_2u(sch_1):led_rst_rsmrst_pld_r_n_d';
NODE_NAME     Q77 6
 '@S9S_MB_2U_LIB.S9S_MB_2U(SCH_1):PAGE242_I6@PURE_QUANTA.MOSFET_NCH_DUAL(CHIPS)':
 'D1': CDS_PINID='D1';
NODE_NAME     D93 C
 '@S9S_MB_2U_LIB.S9S_MB_2U(SCH_1):PAGE242_I13@PURE_QUANTA.Q_LED(CHIPS)':
 'C': CDS_PINID='C';
NET_NAME
'M2_0_P3V3_ADC_ALERT'
 '@S9S_MB_2U_LIB.S9S_MB_2U(SCH_1):M2_0_P3V3_ADC_ALERT':
 C_SIGNAL='@s9s_mb_2u_lib.s9s_mb_2u(sch_1):m2_0_p3v3_adc_alert';
NODE_NAME     U249 K17
 '@S9S_MB_2U_LIB.S9S_MB_2U(SCH_1):PAGE313_I1@PURE_QUANTA.LCMXO3LF9400C5BG484C(CHIPS)':
 'PR13C': CDS_PINID='PR13C';
NODE_NAME     R3560 2
 '@S9S_MB_2U_LIB.S9S_MB_2U(SCH_1):PAGE163_I41@PURE_QUANTA.Q_RES(CHIPS)':
 'B': CDS_PINID='B';
NET_NAME
'M2_0_P3V3_ADC_ALERT_R'
 '@S9S_MB_2U_LIB.S9S_MB_2U(SCH_1):M2_0_P3V3_ADC_ALERT_R':
 C_SIGNAL='@s9s_mb_2u_lib.s9s_mb_2u(sch_1):m2_0_p3v3_adc_alert_r';
NODE_NAME     R3560 1
 '@S9S_MB_2U_LIB.S9S_MB_2U(SCH_1):PAGE163_I41@PURE_QUANTA.Q_RES(CHIPS)':
 'A': CDS_PINID='A';
NODE_NAME     U264 3
 '@S9S_MB_2U_LIB.S9S_MB_2U(SCH_1):PAGE163_I46@PURE_QUANTA.INA230AIRGTR(CHIPS)':
 'ALERT': CDS_PINID='ALERT';
NODE_NAME     R4090 2
 '@S9S_MB_2U_LIB.S9S_MB_2U(SCH_1):PAGE163_I124@PURE_QUANTA.Q_RES(CHIPS)':
 'B': CDS_PINID='B';
NET_NAME
'M2_0_PEWAKE_N'
 '@S9S_MB_2U_LIB.S9S_MB_2U(SCH_1):M2_0_PEWAKE_N':
 C_SIGNAL='@s9s_mb_2u_lib.s9s_mb_2u(sch_1):m2_0_pewake_n';
NODE_NAME     J59 54
 '@S9S_MB_2U_LIB.S9S_MB_2U(SCH_1):PAGE182_I178@PURE_QUANTA.SCONN75K_APCI0155P004A(CHIPS)':
 'PEWAKE#': CDS_PINID='\pewake#\';
NODE_NAME     R3301 2
 '@S9S_MB_2U_LIB.S9S_MB_2U(SCH_1):PAGE182_I299@PURE_QUANTA.Q_RES(CHIPS)':
 'B': CDS_PINID='B';
NET_NAME
'M2_SSD0_CLKREQ_EN_N'
 '@S9S_MB_2U_LIB.S9S_MB_2U(SCH_1):M2_SSD0_CLKREQ_EN_N':
 C_SIGNAL='@s9s_mb_2u_lib.s9s_mb_2u(sch_1):m2_ssd0_clkreq_en_n';
NODE_NAME     U4 BG16
 '@S9S_MB_2U_LIB.S9S_MB_2U(SCH_1):PAGE175_I93@PURE_QUANTA.EMMITSBURG_REV0P9(CHIPS)':
 'GPPC_A_12_SRCCLKREQ_N_2': CDS_PINID='GPPC_A_12_SRCCLKREQ_N_2';
NODE_NAME     R486 1
 '@S9S_MB_2U_LIB.S9S_MB_2U(SCH_1):PAGE182_I162@PURE_QUANTA.Q_RES(CHIPS)':
 'A': CDS_PINID='A';
NODE_NAME     R491 1
 '@S9S_MB_2U_LIB.S9S_MB_2U(SCH_1):PAGE182_I164@PURE_QUANTA.Q_RES(CHIPS)':
 'A': CDS_PINID='A';
NODE_NAME     U259 1
 '@S9S_MB_2U_LIB.S9S_MB_2U(SCH_1):PAGE182_I327@PURE_QUANTA.SN74LVC2G07DCKR(CHIPS)':
 '1A': CDS_PINID='\1a\';
NET_NAME
'M2_SSD0_CLKREQ_EN_N_BUF'
 '@S9S_MB_2U_LIB.S9S_MB_2U(SCH_1):M2_SSD0_CLKREQ_EN_N_BUF':
 C_SIGNAL='@s9s_mb_2u_lib.s9s_mb_2u(sch_1):m2_ssd0_clkreq_en_n_buf';
NODE_NAME     R486 2
 '@S9S_MB_2U_LIB.S9S_MB_2U(SCH_1):PAGE182_I162@PURE_QUANTA.Q_RES(CHIPS)':
 'B': CDS_PINID='B';
NODE_NAME     R487 2
 '@S9S_MB_2U_LIB.S9S_MB_2U(SCH_1):PAGE182_I173@PURE_QUANTA.Q_RES(CHIPS)':
 'B': CDS_PINID='B';
NODE_NAME     J59 52
 '@S9S_MB_2U_LIB.S9S_MB_2U(SCH_1):PAGE182_I178@PURE_QUANTA.SCONN75K_APCI0155P004A(CHIPS)':
 'CLKREQ#': CDS_PINID='\clkreq#\';
NET_NAME
'MAX11617_VREF'
 '@S9S_MB_2U_LIB.S9S_MB_2U(SCH_1):MAX11617_VREF':
 C_SIGNAL='@s9s_mb_2u_lib.s9s_mb_2u(sch_1):max11617_vref';
NODE_NAME     C1767 1
 '@S9S_MB_2U_LIB.S9S_MB_2U(SCH_1):PAGE239_I68@PURE_QUANTA.Q_CAP(CHIPS)':
 'A': CDS_PINID='A';
NODE_NAME     C1347 1
 '@S9S_MB_2U_LIB.S9S_MB_2U(SCH_1):PAGE239_I70@PURE_QUANTA.Q_CAP(CHIPS)':
 'A': CDS_PINID='A';
NODE_NAME     R2900 1
 '@S9S_MB_2U_LIB.S9S_MB_2U(SCH_1):PAGE239_I72@PURE_QUANTA.Q_RES(CHIPS)':
 'A': CDS_PINID='A';
NET_NAME
'MAX11617_VREF_R'
 '@S9S_MB_2U_LIB.S9S_MB_2U(SCH_1):MAX11617_VREF_R':
 C_SIGNAL='@s9s_mb_2u_lib.s9s_mb_2u(sch_1):max11617_vref_r';
NODE_NAME     U193 1
 '@S9S_MB_2U_LIB.S9S_MB_2U(SCH_1):PAGE239_I57@PURE_QUANTA.MAX11617EEET(CHIPS)':
 'AIN11||REF': CDS_PINID='\ain11||ref\';
NODE_NAME     R2900 2
 '@S9S_MB_2U_LIB.S9S_MB_2U(SCH_1):PAGE239_I72@PURE_QUANTA.Q_RES(CHIPS)':
 'B': CDS_PINID='B';
NET_NAME
'MB0_CM_GATE_G0'
 '@S9S_MB_2U_LIB.S9S_MB_2U(SCH_1):MB0_CM_GATE_G0':
 C_SIGNAL='@s9s_mb_2u_lib.s9s_mb_2u(sch_1):mb0_cm_gate_g0';
NODE_NAME     PR2538 1
 '@S9S_MB_2U_LIB.S9S_MB_2U(SCH_1):PAGE328_I76@PURE_QUANTA.Q_RES(CHIPS)':
 'A': CDS_PINID='A';
NODE_NAME     PPQ9 4
 '@S9S_MB_2U_LIB.S9S_MB_2U(SCH_1):PAGE328_I77@PURE_QUANTA.MOSFET_NCH_1D3S(CHIPS)':
 '4': CDS_PINID='\4\';
NET_NAME
'MB0_P12V_STBY_PWRGD'
 '@S9S_MB_2U_LIB.S9S_MB_2U(SCH_1):MB0_P12V_STBY_PWRGD':
 C_SIGNAL='@s9s_mb_2u_lib.s9s_mb_2u(sch_1):mb0_p12v_stby_pwrgd';
NODE_NAME     R2531 1
 '@S9S_MB_2U_LIB.S9S_MB_2U(SCH_1):PAGE234_I3@PURE_QUANTA.Q_RES(CHIPS)':
 'A': CDS_PINID='A';
NODE_NAME     R3047 1
 '@S9S_MB_2U_LIB.S9S_MB_2U(SCH_1):PAGE313_I85@PURE_QUANTA.Q_RES(CHIPS)':
 'A': CDS_PINID='A';
NODE_NAME     R3048 1
 '@S9S_MB_2U_LIB.S9S_MB_2U(SCH_1):PAGE313_I86@PURE_QUANTA.Q_RES(CHIPS)':
 'A': CDS_PINID='A';
NODE_NAME     PU289 13
 '@S9S_MB_2U_LIB.S9S_MB_2U(SCH_1):PAGE303_I56@PURE_QUANTA.MP5990GMA1111Z(CHIPS)':
 'PG||OCW#': CDS_PINID='\pg||ocw#\';
NODE_NAME     R1117 1
 '@S9S_MB_2U_LIB.S9S_MB_2U(SCH_1):PAGE303_I61@PURE_QUANTA.Q_RES(CHIPS)':
 'A': CDS_PINID='A';
NODE_NAME     PJ42 15
 '@S9S_MB_2U_LIB.S9S_MB_2U(SCH_1):PAGE327_I34@PURE_QUANTA.SCONN21_9193031121LF(CHIPS)':
 '15': CDS_PINID='\15\';
NODE_NAME     R3933 2
 '@S9S_MB_2U_LIB.S9S_MB_2U(SCH_1):PAGE303_I62@PURE_QUANTA.Q_RES(CHIPS)':
 'B': CDS_PINID='B';
NODE_NAME     D145 1
 '@S9S_MB_2U_LIB.S9S_MB_2U(SCH_1):PAGE245_I71@PURE_QUANTA.Q_DIODE(CHIPS)':
 '1': CDS_PINID='\1\';
NODE_NAME     R1571 1
 '@S9S_MB_2U_LIB.S9S_MB_2U(SCH_1):PAGE245_I72@PURE_QUANTA.Q_RES(CHIPS)':
 'A': CDS_PINID='A';
NET_NAME
'MB_FRU_ADDR0'
 '@S9S_MB_2U_LIB.S9S_MB_2U(SCH_1):MB_FRU_ADDR0':
 C_SIGNAL='@s9s_mb_2u_lib.s9s_mb_2u(sch_1):mb_fru_addr0';
NODE_NAME     U64 1
 '@S9S_MB_2U_LIB.S9S_MB_2U(SCH_1):PAGE231_I35@PURE_QUANTA.M24128BWMN6TP(CHIPS)':
 'E0': CDS_PINID='E0';
NODE_NAME     R722 1
 '@S9S_MB_2U_LIB.S9S_MB_2U(SCH_1):PAGE231_I61@PURE_QUANTA.Q_RES(CHIPS)':
 'A': CDS_PINID='A';
NODE_NAME     R721 2
 '@S9S_MB_2U_LIB.S9S_MB_2U(SCH_1):PAGE231_I62@PURE_QUANTA.Q_RES(CHIPS)':
 'B': CDS_PINID='B';
NET_NAME
'MB_FRU_ADDR1'
 '@S9S_MB_2U_LIB.S9S_MB_2U(SCH_1):MB_FRU_ADDR1':
 C_SIGNAL='@s9s_mb_2u_lib.s9s_mb_2u(sch_1):mb_fru_addr1';
NODE_NAME     U64 2
 '@S9S_MB_2U_LIB.S9S_MB_2U(SCH_1):PAGE231_I35@PURE_QUANTA.M24128BWMN6TP(CHIPS)':
 'E1': CDS_PINID='E1';
NODE_NAME     R717 2
 '@S9S_MB_2U_LIB.S9S_MB_2U(SCH_1):PAGE231_I45@PURE_QUANTA.Q_RES(CHIPS)':
 'B': CDS_PINID='B';
NODE_NAME     R718 1
 '@S9S_MB_2U_LIB.S9S_MB_2U(SCH_1):PAGE231_I50@PURE_QUANTA.Q_RES(CHIPS)':
 'A': CDS_PINID='A';
NET_NAME
'MB_FRU_ADDR2'
 '@S9S_MB_2U_LIB.S9S_MB_2U(SCH_1):MB_FRU_ADDR2':
 C_SIGNAL='@s9s_mb_2u_lib.s9s_mb_2u(sch_1):mb_fru_addr2';
NODE_NAME     U64 3
 '@S9S_MB_2U_LIB.S9S_MB_2U(SCH_1):PAGE231_I35@PURE_QUANTA.M24128BWMN6TP(CHIPS)':
 'E2': CDS_PINID='E2';
NODE_NAME     R713 2
 '@S9S_MB_2U_LIB.S9S_MB_2U(SCH_1):PAGE231_I47@PURE_QUANTA.Q_RES(CHIPS)':
 'B': CDS_PINID='B';
NODE_NAME     R714 1
 '@S9S_MB_2U_LIB.S9S_MB_2U(SCH_1):PAGE231_I52@PURE_QUANTA.Q_RES(CHIPS)':
 'A': CDS_PINID='A';
NET_NAME
'M_A_CPU0_ALERT_N'
 '@S9S_MB_2U_LIB.S9S_MB_2U(SCH_1):M_A_CPU0_ALERT_N':
 C_SIGNAL='@s9s_mb_2u_lib.s9s_mb_2u(sch_1):m_a_cpu0_alert_n';
NODE_NAME     U2 AT49
 '@S9S_MB_2U_LIB.S9S_MB_2U(SCH_1):PAGE20_I1@PURE_QUANTA.SOCKET4677_AZIF0045P001C01CS(CHIPS)':
 'DDR0_ALERT_N': CDS_PINID='DDR0_ALERT_N';
NODE_NAME     J1 62
 '@S9S_MB_2U_LIB.S9S_MB_2U(SCH_1):PAGE82_I198@PURE_QUANTA.SCONN288_ADR50017P130CC(CHIPS)':
 'ALERT_N': CDS_PINID='ALERT_N';
NODE_NAME     J2 62
 '@S9S_MB_2U_LIB.S9S_MB_2U(SCH_1):PAGE83_I177@PURE_QUANTA.SCONN288_ADR50017P087CC(CHIPS)':
 'ALERT_N': CDS_PINID='ALERT_N';
NET_NAME
'M_A_CPU0_CLK_DN<0>'
 '@S9S_MB_2U_LIB.S9S_MB_2U(SCH_1):M_A_CPU0_CLK_DN'<0>:
 C_SIGNAL='@s9s_mb_2u_lib.s9s_mb_2u(sch_1):m_a_cpu0_clk_dn(0)';
NODE_NAME     U2 B44
 '@S9S_MB_2U_LIB.S9S_MB_2U(SCH_1):PAGE20_I1@PURE_QUANTA.SOCKET4677_AZIF0045P001C01CS(CHIPS)':
 'DDR0_CLK_DN0': CDS_PINID='DDR0_CLK_DN0';
NODE_NAME     J1 218
 '@S9S_MB_2U_LIB.S9S_MB_2U(SCH_1):PAGE82_I198@PURE_QUANTA.SCONN288_ADR50017P130CC(CHIPS)':
 'CK_C': CDS_PINID='CK_C';
NET_NAME
'M_A_CPU0_CLK_DN<1>'
 '@S9S_MB_2U_LIB.S9S_MB_2U(SCH_1):M_A_CPU0_CLK_DN'<1>:
 C_SIGNAL='@s9s_mb_2u_lib.s9s_mb_2u(sch_1):m_a_cpu0_clk_dn(1)';
NODE_NAME     U2 G45
 '@S9S_MB_2U_LIB.S9S_MB_2U(SCH_1):PAGE20_I1@PURE_QUANTA.SOCKET4677_AZIF0045P001C01CS(CHIPS)':
 'DDR0_CLK_DN1': CDS_PINID='DDR0_CLK_DN1';
NODE_NAME     J2 218
 '@S9S_MB_2U_LIB.S9S_MB_2U(SCH_1):PAGE83_I177@PURE_QUANTA.SCONN288_ADR50017P087CC(CHIPS)':
 'CK_C': CDS_PINID='CK_C';
NET_NAME
'M_A_CPU0_CLK_DP<0>'
 '@S9S_MB_2U_LIB.S9S_MB_2U(SCH_1):M_A_CPU0_CLK_DP'<0>:
 C_SIGNAL='@s9s_mb_2u_lib.s9s_mb_2u(sch_1):m_a_cpu0_clk_dp(0)';
NODE_NAME     U2 C43
 '@S9S_MB_2U_LIB.S9S_MB_2U(SCH_1):PAGE20_I1@PURE_QUANTA.SOCKET4677_AZIF0045P001C01CS(CHIPS)':
 'DDR0_CLK_DP0': CDS_PINID='DDR0_CLK_DP0';
NODE_NAME     J1 217
 '@S9S_MB_2U_LIB.S9S_MB_2U(SCH_1):PAGE82_I198@PURE_QUANTA.SCONN288_ADR50017P130CC(CHIPS)':
 'CK_T': CDS_PINID='CK_T';
NET_NAME
'M_A_CPU0_CLK_DP<1>'
 '@S9S_MB_2U_LIB.S9S_MB_2U(SCH_1):M_A_CPU0_CLK_DP'<1>:
 C_SIGNAL='@s9s_mb_2u_lib.s9s_mb_2u(sch_1):m_a_cpu0_clk_dp(1)';
NODE_NAME     U2 E45
 '@S9S_MB_2U_LIB.S9S_MB_2U(SCH_1):PAGE20_I1@PURE_QUANTA.SOCKET4677_AZIF0045P001C01CS(CHIPS)':
 'DDR0_CLK_DP1': CDS_PINID='DDR0_CLK_DP1';
NODE_NAME     J2 217
 '@S9S_MB_2U_LIB.S9S_MB_2U(SCH_1):PAGE83_I177@PURE_QUANTA.SCONN288_ADR50017P087CC(CHIPS)':
 'CK_T': CDS_PINID='CK_T';
NET_NAME
'M_A_CPU0_SA_CA<0>'
 '@S9S_MB_2U_LIB.S9S_MB_2U(SCH_1):M_A_CPU0_SA_CA'<0>:
 C_SIGNAL='@s9s_mb_2u_lib.s9s_mb_2u(sch_1):m_a_cpu0_sa_ca(0)';
NODE_NAME     U2 A52
 '@S9S_MB_2U_LIB.S9S_MB_2U(SCH_1):PAGE20_I1@PURE_QUANTA.SOCKET4677_AZIF0045P001C01CS(CHIPS)':
 'DDR0_SA_CA0': CDS_PINID='DDR0_SA_CA0';
NODE_NAME     J1 66
 '@S9S_MB_2U_LIB.S9S_MB_2U(SCH_1):PAGE82_I198@PURE_QUANTA.SCONN288_ADR50017P130CC(CHIPS)':
 'CA0_A': CDS_PINID='CA0_A';
NODE_NAME     J2 66
 '@S9S_MB_2U_LIB.S9S_MB_2U(SCH_1):PAGE83_I177@PURE_QUANTA.SCONN288_ADR50017P087CC(CHIPS)':
 'CA0_A': CDS_PINID='CA0_A';
NET_NAME
'M_A_CPU0_SA_CA<1>'
 '@S9S_MB_2U_LIB.S9S_MB_2U(SCH_1):M_A_CPU0_SA_CA'<1>:
 C_SIGNAL='@s9s_mb_2u_lib.s9s_mb_2u(sch_1):m_a_cpu0_sa_ca(1)';
NODE_NAME     U2 G52
 '@S9S_MB_2U_LIB.S9S_MB_2U(SCH_1):PAGE20_I1@PURE_QUANTA.SOCKET4677_AZIF0045P001C01CS(CHIPS)':
 'DDR0_SA_CA1': CDS_PINID='DDR0_SA_CA1';
NODE_NAME     J1 211
 '@S9S_MB_2U_LIB.S9S_MB_2U(SCH_1):PAGE82_I198@PURE_QUANTA.SCONN288_ADR50017P130CC(CHIPS)':
 'CA1_A': CDS_PINID='CA1_A';
NODE_NAME     J2 211
 '@S9S_MB_2U_LIB.S9S_MB_2U(SCH_1):PAGE83_I177@PURE_QUANTA.SCONN288_ADR50017P087CC(CHIPS)':
 'CA1_A': CDS_PINID='CA1_A';
NET_NAME
'M_A_CPU0_SA_CA<2>'
 '@S9S_MB_2U_LIB.S9S_MB_2U(SCH_1):M_A_CPU0_SA_CA'<2>:
 C_SIGNAL='@s9s_mb_2u_lib.s9s_mb_2u(sch_1):m_a_cpu0_sa_ca(2)';
NODE_NAME     U2 B51
 '@S9S_MB_2U_LIB.S9S_MB_2U(SCH_1):PAGE20_I1@PURE_QUANTA.SOCKET4677_AZIF0045P001C01CS(CHIPS)':
 'DDR0_SA_CA2': CDS_PINID='DDR0_SA_CA2';
NODE_NAME     J1 68
 '@S9S_MB_2U_LIB.S9S_MB_2U(SCH_1):PAGE82_I198@PURE_QUANTA.SCONN288_ADR50017P130CC(CHIPS)':
 'CA2_A': CDS_PINID='CA2_A';
NODE_NAME     J2 68
 '@S9S_MB_2U_LIB.S9S_MB_2U(SCH_1):PAGE83_I177@PURE_QUANTA.SCONN288_ADR50017P087CC(CHIPS)':
 'CA2_A': CDS_PINID='CA2_A';
NET_NAME
'M_A_CPU0_SA_CA<3>'
 '@S9S_MB_2U_LIB.S9S_MB_2U(SCH_1):M_A_CPU0_SA_CA'<3>:
 C_SIGNAL='@s9s_mb_2u_lib.s9s_mb_2u(sch_1):m_a_cpu0_sa_ca(3)';
NODE_NAME     U2 F51
 '@S9S_MB_2U_LIB.S9S_MB_2U(SCH_1):PAGE20_I1@PURE_QUANTA.SOCKET4677_AZIF0045P001C01CS(CHIPS)':
 'DDR0_SA_CA3': CDS_PINID='DDR0_SA_CA3';
NODE_NAME     J1 213
 '@S9S_MB_2U_LIB.S9S_MB_2U(SCH_1):PAGE82_I198@PURE_QUANTA.SCONN288_ADR50017P130CC(CHIPS)':
 'CA3_A': CDS_PINID='CA3_A';
NODE_NAME     J2 213
 '@S9S_MB_2U_LIB.S9S_MB_2U(SCH_1):PAGE83_I177@PURE_QUANTA.SCONN288_ADR50017P087CC(CHIPS)':
 'CA3_A': CDS_PINID='CA3_A';
NET_NAME
'M_A_CPU0_SA_CA<4>'
 '@S9S_MB_2U_LIB.S9S_MB_2U(SCH_1):M_A_CPU0_SA_CA'<4>:
 C_SIGNAL='@s9s_mb_2u_lib.s9s_mb_2u(sch_1):m_a_cpu0_sa_ca(4)';
NODE_NAME     U2 C50
 '@S9S_MB_2U_LIB.S9S_MB_2U(SCH_1):PAGE20_I1@PURE_QUANTA.SOCKET4677_AZIF0045P001C01CS(CHIPS)':
 'DDR0_SA_CA4': CDS_PINID='DDR0_SA_CA4';
NODE_NAME     J1 70
 '@S9S_MB_2U_LIB.S9S_MB_2U(SCH_1):PAGE82_I198@PURE_QUANTA.SCONN288_ADR50017P130CC(CHIPS)':
 'CA4_A': CDS_PINID='CA4_A';
NODE_NAME     J2 70
 '@S9S_MB_2U_LIB.S9S_MB_2U(SCH_1):PAGE83_I177@PURE_QUANTA.SCONN288_ADR50017P087CC(CHIPS)':
 'CA4_A': CDS_PINID='CA4_A';
NET_NAME
'M_A_CPU0_SA_CA<5>'
 '@S9S_MB_2U_LIB.S9S_MB_2U(SCH_1):M_A_CPU0_SA_CA'<5>:
 C_SIGNAL='@s9s_mb_2u_lib.s9s_mb_2u(sch_1):m_a_cpu0_sa_ca(5)';
NODE_NAME     U2 E50
 '@S9S_MB_2U_LIB.S9S_MB_2U(SCH_1):PAGE20_I1@PURE_QUANTA.SOCKET4677_AZIF0045P001C01CS(CHIPS)':
 'DDR0_SA_CA5': CDS_PINID='DDR0_SA_CA5';
NODE_NAME     J1 215
 '@S9S_MB_2U_LIB.S9S_MB_2U(SCH_1):PAGE82_I198@PURE_QUANTA.SCONN288_ADR50017P130CC(CHIPS)':
 'CA5_A': CDS_PINID='CA5_A';
NODE_NAME     J2 215
 '@S9S_MB_2U_LIB.S9S_MB_2U(SCH_1):PAGE83_I177@PURE_QUANTA.SCONN288_ADR50017P087CC(CHIPS)':
 'CA5_A': CDS_PINID='CA5_A';
NET_NAME
'M_A_CPU0_SA_CA<6>'
 '@S9S_MB_2U_LIB.S9S_MB_2U(SCH_1):M_A_CPU0_SA_CA'<6>:
 C_SIGNAL='@s9s_mb_2u_lib.s9s_mb_2u(sch_1):m_a_cpu0_sa_ca(6)';
NODE_NAME     U2 C48
 '@S9S_MB_2U_LIB.S9S_MB_2U(SCH_1):PAGE20_I1@PURE_QUANTA.SOCKET4677_AZIF0045P001C01CS(CHIPS)':
 'DDR0_SA_CA6': CDS_PINID='DDR0_SA_CA6';
NODE_NAME     J1 72
 '@S9S_MB_2U_LIB.S9S_MB_2U(SCH_1):PAGE82_I198@PURE_QUANTA.SCONN288_ADR50017P130CC(CHIPS)':
 'CA6_A': CDS_PINID='CA6_A';
NODE_NAME     J2 72
 '@S9S_MB_2U_LIB.S9S_MB_2U(SCH_1):PAGE83_I177@PURE_QUANTA.SCONN288_ADR50017P087CC(CHIPS)':
 'CA6_A': CDS_PINID='CA6_A';
NET_NAME
'M_A_CPU0_SA_CB<0>'
 '@S9S_MB_2U_LIB.S9S_MB_2U(SCH_1):M_A_CPU0_SA_CB'<0>:
 C_SIGNAL='@s9s_mb_2u_lib.s9s_mb_2u(sch_1):m_a_cpu0_sa_cb(0)';
NODE_NAME     U2 C60
 '@S9S_MB_2U_LIB.S9S_MB_2U(SCH_1):PAGE20_I1@PURE_QUANTA.SOCKET4677_AZIF0045P001C01CS(CHIPS)':
 'DDR0_SA_ECC0': CDS_PINID='DDR0_SA_ECC0';
NODE_NAME     J1 51
 '@S9S_MB_2U_LIB.S9S_MB_2U(SCH_1):PAGE82_I198@PURE_QUANTA.SCONN288_ADR50017P130CC(CHIPS)':
 'CB0_A': CDS_PINID='CB0_A';
NODE_NAME     J2 51
 '@S9S_MB_2U_LIB.S9S_MB_2U(SCH_1):PAGE83_I177@PURE_QUANTA.SCONN288_ADR50017P087CC(CHIPS)':
 'CB0_A': CDS_PINID='CB0_A';
NET_NAME
'M_A_CPU0_SA_CB<1>'
 '@S9S_MB_2U_LIB.S9S_MB_2U(SCH_1):M_A_CPU0_SA_CB'<1>:
 C_SIGNAL='@s9s_mb_2u_lib.s9s_mb_2u(sch_1):m_a_cpu0_sa_cb(1)';
NODE_NAME     U2 B59
 '@S9S_MB_2U_LIB.S9S_MB_2U(SCH_1):PAGE20_I1@PURE_QUANTA.SOCKET4677_AZIF0045P001C01CS(CHIPS)':
 'DDR0_SA_ECC1': CDS_PINID='DDR0_SA_ECC1';
NODE_NAME     J1 53
 '@S9S_MB_2U_LIB.S9S_MB_2U(SCH_1):PAGE82_I198@PURE_QUANTA.SCONN288_ADR50017P130CC(CHIPS)':
 'CB1_A': CDS_PINID='CB1_A';
NODE_NAME     J2 53
 '@S9S_MB_2U_LIB.S9S_MB_2U(SCH_1):PAGE83_I177@PURE_QUANTA.SCONN288_ADR50017P087CC(CHIPS)':
 'CB1_A': CDS_PINID='CB1_A';
NET_NAME
'M_A_CPU0_SA_CB<2>'
 '@S9S_MB_2U_LIB.S9S_MB_2U(SCH_1):M_A_CPU0_SA_CB'<2>:
 C_SIGNAL='@s9s_mb_2u_lib.s9s_mb_2u(sch_1):m_a_cpu0_sa_cb(2)';
NODE_NAME     U2 E60
 '@S9S_MB_2U_LIB.S9S_MB_2U(SCH_1):PAGE20_I1@PURE_QUANTA.SOCKET4677_AZIF0045P001C01CS(CHIPS)':
 'DDR0_SA_ECC2': CDS_PINID='DDR0_SA_ECC2';
NODE_NAME     J1 196
 '@S9S_MB_2U_LIB.S9S_MB_2U(SCH_1):PAGE82_I198@PURE_QUANTA.SCONN288_ADR50017P130CC(CHIPS)':
 'CB2_A': CDS_PINID='CB2_A';
NODE_NAME     J2 196
 '@S9S_MB_2U_LIB.S9S_MB_2U(SCH_1):PAGE83_I177@PURE_QUANTA.SCONN288_ADR50017P087CC(CHIPS)':
 'CB2_A': CDS_PINID='CB2_A';
NET_NAME
'M_A_CPU0_SA_CB<3>'
 '@S9S_MB_2U_LIB.S9S_MB_2U(SCH_1):M_A_CPU0_SA_CB'<3>:
 C_SIGNAL='@s9s_mb_2u_lib.s9s_mb_2u(sch_1):m_a_cpu0_sa_cb(3)';
NODE_NAME     U2 F59
 '@S9S_MB_2U_LIB.S9S_MB_2U(SCH_1):PAGE20_I1@PURE_QUANTA.SOCKET4677_AZIF0045P001C01CS(CHIPS)':
 'DDR0_SA_ECC3': CDS_PINID='DDR0_SA_ECC3';
NODE_NAME     J1 198
 '@S9S_MB_2U_LIB.S9S_MB_2U(SCH_1):PAGE82_I198@PURE_QUANTA.SCONN288_ADR50017P130CC(CHIPS)':
 'CB3_A': CDS_PINID='CB3_A';
NODE_NAME     J2 198
 '@S9S_MB_2U_LIB.S9S_MB_2U(SCH_1):PAGE83_I177@PURE_QUANTA.SCONN288_ADR50017P087CC(CHIPS)':
 'CB3_A': CDS_PINID='CB3_A';
NET_NAME
'M_A_CPU0_SA_CB<4>'
 '@S9S_MB_2U_LIB.S9S_MB_2U(SCH_1):M_A_CPU0_SA_CB'<4>:
 C_SIGNAL='@s9s_mb_2u_lib.s9s_mb_2u(sch_1):m_a_cpu0_sa_cb(4)';
NODE_NAME     U2 B57
 '@S9S_MB_2U_LIB.S9S_MB_2U(SCH_1):PAGE20_I1@PURE_QUANTA.SOCKET4677_AZIF0045P001C01CS(CHIPS)':
 'DDR0_SA_ECC4': CDS_PINID='DDR0_SA_ECC4';
NODE_NAME     J1 58
 '@S9S_MB_2U_LIB.S9S_MB_2U(SCH_1):PAGE82_I198@PURE_QUANTA.SCONN288_ADR50017P130CC(CHIPS)':
 'CB4_A': CDS_PINID='CB4_A';
NODE_NAME     J2 58
 '@S9S_MB_2U_LIB.S9S_MB_2U(SCH_1):PAGE83_I177@PURE_QUANTA.SCONN288_ADR50017P087CC(CHIPS)':
 'CB4_A': CDS_PINID='CB4_A';
NET_NAME
'M_A_CPU0_SA_CB<5>'
 '@S9S_MB_2U_LIB.S9S_MB_2U(SCH_1):M_A_CPU0_SA_CB'<5>:
 C_SIGNAL='@s9s_mb_2u_lib.s9s_mb_2u(sch_1):m_a_cpu0_sa_cb(5)';
NODE_NAME     U2 C56
 '@S9S_MB_2U_LIB.S9S_MB_2U(SCH_1):PAGE20_I1@PURE_QUANTA.SOCKET4677_AZIF0045P001C01CS(CHIPS)':
 'DDR0_SA_ECC5': CDS_PINID='DDR0_SA_ECC5';
NODE_NAME     J1 60
 '@S9S_MB_2U_LIB.S9S_MB_2U(SCH_1):PAGE82_I198@PURE_QUANTA.SCONN288_ADR50017P130CC(CHIPS)':
 'CB5_A': CDS_PINID='CB5_A';
NODE_NAME     J2 60
 '@S9S_MB_2U_LIB.S9S_MB_2U(SCH_1):PAGE83_I177@PURE_QUANTA.SCONN288_ADR50017P087CC(CHIPS)':
 'CB5_A': CDS_PINID='CB5_A';
NET_NAME
'M_A_CPU0_SA_CB<6>'
 '@S9S_MB_2U_LIB.S9S_MB_2U(SCH_1):M_A_CPU0_SA_CB'<6>:
 C_SIGNAL='@s9s_mb_2u_lib.s9s_mb_2u(sch_1):m_a_cpu0_sa_cb(6)';
NODE_NAME     U2 F57
 '@S9S_MB_2U_LIB.S9S_MB_2U(SCH_1):PAGE20_I1@PURE_QUANTA.SOCKET4677_AZIF0045P001C01CS(CHIPS)':
 'DDR0_SA_ECC6': CDS_PINID='DDR0_SA_ECC6';
NODE_NAME     J1 203
 '@S9S_MB_2U_LIB.S9S_MB_2U(SCH_1):PAGE82_I198@PURE_QUANTA.SCONN288_ADR50017P130CC(CHIPS)':
 'CB6_A': CDS_PINID='CB6_A';
NODE_NAME     J2 203
 '@S9S_MB_2U_LIB.S9S_MB_2U(SCH_1):PAGE83_I177@PURE_QUANTA.SCONN288_ADR50017P087CC(CHIPS)':
 'CB6_A': CDS_PINID='CB6_A';
NET_NAME
'M_A_CPU0_SA_CB<7>'
 '@S9S_MB_2U_LIB.S9S_MB_2U(SCH_1):M_A_CPU0_SA_CB'<7>:
 C_SIGNAL='@s9s_mb_2u_lib.s9s_mb_2u(sch_1):m_a_cpu0_sa_cb(7)';
NODE_NAME     U2 E56
 '@S9S_MB_2U_LIB.S9S_MB_2U(SCH_1):PAGE20_I1@PURE_QUANTA.SOCKET4677_AZIF0045P001C01CS(CHIPS)':
 'DDR0_SA_ECC7': CDS_PINID='DDR0_SA_ECC7';
NODE_NAME     J1 205
 '@S9S_MB_2U_LIB.S9S_MB_2U(SCH_1):PAGE82_I198@PURE_QUANTA.SCONN288_ADR50017P130CC(CHIPS)':
 'CB7_A': CDS_PINID='CB7_A';
NODE_NAME     J2 205
 '@S9S_MB_2U_LIB.S9S_MB_2U(SCH_1):PAGE83_I177@PURE_QUANTA.SCONN288_ADR50017P087CC(CHIPS)':
 'CB7_A': CDS_PINID='CB7_A';
NET_NAME
'M_A_CPU0_SA_CS_N<0>'
 '@S9S_MB_2U_LIB.S9S_MB_2U(SCH_1):M_A_CPU0_SA_CS_N'<0>:
 C_SIGNAL='@s9s_mb_2u_lib.s9s_mb_2u(sch_1):m_a_cpu0_sa_cs_n(0)';
NODE_NAME     U2 C54
 '@S9S_MB_2U_LIB.S9S_MB_2U(SCH_1):PAGE20_I1@PURE_QUANTA.SOCKET4677_AZIF0045P001C01CS(CHIPS)':
 'DDR0_SA_CS_N0': CDS_PINID='DDR0_SA_CS_N0';
NODE_NAME     J1 64
 '@S9S_MB_2U_LIB.S9S_MB_2U(SCH_1):PAGE82_I198@PURE_QUANTA.SCONN288_ADR50017P130CC(CHIPS)':
 'CS0_A_N': CDS_PINID='CS0_A_N';
NET_NAME
'M_A_CPU0_SA_CS_N<1>'
 '@S9S_MB_2U_LIB.S9S_MB_2U(SCH_1):M_A_CPU0_SA_CS_N'<1>:
 C_SIGNAL='@s9s_mb_2u_lib.s9s_mb_2u(sch_1):m_a_cpu0_sa_cs_n(1)';
NODE_NAME     U2 B53
 '@S9S_MB_2U_LIB.S9S_MB_2U(SCH_1):PAGE20_I1@PURE_QUANTA.SOCKET4677_AZIF0045P001C01CS(CHIPS)':
 'DDR0_SA_CS_N1': CDS_PINID='DDR0_SA_CS_N1';
NODE_NAME     J1 209
 '@S9S_MB_2U_LIB.S9S_MB_2U(SCH_1):PAGE82_I198@PURE_QUANTA.SCONN288_ADR50017P130CC(CHIPS)':
 'CS1_A_N': CDS_PINID='CS1_A_N';
NET_NAME
'M_A_CPU0_SA_CS_N<2>'
 '@S9S_MB_2U_LIB.S9S_MB_2U(SCH_1):M_A_CPU0_SA_CS_N'<2>:
 C_SIGNAL='@s9s_mb_2u_lib.s9s_mb_2u(sch_1):m_a_cpu0_sa_cs_n(2)';
NODE_NAME     U2 E54
 '@S9S_MB_2U_LIB.S9S_MB_2U(SCH_1):PAGE20_I1@PURE_QUANTA.SOCKET4677_AZIF0045P001C01CS(CHIPS)':
 'DDR0_SA_CS_N2': CDS_PINID='DDR0_SA_CS_N2';
NODE_NAME     J2 64
 '@S9S_MB_2U_LIB.S9S_MB_2U(SCH_1):PAGE83_I177@PURE_QUANTA.SCONN288_ADR50017P087CC(CHIPS)':
 'CS0_A_N': CDS_PINID='CS0_A_N';
NET_NAME
'M_A_CPU0_SA_CS_N<3>'
 '@S9S_MB_2U_LIB.S9S_MB_2U(SCH_1):M_A_CPU0_SA_CS_N'<3>:
 C_SIGNAL='@s9s_mb_2u_lib.s9s_mb_2u(sch_1):m_a_cpu0_sa_cs_n(3)';
NODE_NAME     U2 F53
 '@S9S_MB_2U_LIB.S9S_MB_2U(SCH_1):PAGE20_I1@PURE_QUANTA.SOCKET4677_AZIF0045P001C01CS(CHIPS)':
 'DDR0_SA_CS_N3': CDS_PINID='DDR0_SA_CS_N3';
NODE_NAME     J2 209
 '@S9S_MB_2U_LIB.S9S_MB_2U(SCH_1):PAGE83_I177@PURE_QUANTA.SCONN288_ADR50017P087CC(CHIPS)':
 'CS1_A_N': CDS_PINID='CS1_A_N';
NET_NAME
'M_A_CPU0_SA_DQ<0>'
 '@S9S_MB_2U_LIB.S9S_MB_2U(SCH_1):M_A_CPU0_SA_DQ'<0>:
 C_SIGNAL='@s9s_mb_2u_lib.s9s_mb_2u(sch_1):m_a_cpu0_sa_dq(0)';
NODE_NAME     U2 B81
 '@S9S_MB_2U_LIB.S9S_MB_2U(SCH_1):PAGE20_I1@PURE_QUANTA.SOCKET4677_AZIF0045P001C01CS(CHIPS)':
 'DDR0_SA_DQ0': CDS_PINID='DDR0_SA_DQ0';
NODE_NAME     J1 7
 '@S9S_MB_2U_LIB.S9S_MB_2U(SCH_1):PAGE82_I198@PURE_QUANTA.SCONN288_ADR50017P130CC(CHIPS)':
 'DQ0_A': CDS_PINID='DQ0_A';
NODE_NAME     J2 7
 '@S9S_MB_2U_LIB.S9S_MB_2U(SCH_1):PAGE83_I177@PURE_QUANTA.SCONN288_ADR50017P087CC(CHIPS)':
 'DQ0_A': CDS_PINID='DQ0_A';
NET_NAME
'M_A_CPU0_SA_DQ<10>'
 '@S9S_MB_2U_LIB.S9S_MB_2U(SCH_1):M_A_CPU0_SA_DQ'<10>:
 C_SIGNAL='@s9s_mb_2u_lib.s9s_mb_2u(sch_1):m_a_cpu0_sa_dq(10)';
NODE_NAME     U2 M69
 '@S9S_MB_2U_LIB.S9S_MB_2U(SCH_1):PAGE20_I1@PURE_QUANTA.SOCKET4677_AZIF0045P001C01CS(CHIPS)':
 'DDR0_SA_DQ10': CDS_PINID='DDR0_SA_DQ10';
NODE_NAME     J1 163
 '@S9S_MB_2U_LIB.S9S_MB_2U(SCH_1):PAGE82_I198@PURE_QUANTA.SCONN288_ADR50017P130CC(CHIPS)':
 'DQ10_A': CDS_PINID='DQ10_A';
NODE_NAME     J2 163
 '@S9S_MB_2U_LIB.S9S_MB_2U(SCH_1):PAGE83_I177@PURE_QUANTA.SCONN288_ADR50017P087CC(CHIPS)':
 'DQ10_A': CDS_PINID='DQ10_A';
NET_NAME
'M_A_CPU0_SA_DQ<11>'
 '@S9S_MB_2U_LIB.S9S_MB_2U(SCH_1):M_A_CPU0_SA_DQ'<11>:
 C_SIGNAL='@s9s_mb_2u_lib.s9s_mb_2u(sch_1):m_a_cpu0_sa_dq(11)';
NODE_NAME     U2 N68
 '@S9S_MB_2U_LIB.S9S_MB_2U(SCH_1):PAGE20_I1@PURE_QUANTA.SOCKET4677_AZIF0045P001C01CS(CHIPS)':
 'DDR0_SA_DQ11': CDS_PINID='DDR0_SA_DQ11';
NODE_NAME     J1 165
 '@S9S_MB_2U_LIB.S9S_MB_2U(SCH_1):PAGE82_I198@PURE_QUANTA.SCONN288_ADR50017P130CC(CHIPS)':
 'DQ11_A': CDS_PINID='DQ11_A';
NODE_NAME     J2 165
 '@S9S_MB_2U_LIB.S9S_MB_2U(SCH_1):PAGE83_I177@PURE_QUANTA.SCONN288_ADR50017P087CC(CHIPS)':
 'DQ11_A': CDS_PINID='DQ11_A';
NET_NAME
'M_A_CPU0_SA_DQ<12>'
 '@S9S_MB_2U_LIB.S9S_MB_2U(SCH_1):M_A_CPU0_SA_DQ'<12>:
 C_SIGNAL='@s9s_mb_2u_lib.s9s_mb_2u(sch_1):m_a_cpu0_sa_dq(12)';
NODE_NAME     U2 J66
 '@S9S_MB_2U_LIB.S9S_MB_2U(SCH_1):PAGE20_I1@PURE_QUANTA.SOCKET4677_AZIF0045P001C01CS(CHIPS)':
 'DDR0_SA_DQ12': CDS_PINID='DDR0_SA_DQ12';
NODE_NAME     J1 25
 '@S9S_MB_2U_LIB.S9S_MB_2U(SCH_1):PAGE82_I198@PURE_QUANTA.SCONN288_ADR50017P130CC(CHIPS)':
 'DQ12_A': CDS_PINID='DQ12_A';
NODE_NAME     J2 25
 '@S9S_MB_2U_LIB.S9S_MB_2U(SCH_1):PAGE83_I177@PURE_QUANTA.SCONN288_ADR50017P087CC(CHIPS)':
 'DQ12_A': CDS_PINID='DQ12_A';
NET_NAME
'M_A_CPU0_SA_DQ<13>'
 '@S9S_MB_2U_LIB.S9S_MB_2U(SCH_1):M_A_CPU0_SA_DQ'<13>:
 C_SIGNAL='@s9s_mb_2u_lib.s9s_mb_2u(sch_1):m_a_cpu0_sa_dq(13)';
NODE_NAME     U2 K65
 '@S9S_MB_2U_LIB.S9S_MB_2U(SCH_1):PAGE20_I1@PURE_QUANTA.SOCKET4677_AZIF0045P001C01CS(CHIPS)':
 'DDR0_SA_DQ13': CDS_PINID='DDR0_SA_DQ13';
NODE_NAME     J1 27
 '@S9S_MB_2U_LIB.S9S_MB_2U(SCH_1):PAGE82_I198@PURE_QUANTA.SCONN288_ADR50017P130CC(CHIPS)':
 'DQ13_A': CDS_PINID='DQ13_A';
NODE_NAME     J2 27
 '@S9S_MB_2U_LIB.S9S_MB_2U(SCH_1):PAGE83_I177@PURE_QUANTA.SCONN288_ADR50017P087CC(CHIPS)':
 'DQ13_A': CDS_PINID='DQ13_A';
NET_NAME
'M_A_CPU0_SA_DQ<14>'
 '@S9S_MB_2U_LIB.S9S_MB_2U(SCH_1):M_A_CPU0_SA_DQ'<14>:
 C_SIGNAL='@s9s_mb_2u_lib.s9s_mb_2u(sch_1):m_a_cpu0_sa_dq(14)';
NODE_NAME     U2 N66
 '@S9S_MB_2U_LIB.S9S_MB_2U(SCH_1):PAGE20_I1@PURE_QUANTA.SOCKET4677_AZIF0045P001C01CS(CHIPS)':
 'DDR0_SA_DQ14': CDS_PINID='DDR0_SA_DQ14';
NODE_NAME     J1 170
 '@S9S_MB_2U_LIB.S9S_MB_2U(SCH_1):PAGE82_I198@PURE_QUANTA.SCONN288_ADR50017P130CC(CHIPS)':
 'DQ14_A': CDS_PINID='DQ14_A';
NODE_NAME     J2 170
 '@S9S_MB_2U_LIB.S9S_MB_2U(SCH_1):PAGE83_I177@PURE_QUANTA.SCONN288_ADR50017P087CC(CHIPS)':
 'DQ14_A': CDS_PINID='DQ14_A';
NET_NAME
'M_A_CPU0_SA_DQ<15>'
 '@S9S_MB_2U_LIB.S9S_MB_2U(SCH_1):M_A_CPU0_SA_DQ'<15>:
 C_SIGNAL='@s9s_mb_2u_lib.s9s_mb_2u(sch_1):m_a_cpu0_sa_dq(15)';
NODE_NAME     U2 M65
 '@S9S_MB_2U_LIB.S9S_MB_2U(SCH_1):PAGE20_I1@PURE_QUANTA.SOCKET4677_AZIF0045P001C01CS(CHIPS)':
 'DDR0_SA_DQ15': CDS_PINID='DDR0_SA_DQ15';
NODE_NAME     J1 172
 '@S9S_MB_2U_LIB.S9S_MB_2U(SCH_1):PAGE82_I198@PURE_QUANTA.SCONN288_ADR50017P130CC(CHIPS)':
 'DQ15_A': CDS_PINID='DQ15_A';
NODE_NAME     J2 172
 '@S9S_MB_2U_LIB.S9S_MB_2U(SCH_1):PAGE83_I177@PURE_QUANTA.SCONN288_ADR50017P087CC(CHIPS)':
 'DQ15_A': CDS_PINID='DQ15_A';
NET_NAME
'M_A_CPU0_SA_DQ<16>'
 '@S9S_MB_2U_LIB.S9S_MB_2U(SCH_1):M_A_CPU0_SA_DQ'<16>:
 C_SIGNAL='@s9s_mb_2u_lib.s9s_mb_2u(sch_1):m_a_cpu0_sa_dq(16)';
NODE_NAME     U2 B73
 '@S9S_MB_2U_LIB.S9S_MB_2U(SCH_1):PAGE20_I1@PURE_QUANTA.SOCKET4677_AZIF0045P001C01CS(CHIPS)':
 'DDR0_SA_DQ16': CDS_PINID='DDR0_SA_DQ16';
NODE_NAME     J1 29
 '@S9S_MB_2U_LIB.S9S_MB_2U(SCH_1):PAGE82_I198@PURE_QUANTA.SCONN288_ADR50017P130CC(CHIPS)':
 'DQ16_A': CDS_PINID='DQ16_A';
NODE_NAME     J2 29
 '@S9S_MB_2U_LIB.S9S_MB_2U(SCH_1):PAGE83_I177@PURE_QUANTA.SCONN288_ADR50017P087CC(CHIPS)':
 'DQ16_A': CDS_PINID='DQ16_A';
NET_NAME
'M_A_CPU0_SA_DQ<17>'
 '@S9S_MB_2U_LIB.S9S_MB_2U(SCH_1):M_A_CPU0_SA_DQ'<17>:
 C_SIGNAL='@s9s_mb_2u_lib.s9s_mb_2u(sch_1):m_a_cpu0_sa_dq(17)';
NODE_NAME     U2 E72
 '@S9S_MB_2U_LIB.S9S_MB_2U(SCH_1):PAGE20_I1@PURE_QUANTA.SOCKET4677_AZIF0045P001C01CS(CHIPS)':
 'DDR0_SA_DQ17': CDS_PINID='DDR0_SA_DQ17';
NODE_NAME     J1 31
 '@S9S_MB_2U_LIB.S9S_MB_2U(SCH_1):PAGE82_I198@PURE_QUANTA.SCONN288_ADR50017P130CC(CHIPS)':
 'DQ17_A': CDS_PINID='DQ17_A';
NODE_NAME     J2 31
 '@S9S_MB_2U_LIB.S9S_MB_2U(SCH_1):PAGE83_I177@PURE_QUANTA.SCONN288_ADR50017P087CC(CHIPS)':
 'DQ17_A': CDS_PINID='DQ17_A';
NET_NAME
'M_A_CPU0_SA_DQ<18>'
 '@S9S_MB_2U_LIB.S9S_MB_2U(SCH_1):M_A_CPU0_SA_DQ'<18>:
 C_SIGNAL='@s9s_mb_2u_lib.s9s_mb_2u(sch_1):m_a_cpu0_sa_dq(18)';
NODE_NAME     U2 D73
 '@S9S_MB_2U_LIB.S9S_MB_2U(SCH_1):PAGE20_I1@PURE_QUANTA.SOCKET4677_AZIF0045P001C01CS(CHIPS)':
 'DDR0_SA_DQ18': CDS_PINID='DDR0_SA_DQ18';
NODE_NAME     J1 174
 '@S9S_MB_2U_LIB.S9S_MB_2U(SCH_1):PAGE82_I198@PURE_QUANTA.SCONN288_ADR50017P130CC(CHIPS)':
 'DQ18_A': CDS_PINID='DQ18_A';
NODE_NAME     J2 174
 '@S9S_MB_2U_LIB.S9S_MB_2U(SCH_1):PAGE83_I177@PURE_QUANTA.SCONN288_ADR50017P087CC(CHIPS)':
 'DQ18_A': CDS_PINID='DQ18_A';
NET_NAME
'M_A_CPU0_SA_DQ<19>'
 '@S9S_MB_2U_LIB.S9S_MB_2U(SCH_1):M_A_CPU0_SA_DQ'<19>:
 C_SIGNAL='@s9s_mb_2u_lib.s9s_mb_2u(sch_1):m_a_cpu0_sa_dq(19)';
NODE_NAME     U2 F71
 '@S9S_MB_2U_LIB.S9S_MB_2U(SCH_1):PAGE20_I1@PURE_QUANTA.SOCKET4677_AZIF0045P001C01CS(CHIPS)':
 'DDR0_SA_DQ19': CDS_PINID='DDR0_SA_DQ19';
NODE_NAME     J1 176
 '@S9S_MB_2U_LIB.S9S_MB_2U(SCH_1):PAGE82_I198@PURE_QUANTA.SCONN288_ADR50017P130CC(CHIPS)':
 'DQ19_A': CDS_PINID='DQ19_A';
NODE_NAME     J2 176
 '@S9S_MB_2U_LIB.S9S_MB_2U(SCH_1):PAGE83_I177@PURE_QUANTA.SCONN288_ADR50017P087CC(CHIPS)':
 'DQ19_A': CDS_PINID='DQ19_A';
NET_NAME
'M_A_CPU0_SA_DQ<1>'
 '@S9S_MB_2U_LIB.S9S_MB_2U(SCH_1):M_A_CPU0_SA_DQ'<1>:
 C_SIGNAL='@s9s_mb_2u_lib.s9s_mb_2u(sch_1):m_a_cpu0_sa_dq(1)';
NODE_NAME     U2 B79
 '@S9S_MB_2U_LIB.S9S_MB_2U(SCH_1):PAGE20_I1@PURE_QUANTA.SOCKET4677_AZIF0045P001C01CS(CHIPS)':
 'DDR0_SA_DQ1': CDS_PINID='DDR0_SA_DQ1';
NODE_NAME     J1 9
 '@S9S_MB_2U_LIB.S9S_MB_2U(SCH_1):PAGE82_I198@PURE_QUANTA.SCONN288_ADR50017P130CC(CHIPS)':
 'DQ1_A': CDS_PINID='DQ1_A';
NODE_NAME     J2 9
 '@S9S_MB_2U_LIB.S9S_MB_2U(SCH_1):PAGE83_I177@PURE_QUANTA.SCONN288_ADR50017P087CC(CHIPS)':
 'DQ1_A': CDS_PINID='DQ1_A';
NET_NAME
'M_A_CPU0_SA_DQ<20>'
 '@S9S_MB_2U_LIB.S9S_MB_2U(SCH_1):M_A_CPU0_SA_DQ'<20>:
 C_SIGNAL='@s9s_mb_2u_lib.s9s_mb_2u(sch_1):m_a_cpu0_sa_dq(20)';
NODE_NAME     U2 B69
 '@S9S_MB_2U_LIB.S9S_MB_2U(SCH_1):PAGE20_I1@PURE_QUANTA.SOCKET4677_AZIF0045P001C01CS(CHIPS)':
 'DDR0_SA_DQ20': CDS_PINID='DDR0_SA_DQ20';
NODE_NAME     J1 36
 '@S9S_MB_2U_LIB.S9S_MB_2U(SCH_1):PAGE82_I198@PURE_QUANTA.SCONN288_ADR50017P130CC(CHIPS)':
 'DQ20_A': CDS_PINID='DQ20_A';
NODE_NAME     J2 36
 '@S9S_MB_2U_LIB.S9S_MB_2U(SCH_1):PAGE83_I177@PURE_QUANTA.SCONN288_ADR50017P087CC(CHIPS)':
 'DQ20_A': CDS_PINID='DQ20_A';
NET_NAME
'M_A_CPU0_SA_DQ<21>'
 '@S9S_MB_2U_LIB.S9S_MB_2U(SCH_1):M_A_CPU0_SA_DQ'<21>:
 C_SIGNAL='@s9s_mb_2u_lib.s9s_mb_2u(sch_1):m_a_cpu0_sa_dq(21)';
NODE_NAME     U2 C68
 '@S9S_MB_2U_LIB.S9S_MB_2U(SCH_1):PAGE20_I1@PURE_QUANTA.SOCKET4677_AZIF0045P001C01CS(CHIPS)':
 'DDR0_SA_DQ21': CDS_PINID='DDR0_SA_DQ21';
NODE_NAME     J1 38
 '@S9S_MB_2U_LIB.S9S_MB_2U(SCH_1):PAGE82_I198@PURE_QUANTA.SCONN288_ADR50017P130CC(CHIPS)':
 'DQ21_A': CDS_PINID='DQ21_A';
NODE_NAME     J2 38
 '@S9S_MB_2U_LIB.S9S_MB_2U(SCH_1):PAGE83_I177@PURE_QUANTA.SCONN288_ADR50017P087CC(CHIPS)':
 'DQ21_A': CDS_PINID='DQ21_A';
NET_NAME
'M_A_CPU0_SA_DQ<22>'
 '@S9S_MB_2U_LIB.S9S_MB_2U(SCH_1):M_A_CPU0_SA_DQ'<22>:
 C_SIGNAL='@s9s_mb_2u_lib.s9s_mb_2u(sch_1):m_a_cpu0_sa_dq(22)';
NODE_NAME     U2 F69
 '@S9S_MB_2U_LIB.S9S_MB_2U(SCH_1):PAGE20_I1@PURE_QUANTA.SOCKET4677_AZIF0045P001C01CS(CHIPS)':
 'DDR0_SA_DQ22': CDS_PINID='DDR0_SA_DQ22';
NODE_NAME     J1 181
 '@S9S_MB_2U_LIB.S9S_MB_2U(SCH_1):PAGE82_I198@PURE_QUANTA.SCONN288_ADR50017P130CC(CHIPS)':
 'DQ22_A': CDS_PINID='DQ22_A';
NODE_NAME     J2 181
 '@S9S_MB_2U_LIB.S9S_MB_2U(SCH_1):PAGE83_I177@PURE_QUANTA.SCONN288_ADR50017P087CC(CHIPS)':
 'DQ22_A': CDS_PINID='DQ22_A';
NET_NAME
'M_A_CPU0_SA_DQ<23>'
 '@S9S_MB_2U_LIB.S9S_MB_2U(SCH_1):M_A_CPU0_SA_DQ'<23>:
 C_SIGNAL='@s9s_mb_2u_lib.s9s_mb_2u(sch_1):m_a_cpu0_sa_dq(23)';
NODE_NAME     U2 E68
 '@S9S_MB_2U_LIB.S9S_MB_2U(SCH_1):PAGE20_I1@PURE_QUANTA.SOCKET4677_AZIF0045P001C01CS(CHIPS)':
 'DDR0_SA_DQ23': CDS_PINID='DDR0_SA_DQ23';
NODE_NAME     J1 183
 '@S9S_MB_2U_LIB.S9S_MB_2U(SCH_1):PAGE82_I198@PURE_QUANTA.SCONN288_ADR50017P130CC(CHIPS)':
 'DQ23_A': CDS_PINID='DQ23_A';
NODE_NAME     J2 183
 '@S9S_MB_2U_LIB.S9S_MB_2U(SCH_1):PAGE83_I177@PURE_QUANTA.SCONN288_ADR50017P087CC(CHIPS)':
 'DQ23_A': CDS_PINID='DQ23_A';
NET_NAME
'M_A_CPU0_SA_DQ<24>'
 '@S9S_MB_2U_LIB.S9S_MB_2U(SCH_1):M_A_CPU0_SA_DQ'<24>:
 C_SIGNAL='@s9s_mb_2u_lib.s9s_mb_2u(sch_1):m_a_cpu0_sa_dq(24)';
NODE_NAME     U2 C66
 '@S9S_MB_2U_LIB.S9S_MB_2U(SCH_1):PAGE20_I1@PURE_QUANTA.SOCKET4677_AZIF0045P001C01CS(CHIPS)':
 'DDR0_SA_DQ24': CDS_PINID='DDR0_SA_DQ24';
NODE_NAME     J1 40
 '@S9S_MB_2U_LIB.S9S_MB_2U(SCH_1):PAGE82_I198@PURE_QUANTA.SCONN288_ADR50017P130CC(CHIPS)':
 'DQ24_A': CDS_PINID='DQ24_A';
NODE_NAME     J2 40
 '@S9S_MB_2U_LIB.S9S_MB_2U(SCH_1):PAGE83_I177@PURE_QUANTA.SCONN288_ADR50017P087CC(CHIPS)':
 'DQ24_A': CDS_PINID='DQ24_A';
NET_NAME
'M_A_CPU0_SA_DQ<25>'
 '@S9S_MB_2U_LIB.S9S_MB_2U(SCH_1):M_A_CPU0_SA_DQ'<25>:
 C_SIGNAL='@s9s_mb_2u_lib.s9s_mb_2u(sch_1):m_a_cpu0_sa_dq(25)';
NODE_NAME     U2 B65
 '@S9S_MB_2U_LIB.S9S_MB_2U(SCH_1):PAGE20_I1@PURE_QUANTA.SOCKET4677_AZIF0045P001C01CS(CHIPS)':
 'DDR0_SA_DQ25': CDS_PINID='DDR0_SA_DQ25';
NODE_NAME     J1 42
 '@S9S_MB_2U_LIB.S9S_MB_2U(SCH_1):PAGE82_I198@PURE_QUANTA.SCONN288_ADR50017P130CC(CHIPS)':
 'DQ25_A': CDS_PINID='DQ25_A';
NODE_NAME     J2 42
 '@S9S_MB_2U_LIB.S9S_MB_2U(SCH_1):PAGE83_I177@PURE_QUANTA.SCONN288_ADR50017P087CC(CHIPS)':
 'DQ25_A': CDS_PINID='DQ25_A';
NET_NAME
'M_A_CPU0_SA_DQ<26>'
 '@S9S_MB_2U_LIB.S9S_MB_2U(SCH_1):M_A_CPU0_SA_DQ'<26>:
 C_SIGNAL='@s9s_mb_2u_lib.s9s_mb_2u(sch_1):m_a_cpu0_sa_dq(26)';
NODE_NAME     U2 E66
 '@S9S_MB_2U_LIB.S9S_MB_2U(SCH_1):PAGE20_I1@PURE_QUANTA.SOCKET4677_AZIF0045P001C01CS(CHIPS)':
 'DDR0_SA_DQ26': CDS_PINID='DDR0_SA_DQ26';
NODE_NAME     J1 185
 '@S9S_MB_2U_LIB.S9S_MB_2U(SCH_1):PAGE82_I198@PURE_QUANTA.SCONN288_ADR50017P130CC(CHIPS)':
 'DQ26_A': CDS_PINID='DQ26_A';
NODE_NAME     J2 185
 '@S9S_MB_2U_LIB.S9S_MB_2U(SCH_1):PAGE83_I177@PURE_QUANTA.SCONN288_ADR50017P087CC(CHIPS)':
 'DQ26_A': CDS_PINID='DQ26_A';
NET_NAME
'M_A_CPU0_SA_DQ<27>'
 '@S9S_MB_2U_LIB.S9S_MB_2U(SCH_1):M_A_CPU0_SA_DQ'<27>:
 C_SIGNAL='@s9s_mb_2u_lib.s9s_mb_2u(sch_1):m_a_cpu0_sa_dq(27)';
NODE_NAME     U2 F65
 '@S9S_MB_2U_LIB.S9S_MB_2U(SCH_1):PAGE20_I1@PURE_QUANTA.SOCKET4677_AZIF0045P001C01CS(CHIPS)':
 'DDR0_SA_DQ27': CDS_PINID='DDR0_SA_DQ27';
NODE_NAME     J1 187
 '@S9S_MB_2U_LIB.S9S_MB_2U(SCH_1):PAGE82_I198@PURE_QUANTA.SCONN288_ADR50017P130CC(CHIPS)':
 'DQ27_A': CDS_PINID='DQ27_A';
NODE_NAME     J2 187
 '@S9S_MB_2U_LIB.S9S_MB_2U(SCH_1):PAGE83_I177@PURE_QUANTA.SCONN288_ADR50017P087CC(CHIPS)':
 'DQ27_A': CDS_PINID='DQ27_A';
NET_NAME
'M_A_CPU0_SA_DQ<28>'
 '@S9S_MB_2U_LIB.S9S_MB_2U(SCH_1):M_A_CPU0_SA_DQ'<28>:
 C_SIGNAL='@s9s_mb_2u_lib.s9s_mb_2u(sch_1):m_a_cpu0_sa_dq(28)';
NODE_NAME     U2 B63
 '@S9S_MB_2U_LIB.S9S_MB_2U(SCH_1):PAGE20_I1@PURE_QUANTA.SOCKET4677_AZIF0045P001C01CS(CHIPS)':
 'DDR0_SA_DQ28': CDS_PINID='DDR0_SA_DQ28';
NODE_NAME     J1 47
 '@S9S_MB_2U_LIB.S9S_MB_2U(SCH_1):PAGE82_I198@PURE_QUANTA.SCONN288_ADR50017P130CC(CHIPS)':
 'DQ28_A': CDS_PINID='DQ28_A';
NODE_NAME     J2 47
 '@S9S_MB_2U_LIB.S9S_MB_2U(SCH_1):PAGE83_I177@PURE_QUANTA.SCONN288_ADR50017P087CC(CHIPS)':
 'DQ28_A': CDS_PINID='DQ28_A';
NET_NAME
'M_A_CPU0_SA_DQ<29>'
 '@S9S_MB_2U_LIB.S9S_MB_2U(SCH_1):M_A_CPU0_SA_DQ'<29>:
 C_SIGNAL='@s9s_mb_2u_lib.s9s_mb_2u(sch_1):m_a_cpu0_sa_dq(29)';
NODE_NAME     U2 C62
 '@S9S_MB_2U_LIB.S9S_MB_2U(SCH_1):PAGE20_I1@PURE_QUANTA.SOCKET4677_AZIF0045P001C01CS(CHIPS)':
 'DDR0_SA_DQ29': CDS_PINID='DDR0_SA_DQ29';
NODE_NAME     J1 49
 '@S9S_MB_2U_LIB.S9S_MB_2U(SCH_1):PAGE82_I198@PURE_QUANTA.SCONN288_ADR50017P130CC(CHIPS)':
 'DQ29_A': CDS_PINID='DQ29_A';
NODE_NAME     J2 49
 '@S9S_MB_2U_LIB.S9S_MB_2U(SCH_1):PAGE83_I177@PURE_QUANTA.SCONN288_ADR50017P087CC(CHIPS)':
 'DQ29_A': CDS_PINID='DQ29_A';
NET_NAME
'M_A_CPU0_SA_DQ<2>'
 '@S9S_MB_2U_LIB.S9S_MB_2U(SCH_1):M_A_CPU0_SA_DQ'<2>:
 C_SIGNAL='@s9s_mb_2u_lib.s9s_mb_2u(sch_1):m_a_cpu0_sa_dq(2)';
NODE_NAME     U2 M77
 '@S9S_MB_2U_LIB.S9S_MB_2U(SCH_1):PAGE20_I1@PURE_QUANTA.SOCKET4677_AZIF0045P001C01CS(CHIPS)':
 'DDR0_SA_DQ2': CDS_PINID='DDR0_SA_DQ2';
NODE_NAME     J1 152
 '@S9S_MB_2U_LIB.S9S_MB_2U(SCH_1):PAGE82_I198@PURE_QUANTA.SCONN288_ADR50017P130CC(CHIPS)':
 'DQ2_A': CDS_PINID='DQ2_A';
NODE_NAME     J2 152
 '@S9S_MB_2U_LIB.S9S_MB_2U(SCH_1):PAGE83_I177@PURE_QUANTA.SCONN288_ADR50017P087CC(CHIPS)':
 'DQ2_A': CDS_PINID='DQ2_A';
NET_NAME
'M_A_CPU0_SA_DQ<30>'
 '@S9S_MB_2U_LIB.S9S_MB_2U(SCH_1):M_A_CPU0_SA_DQ'<30>:
 C_SIGNAL='@s9s_mb_2u_lib.s9s_mb_2u(sch_1):m_a_cpu0_sa_dq(30)';
NODE_NAME     U2 F63
 '@S9S_MB_2U_LIB.S9S_MB_2U(SCH_1):PAGE20_I1@PURE_QUANTA.SOCKET4677_AZIF0045P001C01CS(CHIPS)':
 'DDR0_SA_DQ30': CDS_PINID='DDR0_SA_DQ30';
NODE_NAME     J1 192
 '@S9S_MB_2U_LIB.S9S_MB_2U(SCH_1):PAGE82_I198@PURE_QUANTA.SCONN288_ADR50017P130CC(CHIPS)':
 'DQ30_A': CDS_PINID='DQ30_A';
NODE_NAME     J2 192
 '@S9S_MB_2U_LIB.S9S_MB_2U(SCH_1):PAGE83_I177@PURE_QUANTA.SCONN288_ADR50017P087CC(CHIPS)':
 'DQ30_A': CDS_PINID='DQ30_A';
NET_NAME
'M_A_CPU0_SA_DQ<31>'
 '@S9S_MB_2U_LIB.S9S_MB_2U(SCH_1):M_A_CPU0_SA_DQ'<31>:
 C_SIGNAL='@s9s_mb_2u_lib.s9s_mb_2u(sch_1):m_a_cpu0_sa_dq(31)';
NODE_NAME     U2 E62
 '@S9S_MB_2U_LIB.S9S_MB_2U(SCH_1):PAGE20_I1@PURE_QUANTA.SOCKET4677_AZIF0045P001C01CS(CHIPS)':
 'DDR0_SA_DQ31': CDS_PINID='DDR0_SA_DQ31';
NODE_NAME     J1 194
 '@S9S_MB_2U_LIB.S9S_MB_2U(SCH_1):PAGE82_I198@PURE_QUANTA.SCONN288_ADR50017P130CC(CHIPS)':
 'DQ31_A': CDS_PINID='DQ31_A';
NODE_NAME     J2 194
 '@S9S_MB_2U_LIB.S9S_MB_2U(SCH_1):PAGE83_I177@PURE_QUANTA.SCONN288_ADR50017P087CC(CHIPS)':
 'DQ31_A': CDS_PINID='DQ31_A';
NET_NAME
'M_A_CPU0_SA_DQ<3>'
 '@S9S_MB_2U_LIB.S9S_MB_2U(SCH_1):M_A_CPU0_SA_DQ'<3>:
 C_SIGNAL='@s9s_mb_2u_lib.s9s_mb_2u(sch_1):m_a_cpu0_sa_dq(3)';
NODE_NAME     U2 G78
 '@S9S_MB_2U_LIB.S9S_MB_2U(SCH_1):PAGE20_I1@PURE_QUANTA.SOCKET4677_AZIF0045P001C01CS(CHIPS)':
 'DDR0_SA_DQ3': CDS_PINID='DDR0_SA_DQ3';
NODE_NAME     J1 154
 '@S9S_MB_2U_LIB.S9S_MB_2U(SCH_1):PAGE82_I198@PURE_QUANTA.SCONN288_ADR50017P130CC(CHIPS)':
 'DQ3_A': CDS_PINID='DQ3_A';
NODE_NAME     J2 154
 '@S9S_MB_2U_LIB.S9S_MB_2U(SCH_1):PAGE83_I177@PURE_QUANTA.SCONN288_ADR50017P087CC(CHIPS)':
 'DQ3_A': CDS_PINID='DQ3_A';
NET_NAME
'M_A_CPU0_SA_DQ<4>'
 '@S9S_MB_2U_LIB.S9S_MB_2U(SCH_1):M_A_CPU0_SA_DQ'<4>:
 C_SIGNAL='@s9s_mb_2u_lib.s9s_mb_2u(sch_1):m_a_cpu0_sa_dq(4)';
NODE_NAME     U2 C76
 '@S9S_MB_2U_LIB.S9S_MB_2U(SCH_1):PAGE20_I1@PURE_QUANTA.SOCKET4677_AZIF0045P001C01CS(CHIPS)':
 'DDR0_SA_DQ4': CDS_PINID='DDR0_SA_DQ4';
NODE_NAME     J1 14
 '@S9S_MB_2U_LIB.S9S_MB_2U(SCH_1):PAGE82_I198@PURE_QUANTA.SCONN288_ADR50017P130CC(CHIPS)':
 'DQ4_A': CDS_PINID='DQ4_A';
NODE_NAME     J2 14
 '@S9S_MB_2U_LIB.S9S_MB_2U(SCH_1):PAGE83_I177@PURE_QUANTA.SCONN288_ADR50017P087CC(CHIPS)':
 'DQ4_A': CDS_PINID='DQ4_A';
NET_NAME
'M_A_CPU0_SA_DQ<5>'
 '@S9S_MB_2U_LIB.S9S_MB_2U(SCH_1):M_A_CPU0_SA_DQ'<5>:
 C_SIGNAL='@s9s_mb_2u_lib.s9s_mb_2u(sch_1):m_a_cpu0_sa_dq(5)';
NODE_NAME     U2 D75
 '@S9S_MB_2U_LIB.S9S_MB_2U(SCH_1):PAGE20_I1@PURE_QUANTA.SOCKET4677_AZIF0045P001C01CS(CHIPS)':
 'DDR0_SA_DQ5': CDS_PINID='DDR0_SA_DQ5';
NODE_NAME     J1 16
 '@S9S_MB_2U_LIB.S9S_MB_2U(SCH_1):PAGE82_I198@PURE_QUANTA.SCONN288_ADR50017P130CC(CHIPS)':
 'DQ5_A': CDS_PINID='DQ5_A';
NODE_NAME     J2 16
 '@S9S_MB_2U_LIB.S9S_MB_2U(SCH_1):PAGE83_I177@PURE_QUANTA.SCONN288_ADR50017P087CC(CHIPS)':
 'DQ5_A': CDS_PINID='DQ5_A';
NET_NAME
'M_A_CPU0_SA_DQ<6>'
 '@S9S_MB_2U_LIB.S9S_MB_2U(SCH_1):M_A_CPU0_SA_DQ'<6>:
 C_SIGNAL='@s9s_mb_2u_lib.s9s_mb_2u(sch_1):m_a_cpu0_sa_dq(6)';
NODE_NAME     U2 G76
 '@S9S_MB_2U_LIB.S9S_MB_2U(SCH_1):PAGE20_I1@PURE_QUANTA.SOCKET4677_AZIF0045P001C01CS(CHIPS)':
 'DDR0_SA_DQ6': CDS_PINID='DDR0_SA_DQ6';
NODE_NAME     J1 159
 '@S9S_MB_2U_LIB.S9S_MB_2U(SCH_1):PAGE82_I198@PURE_QUANTA.SCONN288_ADR50017P130CC(CHIPS)':
 'DQ6_A': CDS_PINID='DQ6_A';
NODE_NAME     J2 159
 '@S9S_MB_2U_LIB.S9S_MB_2U(SCH_1):PAGE83_I177@PURE_QUANTA.SCONN288_ADR50017P087CC(CHIPS)':
 'DQ6_A': CDS_PINID='DQ6_A';
NET_NAME
'M_A_CPU0_SA_DQ<7>'
 '@S9S_MB_2U_LIB.S9S_MB_2U(SCH_1):M_A_CPU0_SA_DQ'<7>:
 C_SIGNAL='@s9s_mb_2u_lib.s9s_mb_2u(sch_1):m_a_cpu0_sa_dq(7)';
NODE_NAME     U2 F75
 '@S9S_MB_2U_LIB.S9S_MB_2U(SCH_1):PAGE20_I1@PURE_QUANTA.SOCKET4677_AZIF0045P001C01CS(CHIPS)':
 'DDR0_SA_DQ7': CDS_PINID='DDR0_SA_DQ7';
NODE_NAME     J1 161
 '@S9S_MB_2U_LIB.S9S_MB_2U(SCH_1):PAGE82_I198@PURE_QUANTA.SCONN288_ADR50017P130CC(CHIPS)':
 'DQ7_A': CDS_PINID='DQ7_A';
NODE_NAME     J2 161
 '@S9S_MB_2U_LIB.S9S_MB_2U(SCH_1):PAGE83_I177@PURE_QUANTA.SCONN288_ADR50017P087CC(CHIPS)':
 'DQ7_A': CDS_PINID='DQ7_A';
NET_NAME
'M_A_CPU0_SA_DQ<8>'
 '@S9S_MB_2U_LIB.S9S_MB_2U(SCH_1):M_A_CPU0_SA_DQ'<8>:
 C_SIGNAL='@s9s_mb_2u_lib.s9s_mb_2u(sch_1):m_a_cpu0_sa_dq(8)';
NODE_NAME     U2 K69
 '@S9S_MB_2U_LIB.S9S_MB_2U(SCH_1):PAGE20_I1@PURE_QUANTA.SOCKET4677_AZIF0045P001C01CS(CHIPS)':
 'DDR0_SA_DQ8': CDS_PINID='DDR0_SA_DQ8';
NODE_NAME     J1 18
 '@S9S_MB_2U_LIB.S9S_MB_2U(SCH_1):PAGE82_I198@PURE_QUANTA.SCONN288_ADR50017P130CC(CHIPS)':
 'DQ8_A': CDS_PINID='DQ8_A';
NODE_NAME     J2 18
 '@S9S_MB_2U_LIB.S9S_MB_2U(SCH_1):PAGE83_I177@PURE_QUANTA.SCONN288_ADR50017P087CC(CHIPS)':
 'DQ8_A': CDS_PINID='DQ8_A';
NET_NAME
'M_A_CPU0_SA_DQ<9>'
 '@S9S_MB_2U_LIB.S9S_MB_2U(SCH_1):M_A_CPU0_SA_DQ'<9>:
 C_SIGNAL='@s9s_mb_2u_lib.s9s_mb_2u(sch_1):m_a_cpu0_sa_dq(9)';
NODE_NAME     U2 J68
 '@S9S_MB_2U_LIB.S9S_MB_2U(SCH_1):PAGE20_I1@PURE_QUANTA.SOCKET4677_AZIF0045P001C01CS(CHIPS)':
 'DDR0_SA_DQ9': CDS_PINID='DDR0_SA_DQ9';
NODE_NAME     J1 20
 '@S9S_MB_2U_LIB.S9S_MB_2U(SCH_1):PAGE82_I198@PURE_QUANTA.SCONN288_ADR50017P130CC(CHIPS)':
 'DQ9_A': CDS_PINID='DQ9_A';
NODE_NAME     J2 20
 '@S9S_MB_2U_LIB.S9S_MB_2U(SCH_1):PAGE83_I177@PURE_QUANTA.SCONN288_ADR50017P087CC(CHIPS)':
 'DQ9_A': CDS_PINID='DQ9_A';
NET_NAME
'M_A_CPU0_SA_DQS_DN<0>'
 '@S9S_MB_2U_LIB.S9S_MB_2U(SCH_1):M_A_CPU0_SA_DQS_DN'<0>:
 C_SIGNAL='@s9s_mb_2u_lib.s9s_mb_2u(sch_1):m_a_cpu0_sa_dqs_dn(0)';
NODE_NAME     U2 B77
 '@S9S_MB_2U_LIB.S9S_MB_2U(SCH_1):PAGE20_I1@PURE_QUANTA.SOCKET4677_AZIF0045P001C01CS(CHIPS)':
 'DDR0_SA_DQS_DN0': CDS_PINID='DDR0_SA_DQS_DN0';
NODE_NAME     J1 12
 '@S9S_MB_2U_LIB.S9S_MB_2U(SCH_1):PAGE82_I202@PURE_QUANTA.SCONN288_ADR50017P130CC(CHIPS)':
 'DQS0_A_C': CDS_PINID='DQS0_A_C';
NODE_NAME     J2 12
 '@S9S_MB_2U_LIB.S9S_MB_2U(SCH_1):PAGE83_I181@PURE_QUANTA.SCONN288_ADR50017P087CC(CHIPS)':
 'DQS0_A_C': CDS_PINID='DQS0_A_C';
NET_NAME
'M_A_CPU0_SA_DQS_DN<1>'
 '@S9S_MB_2U_LIB.S9S_MB_2U(SCH_1):M_A_CPU0_SA_DQS_DN'<1>:
 C_SIGNAL='@s9s_mb_2u_lib.s9s_mb_2u(sch_1):m_a_cpu0_sa_dqs_dn(1)';
NODE_NAME     U2 H67
 '@S9S_MB_2U_LIB.S9S_MB_2U(SCH_1):PAGE20_I1@PURE_QUANTA.SOCKET4677_AZIF0045P001C01CS(CHIPS)':
 'DDR0_SA_DQS_DN1': CDS_PINID='DDR0_SA_DQS_DN1';
NODE_NAME     J1 23
 '@S9S_MB_2U_LIB.S9S_MB_2U(SCH_1):PAGE82_I202@PURE_QUANTA.SCONN288_ADR50017P130CC(CHIPS)':
 'DQS1_A_C': CDS_PINID='DQS1_A_C';
NODE_NAME     J2 23
 '@S9S_MB_2U_LIB.S9S_MB_2U(SCH_1):PAGE83_I181@PURE_QUANTA.SCONN288_ADR50017P087CC(CHIPS)':
 'DQS1_A_C': CDS_PINID='DQS1_A_C';
NET_NAME
'M_A_CPU0_SA_DQS_DN<2>'
 '@S9S_MB_2U_LIB.S9S_MB_2U(SCH_1):M_A_CPU0_SA_DQS_DN'<2>:
 C_SIGNAL='@s9s_mb_2u_lib.s9s_mb_2u(sch_1):m_a_cpu0_sa_dqs_dn(2)';
NODE_NAME     U2 B71
 '@S9S_MB_2U_LIB.S9S_MB_2U(SCH_1):PAGE20_I1@PURE_QUANTA.SOCKET4677_AZIF0045P001C01CS(CHIPS)':
 'DDR0_SA_DQS_DN2': CDS_PINID='DDR0_SA_DQS_DN2';
NODE_NAME     J1 34
 '@S9S_MB_2U_LIB.S9S_MB_2U(SCH_1):PAGE82_I202@PURE_QUANTA.SCONN288_ADR50017P130CC(CHIPS)':
 'DQS2_A_C': CDS_PINID='DQS2_A_C';
NODE_NAME     J2 34
 '@S9S_MB_2U_LIB.S9S_MB_2U(SCH_1):PAGE83_I181@PURE_QUANTA.SCONN288_ADR50017P087CC(CHIPS)':
 'DQS2_A_C': CDS_PINID='DQS2_A_C';
NET_NAME
'M_A_CPU0_SA_DQS_DN<3>'
 '@S9S_MB_2U_LIB.S9S_MB_2U(SCH_1):M_A_CPU0_SA_DQS_DN'<3>:
 C_SIGNAL='@s9s_mb_2u_lib.s9s_mb_2u(sch_1):m_a_cpu0_sa_dqs_dn(3)';
NODE_NAME     U2 A64
 '@S9S_MB_2U_LIB.S9S_MB_2U(SCH_1):PAGE20_I1@PURE_QUANTA.SOCKET4677_AZIF0045P001C01CS(CHIPS)':
 'DDR0_SA_DQS_DN3': CDS_PINID='DDR0_SA_DQS_DN3';
NODE_NAME     J1 45
 '@S9S_MB_2U_LIB.S9S_MB_2U(SCH_1):PAGE82_I202@PURE_QUANTA.SCONN288_ADR50017P130CC(CHIPS)':
 'DQS3_A_C': CDS_PINID='DQS3_A_C';
NODE_NAME     J2 45
 '@S9S_MB_2U_LIB.S9S_MB_2U(SCH_1):PAGE83_I181@PURE_QUANTA.SCONN288_ADR50017P087CC(CHIPS)':
 'DQS3_A_C': CDS_PINID='DQS3_A_C';
NET_NAME
'M_A_CPU0_SA_DQS_DN<4>'
 '@S9S_MB_2U_LIB.S9S_MB_2U(SCH_1):M_A_CPU0_SA_DQS_DN'<4>:
 C_SIGNAL='@s9s_mb_2u_lib.s9s_mb_2u(sch_1):m_a_cpu0_sa_dqs_dn(4)';
NODE_NAME     U2 A58
 '@S9S_MB_2U_LIB.S9S_MB_2U(SCH_1):PAGE20_I1@PURE_QUANTA.SOCKET4677_AZIF0045P001C01CS(CHIPS)':
 'DDR0_SA_DQS_DN4': CDS_PINID='DDR0_SA_DQS_DN4';
NODE_NAME     J1 56
 '@S9S_MB_2U_LIB.S9S_MB_2U(SCH_1):PAGE82_I202@PURE_QUANTA.SCONN288_ADR50017P130CC(CHIPS)':
 'DQS4_A_C': CDS_PINID='DQS4_A_C';
NODE_NAME     J2 56
 '@S9S_MB_2U_LIB.S9S_MB_2U(SCH_1):PAGE83_I181@PURE_QUANTA.SCONN288_ADR50017P087CC(CHIPS)':
 'DQS4_A_C': CDS_PINID='DQS4_A_C';
NET_NAME
'M_A_CPU0_SA_DQS_DN<5>'
 '@S9S_MB_2U_LIB.S9S_MB_2U(SCH_1):M_A_CPU0_SA_DQS_DN'<5>:
 C_SIGNAL='@s9s_mb_2u_lib.s9s_mb_2u(sch_1):m_a_cpu0_sa_dqs_dn(5)';
NODE_NAME     U2 H77
 '@S9S_MB_2U_LIB.S9S_MB_2U(SCH_1):PAGE20_I1@PURE_QUANTA.SOCKET4677_AZIF0045P001C01CS(CHIPS)':
 'DDR0_SA_DQS_DN5': CDS_PINID='DDR0_SA_DQS_DN5';
NODE_NAME     J1 156
 '@S9S_MB_2U_LIB.S9S_MB_2U(SCH_1):PAGE82_I202@PURE_QUANTA.SCONN288_ADR50017P130CC(CHIPS)':
 'DQS5_A_C||TDQS5_A_C||DQS5_A_T||TDQS5_A_T': CDS_PINID='\dqs5_a_c||tdqs5_a_c||dqs5_a_t||tdqs5_a_t\';
NODE_NAME     J2 156
 '@S9S_MB_2U_LIB.S9S_MB_2U(SCH_1):PAGE83_I181@PURE_QUANTA.SCONN288_ADR50017P087CC(CHIPS)':
 'DQS5_A_C||TDQS5_A_C||DQS5_A_T||TDQS5_A_T': CDS_PINID='\dqs5_a_c||tdqs5_a_c||dqs5_a_t||tdqs5_a_t\';
NET_NAME
'M_A_CPU0_SA_DQS_DN<6>'
 '@S9S_MB_2U_LIB.S9S_MB_2U(SCH_1):M_A_CPU0_SA_DQS_DN'<6>:
 C_SIGNAL='@s9s_mb_2u_lib.s9s_mb_2u(sch_1):m_a_cpu0_sa_dqs_dn(6)';
NODE_NAME     U2 P67
 '@S9S_MB_2U_LIB.S9S_MB_2U(SCH_1):PAGE20_I1@PURE_QUANTA.SOCKET4677_AZIF0045P001C01CS(CHIPS)':
 'DDR0_SA_DQS_DN6': CDS_PINID='DDR0_SA_DQS_DN6';
NODE_NAME     J1 167
 '@S9S_MB_2U_LIB.S9S_MB_2U(SCH_1):PAGE82_I202@PURE_QUANTA.SCONN288_ADR50017P130CC(CHIPS)':
 'DQS6_A_C||TDQS6_A_C||DQS6_A_T||TDQS6_A_T': CDS_PINID='\dqs6_a_c||tdqs6_a_c||dqs6_a_t||tdqs6_a_t\';
NODE_NAME     J2 167
 '@S9S_MB_2U_LIB.S9S_MB_2U(SCH_1):PAGE83_I181@PURE_QUANTA.SCONN288_ADR50017P087CC(CHIPS)':
 'DQS6_A_C||TDQS6_A_C||DQS6_A_T||TDQS6_A_T': CDS_PINID='\dqs6_a_c||tdqs6_a_c||dqs6_a_t||tdqs6_a_t\';
NET_NAME
'M_A_CPU0_SA_DQS_DN<7>'
 '@S9S_MB_2U_LIB.S9S_MB_2U(SCH_1):M_A_CPU0_SA_DQS_DN'<7>:
 C_SIGNAL='@s9s_mb_2u_lib.s9s_mb_2u(sch_1):m_a_cpu0_sa_dqs_dn(7)';
NODE_NAME     U2 G70
 '@S9S_MB_2U_LIB.S9S_MB_2U(SCH_1):PAGE20_I1@PURE_QUANTA.SOCKET4677_AZIF0045P001C01CS(CHIPS)':
 'DDR0_SA_DQS_DN7': CDS_PINID='DDR0_SA_DQS_DN7';
NODE_NAME     J1 178
 '@S9S_MB_2U_LIB.S9S_MB_2U(SCH_1):PAGE82_I202@PURE_QUANTA.SCONN288_ADR50017P130CC(CHIPS)':
 'DQS7_A_C||TDQS7_A_C': CDS_PINID='\dqs7_a_c||tdqs7_a_c\';
NODE_NAME     J2 178
 '@S9S_MB_2U_LIB.S9S_MB_2U(SCH_1):PAGE83_I181@PURE_QUANTA.SCONN288_ADR50017P087CC(CHIPS)':
 'DQS7_A_C||TDQS7_A_C': CDS_PINID='\dqs7_a_c||tdqs7_a_c\';
NET_NAME
'M_A_CPU0_SA_DQS_DN<8>'
 '@S9S_MB_2U_LIB.S9S_MB_2U(SCH_1):M_A_CPU0_SA_DQS_DN'<8>:
 C_SIGNAL='@s9s_mb_2u_lib.s9s_mb_2u(sch_1):m_a_cpu0_sa_dqs_dn(8)';
NODE_NAME     U2 G64
 '@S9S_MB_2U_LIB.S9S_MB_2U(SCH_1):PAGE20_I1@PURE_QUANTA.SOCKET4677_AZIF0045P001C01CS(CHIPS)':
 'DDR0_SA_DQS_DN8': CDS_PINID='DDR0_SA_DQS_DN8';
NODE_NAME     J1 189
 '@S9S_MB_2U_LIB.S9S_MB_2U(SCH_1):PAGE82_I202@PURE_QUANTA.SCONN288_ADR50017P130CC(CHIPS)':
 'DQS8_A_C||TDQS8_A_C': CDS_PINID='\dqs8_a_c||tdqs8_a_c\';
NODE_NAME     J2 189
 '@S9S_MB_2U_LIB.S9S_MB_2U(SCH_1):PAGE83_I181@PURE_QUANTA.SCONN288_ADR50017P087CC(CHIPS)':
 'DQS8_A_C||TDQS8_A_C': CDS_PINID='\dqs8_a_c||tdqs8_a_c\';
NET_NAME
'M_A_CPU0_SA_DQS_DN<9>'
 '@S9S_MB_2U_LIB.S9S_MB_2U(SCH_1):M_A_CPU0_SA_DQS_DN'<9>:
 C_SIGNAL='@s9s_mb_2u_lib.s9s_mb_2u(sch_1):m_a_cpu0_sa_dqs_dn(9)';
NODE_NAME     U2 G58
 '@S9S_MB_2U_LIB.S9S_MB_2U(SCH_1):PAGE20_I1@PURE_QUANTA.SOCKET4677_AZIF0045P001C01CS(CHIPS)':
 'DDR0_SA_DQS_DN9': CDS_PINID='DDR0_SA_DQS_DN9';
NODE_NAME     J1 200
 '@S9S_MB_2U_LIB.S9S_MB_2U(SCH_1):PAGE82_I202@PURE_QUANTA.SCONN288_ADR50017P130CC(CHIPS)':
 'DQS9_A_C||TDQS9_A_C': CDS_PINID='\dqs9_a_c||tdqs9_a_c\';
NODE_NAME     J2 200
 '@S9S_MB_2U_LIB.S9S_MB_2U(SCH_1):PAGE83_I181@PURE_QUANTA.SCONN288_ADR50017P087CC(CHIPS)':
 'DQS9_A_C||TDQS9_A_C': CDS_PINID='\dqs9_a_c||tdqs9_a_c\';
NET_NAME
'M_A_CPU0_SA_DQS_DP<0>'
 '@S9S_MB_2U_LIB.S9S_MB_2U(SCH_1):M_A_CPU0_SA_DQS_DP'<0>:
 C_SIGNAL='@s9s_mb_2u_lib.s9s_mb_2u(sch_1):m_a_cpu0_sa_dqs_dp(0)';
NODE_NAME     U2 D77
 '@S9S_MB_2U_LIB.S9S_MB_2U(SCH_1):PAGE20_I1@PURE_QUANTA.SOCKET4677_AZIF0045P001C01CS(CHIPS)':
 'DDR0_SA_DQS_DP0': CDS_PINID='DDR0_SA_DQS_DP0';
NODE_NAME     J1 11
 '@S9S_MB_2U_LIB.S9S_MB_2U(SCH_1):PAGE82_I202@PURE_QUANTA.SCONN288_ADR50017P130CC(CHIPS)':
 'DQS0_A_T': CDS_PINID='DQS0_A_T';
NODE_NAME     J2 11
 '@S9S_MB_2U_LIB.S9S_MB_2U(SCH_1):PAGE83_I181@PURE_QUANTA.SCONN288_ADR50017P087CC(CHIPS)':
 'DQS0_A_T': CDS_PINID='DQS0_A_T';
NET_NAME
'M_A_CPU0_SA_DQS_DP<1>'
 '@S9S_MB_2U_LIB.S9S_MB_2U(SCH_1):M_A_CPU0_SA_DQS_DP'<1>:
 C_SIGNAL='@s9s_mb_2u_lib.s9s_mb_2u(sch_1):m_a_cpu0_sa_dqs_dp(1)';
NODE_NAME     U2 K67
 '@S9S_MB_2U_LIB.S9S_MB_2U(SCH_1):PAGE20_I1@PURE_QUANTA.SOCKET4677_AZIF0045P001C01CS(CHIPS)':
 'DDR0_SA_DQS_DP1': CDS_PINID='DDR0_SA_DQS_DP1';
NODE_NAME     J1 22
 '@S9S_MB_2U_LIB.S9S_MB_2U(SCH_1):PAGE82_I202@PURE_QUANTA.SCONN288_ADR50017P130CC(CHIPS)':
 'DQS1_A_T': CDS_PINID='DQS1_A_T';
NODE_NAME     J2 22
 '@S9S_MB_2U_LIB.S9S_MB_2U(SCH_1):PAGE83_I181@PURE_QUANTA.SCONN288_ADR50017P087CC(CHIPS)':
 'DQS1_A_T': CDS_PINID='DQS1_A_T';
NET_NAME
'M_A_CPU0_SA_DQS_DP<2>'
 '@S9S_MB_2U_LIB.S9S_MB_2U(SCH_1):M_A_CPU0_SA_DQS_DP'<2>:
 C_SIGNAL='@s9s_mb_2u_lib.s9s_mb_2u(sch_1):m_a_cpu0_sa_dqs_dp(2)';
NODE_NAME     U2 C70
 '@S9S_MB_2U_LIB.S9S_MB_2U(SCH_1):PAGE20_I1@PURE_QUANTA.SOCKET4677_AZIF0045P001C01CS(CHIPS)':
 'DDR0_SA_DQS_DP2': CDS_PINID='DDR0_SA_DQS_DP2';
NODE_NAME     J1 33
 '@S9S_MB_2U_LIB.S9S_MB_2U(SCH_1):PAGE82_I202@PURE_QUANTA.SCONN288_ADR50017P130CC(CHIPS)':
 'DQS2_A_T': CDS_PINID='DQS2_A_T';
NODE_NAME     J2 33
 '@S9S_MB_2U_LIB.S9S_MB_2U(SCH_1):PAGE83_I181@PURE_QUANTA.SCONN288_ADR50017P087CC(CHIPS)':
 'DQS2_A_T': CDS_PINID='DQS2_A_T';
NET_NAME
'M_A_CPU0_SA_DQS_DP<3>'
 '@S9S_MB_2U_LIB.S9S_MB_2U(SCH_1):M_A_CPU0_SA_DQS_DP'<3>:
 C_SIGNAL='@s9s_mb_2u_lib.s9s_mb_2u(sch_1):m_a_cpu0_sa_dqs_dp(3)';
NODE_NAME     U2 C64
 '@S9S_MB_2U_LIB.S9S_MB_2U(SCH_1):PAGE20_I1@PURE_QUANTA.SOCKET4677_AZIF0045P001C01CS(CHIPS)':
 'DDR0_SA_DQS_DP3': CDS_PINID='DDR0_SA_DQS_DP3';
NODE_NAME     J1 44
 '@S9S_MB_2U_LIB.S9S_MB_2U(SCH_1):PAGE82_I202@PURE_QUANTA.SCONN288_ADR50017P130CC(CHIPS)':
 'DQS3_A_T': CDS_PINID='DQS3_A_T';
NODE_NAME     J2 44
 '@S9S_MB_2U_LIB.S9S_MB_2U(SCH_1):PAGE83_I181@PURE_QUANTA.SCONN288_ADR50017P087CC(CHIPS)':
 'DQS3_A_T': CDS_PINID='DQS3_A_T';
NET_NAME
'M_A_CPU0_SA_DQS_DP<4>'
 '@S9S_MB_2U_LIB.S9S_MB_2U(SCH_1):M_A_CPU0_SA_DQS_DP'<4>:
 C_SIGNAL='@s9s_mb_2u_lib.s9s_mb_2u(sch_1):m_a_cpu0_sa_dqs_dp(4)';
NODE_NAME     U2 C58
 '@S9S_MB_2U_LIB.S9S_MB_2U(SCH_1):PAGE20_I1@PURE_QUANTA.SOCKET4677_AZIF0045P001C01CS(CHIPS)':
 'DDR0_SA_DQS_DP4': CDS_PINID='DDR0_SA_DQS_DP4';
NODE_NAME     J1 55
 '@S9S_MB_2U_LIB.S9S_MB_2U(SCH_1):PAGE82_I202@PURE_QUANTA.SCONN288_ADR50017P130CC(CHIPS)':
 'DQS4_A_T': CDS_PINID='DQS4_A_T';
NODE_NAME     J2 55
 '@S9S_MB_2U_LIB.S9S_MB_2U(SCH_1):PAGE83_I181@PURE_QUANTA.SCONN288_ADR50017P087CC(CHIPS)':
 'DQS4_A_T': CDS_PINID='DQS4_A_T';
NET_NAME
'M_A_CPU0_SA_DQS_DP<5>'
 '@S9S_MB_2U_LIB.S9S_MB_2U(SCH_1):M_A_CPU0_SA_DQS_DP'<5>:
 C_SIGNAL='@s9s_mb_2u_lib.s9s_mb_2u(sch_1):m_a_cpu0_sa_dqs_dp(5)';
NODE_NAME     U2 F77
 '@S9S_MB_2U_LIB.S9S_MB_2U(SCH_1):PAGE20_I1@PURE_QUANTA.SOCKET4677_AZIF0045P001C01CS(CHIPS)':
 'DDR0_SA_DQS_DP5': CDS_PINID='DDR0_SA_DQS_DP5';
NODE_NAME     J1 157
 '@S9S_MB_2U_LIB.S9S_MB_2U(SCH_1):PAGE82_I202@PURE_QUANTA.SCONN288_ADR50017P130CC(CHIPS)':
 'DQS5_A_T||TDQS5_A_T': CDS_PINID='\dqs5_a_t||tdqs5_a_t\';
NODE_NAME     J2 157
 '@S9S_MB_2U_LIB.S9S_MB_2U(SCH_1):PAGE83_I181@PURE_QUANTA.SCONN288_ADR50017P087CC(CHIPS)':
 'DQS5_A_T||TDQS5_A_T': CDS_PINID='\dqs5_a_t||tdqs5_a_t\';
NET_NAME
'M_A_CPU0_SA_DQS_DP<6>'
 '@S9S_MB_2U_LIB.S9S_MB_2U(SCH_1):M_A_CPU0_SA_DQS_DP'<6>:
 C_SIGNAL='@s9s_mb_2u_lib.s9s_mb_2u(sch_1):m_a_cpu0_sa_dqs_dp(6)';
NODE_NAME     U2 M67
 '@S9S_MB_2U_LIB.S9S_MB_2U(SCH_1):PAGE20_I1@PURE_QUANTA.SOCKET4677_AZIF0045P001C01CS(CHIPS)':
 'DDR0_SA_DQS_DP6': CDS_PINID='DDR0_SA_DQS_DP6';
NODE_NAME     J1 168
 '@S9S_MB_2U_LIB.S9S_MB_2U(SCH_1):PAGE82_I202@PURE_QUANTA.SCONN288_ADR50017P130CC(CHIPS)':
 'DQS6_A_T||TDQS6_A_T': CDS_PINID='\dqs6_a_t||tdqs6_a_t\';
NODE_NAME     J2 168
 '@S9S_MB_2U_LIB.S9S_MB_2U(SCH_1):PAGE83_I181@PURE_QUANTA.SCONN288_ADR50017P087CC(CHIPS)':
 'DQS6_A_T||TDQS6_A_T': CDS_PINID='\dqs6_a_t||tdqs6_a_t\';
NET_NAME
'M_A_CPU0_SA_DQS_DP<7>'
 '@S9S_MB_2U_LIB.S9S_MB_2U(SCH_1):M_A_CPU0_SA_DQS_DP'<7>:
 C_SIGNAL='@s9s_mb_2u_lib.s9s_mb_2u(sch_1):m_a_cpu0_sa_dqs_dp(7)';
NODE_NAME     U2 E70
 '@S9S_MB_2U_LIB.S9S_MB_2U(SCH_1):PAGE20_I1@PURE_QUANTA.SOCKET4677_AZIF0045P001C01CS(CHIPS)':
 'DDR0_SA_DQS_DP7': CDS_PINID='DDR0_SA_DQS_DP7';
NODE_NAME     J1 179
 '@S9S_MB_2U_LIB.S9S_MB_2U(SCH_1):PAGE82_I202@PURE_QUANTA.SCONN288_ADR50017P130CC(CHIPS)':
 'DQS7_A_T||TDQS7_A_T': CDS_PINID='\dqs7_a_t||tdqs7_a_t\';
NODE_NAME     J2 179
 '@S9S_MB_2U_LIB.S9S_MB_2U(SCH_1):PAGE83_I181@PURE_QUANTA.SCONN288_ADR50017P087CC(CHIPS)':
 'DQS7_A_T||TDQS7_A_T': CDS_PINID='\dqs7_a_t||tdqs7_a_t\';
NET_NAME
'M_A_CPU0_SA_DQS_DP<8>'
 '@S9S_MB_2U_LIB.S9S_MB_2U(SCH_1):M_A_CPU0_SA_DQS_DP'<8>:
 C_SIGNAL='@s9s_mb_2u_lib.s9s_mb_2u(sch_1):m_a_cpu0_sa_dqs_dp(8)';
NODE_NAME     U2 E64
 '@S9S_MB_2U_LIB.S9S_MB_2U(SCH_1):PAGE20_I1@PURE_QUANTA.SOCKET4677_AZIF0045P001C01CS(CHIPS)':
 'DDR0_SA_DQS_DP8': CDS_PINID='DDR0_SA_DQS_DP8';
NODE_NAME     J1 190
 '@S9S_MB_2U_LIB.S9S_MB_2U(SCH_1):PAGE82_I202@PURE_QUANTA.SCONN288_ADR50017P130CC(CHIPS)':
 'DQS8_A_T||TDQS8_A_T': CDS_PINID='\dqs8_a_t||tdqs8_a_t\';
NODE_NAME     J2 190
 '@S9S_MB_2U_LIB.S9S_MB_2U(SCH_1):PAGE83_I181@PURE_QUANTA.SCONN288_ADR50017P087CC(CHIPS)':
 'DQS8_A_T||TDQS8_A_T': CDS_PINID='\dqs8_a_t||tdqs8_a_t\';
NET_NAME
'M_A_CPU0_SA_DQS_DP<9>'
 '@S9S_MB_2U_LIB.S9S_MB_2U(SCH_1):M_A_CPU0_SA_DQS_DP'<9>:
 C_SIGNAL='@s9s_mb_2u_lib.s9s_mb_2u(sch_1):m_a_cpu0_sa_dqs_dp(9)';
NODE_NAME     U2 E58
 '@S9S_MB_2U_LIB.S9S_MB_2U(SCH_1):PAGE20_I1@PURE_QUANTA.SOCKET4677_AZIF0045P001C01CS(CHIPS)':
 'DDR0_SA_DQS_DP9': CDS_PINID='DDR0_SA_DQS_DP9';
NODE_NAME     J1 201
 '@S9S_MB_2U_LIB.S9S_MB_2U(SCH_1):PAGE82_I202@PURE_QUANTA.SCONN288_ADR50017P130CC(CHIPS)':
 'DQS9_A_T||TDQS9_A_T': CDS_PINID='\dqs9_a_t||tdqs9_a_t\';
NODE_NAME     J2 201
 '@S9S_MB_2U_LIB.S9S_MB_2U(SCH_1):PAGE83_I181@PURE_QUANTA.SCONN288_ADR50017P087CC(CHIPS)':
 'DQS9_A_T||TDQS9_A_T': CDS_PINID='\dqs9_a_t||tdqs9_a_t\';
NET_NAME
'M_A_CPU0_SA_PAR'
 '@S9S_MB_2U_LIB.S9S_MB_2U(SCH_1):M_A_CPU0_SA_PAR':
 C_SIGNAL='@s9s_mb_2u_lib.s9s_mb_2u(sch_1):m_a_cpu0_sa_par';
NODE_NAME     U2 E48
 '@S9S_MB_2U_LIB.S9S_MB_2U(SCH_1):PAGE20_I1@PURE_QUANTA.SOCKET4677_AZIF0045P001C01CS(CHIPS)':
 'DDR0_SA_PAR': CDS_PINID='DDR0_SA_PAR';
NODE_NAME     J1 74
 '@S9S_MB_2U_LIB.S9S_MB_2U(SCH_1):PAGE82_I198@PURE_QUANTA.SCONN288_ADR50017P130CC(CHIPS)':
 'PAR_A': CDS_PINID='PAR_A';
NODE_NAME     J2 74
 '@S9S_MB_2U_LIB.S9S_MB_2U(SCH_1):PAGE83_I177@PURE_QUANTA.SCONN288_ADR50017P087CC(CHIPS)':
 'PAR_A': CDS_PINID='PAR_A';
NET_NAME
'M_A_CPU0_SA_RSP<0>'
 '@S9S_MB_2U_LIB.S9S_MB_2U(SCH_1):M_A_CPU0_SA_RSP'<0>:
 C_SIGNAL='@s9s_mb_2u_lib.s9s_mb_2u(sch_1):m_a_cpu0_sa_rsp(0)';
NODE_NAME     U2 AT42
 '@S9S_MB_2U_LIB.S9S_MB_2U(SCH_1):PAGE20_I1@PURE_QUANTA.SOCKET4677_AZIF0045P001C01CS(CHIPS)':
 'DDR0_A_RSP0': CDS_PINID='DDR0_A_RSP0';
NODE_NAME     J1 86
 '@S9S_MB_2U_LIB.S9S_MB_2U(SCH_1):PAGE82_I198@PURE_QUANTA.SCONN288_ADR50017P130CC(CHIPS)':
 'LBD||RSP_A_N': CDS_PINID='\lbd||rsp_a_n\';
NET_NAME
'M_A_CPU0_SA_RSP<1>'
 '@S9S_MB_2U_LIB.S9S_MB_2U(SCH_1):M_A_CPU0_SA_RSP'<1>:
 C_SIGNAL='@s9s_mb_2u_lib.s9s_mb_2u(sch_1):m_a_cpu0_sa_rsp(1)';
NODE_NAME     U2 AU43
 '@S9S_MB_2U_LIB.S9S_MB_2U(SCH_1):PAGE20_I1@PURE_QUANTA.SOCKET4677_AZIF0045P001C01CS(CHIPS)':
 'DDR0_A_RSP1': CDS_PINID='DDR0_A_RSP1';
NODE_NAME     J2 86
 '@S9S_MB_2U_LIB.S9S_MB_2U(SCH_1):PAGE83_I177@PURE_QUANTA.SCONN288_ADR50017P087CC(CHIPS)':
 'LBD||RSP_A_N': CDS_PINID='\lbd||rsp_a_n\';
NET_NAME
'M_A_CPU0_SB_CA<0>'
 '@S9S_MB_2U_LIB.S9S_MB_2U(SCH_1):M_A_CPU0_SB_CA'<0>:
 C_SIGNAL='@s9s_mb_2u_lib.s9s_mb_2u(sch_1):m_a_cpu0_sb_ca(0)';
NODE_NAME     U2 E43
 '@S9S_MB_2U_LIB.S9S_MB_2U(SCH_1):PAGE20_I1@PURE_QUANTA.SOCKET4677_AZIF0045P001C01CS(CHIPS)':
 'DDR0_SB_CA0': CDS_PINID='DDR0_SB_CA0';
NODE_NAME     J1 76
 '@S9S_MB_2U_LIB.S9S_MB_2U(SCH_1):PAGE82_I198@PURE_QUANTA.SCONN288_ADR50017P130CC(CHIPS)':
 'CA0_B': CDS_PINID='CA0_B';
NODE_NAME     J2 76
 '@S9S_MB_2U_LIB.S9S_MB_2U(SCH_1):PAGE83_I177@PURE_QUANTA.SCONN288_ADR50017P087CC(CHIPS)':
 'CA0_B': CDS_PINID='CA0_B';
NET_NAME
'M_A_CPU0_SB_CA<1>'
 '@S9S_MB_2U_LIB.S9S_MB_2U(SCH_1):M_A_CPU0_SB_CA'<1>:
 C_SIGNAL='@s9s_mb_2u_lib.s9s_mb_2u(sch_1):m_a_cpu0_sb_ca(1)';
NODE_NAME     U2 F44
 '@S9S_MB_2U_LIB.S9S_MB_2U(SCH_1):PAGE20_I1@PURE_QUANTA.SOCKET4677_AZIF0045P001C01CS(CHIPS)':
 'DDR0_SB_CA1': CDS_PINID='DDR0_SB_CA1';
NODE_NAME     J1 221
 '@S9S_MB_2U_LIB.S9S_MB_2U(SCH_1):PAGE82_I198@PURE_QUANTA.SCONN288_ADR50017P130CC(CHIPS)':
 'CA1_B': CDS_PINID='CA1_B';
NODE_NAME     J2 221
 '@S9S_MB_2U_LIB.S9S_MB_2U(SCH_1):PAGE83_I177@PURE_QUANTA.SCONN288_ADR50017P087CC(CHIPS)':
 'CA1_B': CDS_PINID='CA1_B';
NET_NAME
'M_A_CPU0_SB_CA<2>'
 '@S9S_MB_2U_LIB.S9S_MB_2U(SCH_1):M_A_CPU0_SB_CA'<2>:
 C_SIGNAL='@s9s_mb_2u_lib.s9s_mb_2u(sch_1):m_a_cpu0_sb_ca(2)';
NODE_NAME     U2 C41
 '@S9S_MB_2U_LIB.S9S_MB_2U(SCH_1):PAGE20_I1@PURE_QUANTA.SOCKET4677_AZIF0045P001C01CS(CHIPS)':
 'DDR0_SB_CA2': CDS_PINID='DDR0_SB_CA2';
NODE_NAME     J1 78
 '@S9S_MB_2U_LIB.S9S_MB_2U(SCH_1):PAGE82_I198@PURE_QUANTA.SCONN288_ADR50017P130CC(CHIPS)':
 'CA2_B': CDS_PINID='CA2_B';
NODE_NAME     J2 78
 '@S9S_MB_2U_LIB.S9S_MB_2U(SCH_1):PAGE83_I177@PURE_QUANTA.SCONN288_ADR50017P087CC(CHIPS)':
 'CA2_B': CDS_PINID='CA2_B';
NET_NAME
'M_A_CPU0_SB_CA<3>'
 '@S9S_MB_2U_LIB.S9S_MB_2U(SCH_1):M_A_CPU0_SB_CA'<3>:
 C_SIGNAL='@s9s_mb_2u_lib.s9s_mb_2u(sch_1):m_a_cpu0_sb_ca(3)';
NODE_NAME     U2 E41
 '@S9S_MB_2U_LIB.S9S_MB_2U(SCH_1):PAGE20_I1@PURE_QUANTA.SOCKET4677_AZIF0045P001C01CS(CHIPS)':
 'DDR0_SB_CA3': CDS_PINID='DDR0_SB_CA3';
NODE_NAME     J1 223
 '@S9S_MB_2U_LIB.S9S_MB_2U(SCH_1):PAGE82_I198@PURE_QUANTA.SCONN288_ADR50017P130CC(CHIPS)':
 'CA3_B': CDS_PINID='CA3_B';
NODE_NAME     J2 223
 '@S9S_MB_2U_LIB.S9S_MB_2U(SCH_1):PAGE83_I177@PURE_QUANTA.SCONN288_ADR50017P087CC(CHIPS)':
 'CA3_B': CDS_PINID='CA3_B';
NET_NAME
'M_A_CPU0_SB_CA<4>'
 '@S9S_MB_2U_LIB.S9S_MB_2U(SCH_1):M_A_CPU0_SB_CA'<4>:
 C_SIGNAL='@s9s_mb_2u_lib.s9s_mb_2u(sch_1):m_a_cpu0_sb_ca(4)';
NODE_NAME     U2 B40
 '@S9S_MB_2U_LIB.S9S_MB_2U(SCH_1):PAGE20_I1@PURE_QUANTA.SOCKET4677_AZIF0045P001C01CS(CHIPS)':
 'DDR0_SB_CA4': CDS_PINID='DDR0_SB_CA4';
NODE_NAME     J1 80
 '@S9S_MB_2U_LIB.S9S_MB_2U(SCH_1):PAGE82_I198@PURE_QUANTA.SCONN288_ADR50017P130CC(CHIPS)':
 'CA4_B': CDS_PINID='CA4_B';
NODE_NAME     J2 80
 '@S9S_MB_2U_LIB.S9S_MB_2U(SCH_1):PAGE83_I177@PURE_QUANTA.SCONN288_ADR50017P087CC(CHIPS)':
 'CA4_B': CDS_PINID='CA4_B';
NET_NAME
'M_A_CPU0_SB_CA<5>'
 '@S9S_MB_2U_LIB.S9S_MB_2U(SCH_1):M_A_CPU0_SB_CA'<5>:
 C_SIGNAL='@s9s_mb_2u_lib.s9s_mb_2u(sch_1):m_a_cpu0_sb_ca(5)';
NODE_NAME     U2 F40
 '@S9S_MB_2U_LIB.S9S_MB_2U(SCH_1):PAGE20_I1@PURE_QUANTA.SOCKET4677_AZIF0045P001C01CS(CHIPS)':
 'DDR0_SB_CA5': CDS_PINID='DDR0_SB_CA5';
NODE_NAME     J1 225
 '@S9S_MB_2U_LIB.S9S_MB_2U(SCH_1):PAGE82_I198@PURE_QUANTA.SCONN288_ADR50017P130CC(CHIPS)':
 'CA5_B': CDS_PINID='CA5_B';
NODE_NAME     J2 225
 '@S9S_MB_2U_LIB.S9S_MB_2U(SCH_1):PAGE83_I177@PURE_QUANTA.SCONN288_ADR50017P087CC(CHIPS)':
 'CA5_B': CDS_PINID='CA5_B';
NET_NAME
'M_A_CPU0_SB_CA<6>'
 '@S9S_MB_2U_LIB.S9S_MB_2U(SCH_1):M_A_CPU0_SB_CA'<6>:
 C_SIGNAL='@s9s_mb_2u_lib.s9s_mb_2u(sch_1):m_a_cpu0_sb_ca(6)';
NODE_NAME     U2 A39
 '@S9S_MB_2U_LIB.S9S_MB_2U(SCH_1):PAGE20_I1@PURE_QUANTA.SOCKET4677_AZIF0045P001C01CS(CHIPS)':
 'DDR0_SB_CA6': CDS_PINID='DDR0_SB_CA6';
NODE_NAME     J1 82
 '@S9S_MB_2U_LIB.S9S_MB_2U(SCH_1):PAGE82_I198@PURE_QUANTA.SCONN288_ADR50017P130CC(CHIPS)':
 'CA6_B': CDS_PINID='CA6_B';
NODE_NAME     J2 82
 '@S9S_MB_2U_LIB.S9S_MB_2U(SCH_1):PAGE83_I177@PURE_QUANTA.SCONN288_ADR50017P087CC(CHIPS)':
 'CA6_B': CDS_PINID='CA6_B';
NET_NAME
'M_A_CPU0_SB_CB<0>'
 '@S9S_MB_2U_LIB.S9S_MB_2U(SCH_1):M_A_CPU0_SB_CB'<0>:
 C_SIGNAL='@s9s_mb_2u_lib.s9s_mb_2u(sch_1):m_a_cpu0_sb_cb(0)';
NODE_NAME     U2 B32
 '@S9S_MB_2U_LIB.S9S_MB_2U(SCH_1):PAGE20_I1@PURE_QUANTA.SOCKET4677_AZIF0045P001C01CS(CHIPS)':
 'DDR0_SB_ECC0': CDS_PINID='DDR0_SB_ECC0';
NODE_NAME     J1 96
 '@S9S_MB_2U_LIB.S9S_MB_2U(SCH_1):PAGE82_I198@PURE_QUANTA.SCONN288_ADR50017P130CC(CHIPS)':
 'CB0_B': CDS_PINID='CB0_B';
NODE_NAME     J2 96
 '@S9S_MB_2U_LIB.S9S_MB_2U(SCH_1):PAGE83_I177@PURE_QUANTA.SCONN288_ADR50017P087CC(CHIPS)':
 'CB0_B': CDS_PINID='CB0_B';
NET_NAME
'M_A_CPU0_SB_CB<1>'
 '@S9S_MB_2U_LIB.S9S_MB_2U(SCH_1):M_A_CPU0_SB_CB'<1>:
 C_SIGNAL='@s9s_mb_2u_lib.s9s_mb_2u(sch_1):m_a_cpu0_sb_cb(1)';
NODE_NAME     U2 C31
 '@S9S_MB_2U_LIB.S9S_MB_2U(SCH_1):PAGE20_I1@PURE_QUANTA.SOCKET4677_AZIF0045P001C01CS(CHIPS)':
 'DDR0_SB_ECC1': CDS_PINID='DDR0_SB_ECC1';
NODE_NAME     J1 98
 '@S9S_MB_2U_LIB.S9S_MB_2U(SCH_1):PAGE82_I198@PURE_QUANTA.SCONN288_ADR50017P130CC(CHIPS)':
 'CB1_B': CDS_PINID='CB1_B';
NODE_NAME     J2 98
 '@S9S_MB_2U_LIB.S9S_MB_2U(SCH_1):PAGE83_I177@PURE_QUANTA.SCONN288_ADR50017P087CC(CHIPS)':
 'CB1_B': CDS_PINID='CB1_B';
NET_NAME
'M_A_CPU0_SB_CB<2>'
 '@S9S_MB_2U_LIB.S9S_MB_2U(SCH_1):M_A_CPU0_SB_CB'<2>:
 C_SIGNAL='@s9s_mb_2u_lib.s9s_mb_2u(sch_1):m_a_cpu0_sb_cb(2)';
NODE_NAME     U2 F32
 '@S9S_MB_2U_LIB.S9S_MB_2U(SCH_1):PAGE20_I1@PURE_QUANTA.SOCKET4677_AZIF0045P001C01CS(CHIPS)':
 'DDR0_SB_ECC2': CDS_PINID='DDR0_SB_ECC2';
NODE_NAME     J1 241
 '@S9S_MB_2U_LIB.S9S_MB_2U(SCH_1):PAGE82_I198@PURE_QUANTA.SCONN288_ADR50017P130CC(CHIPS)':
 'CB2_B': CDS_PINID='CB2_B';
NODE_NAME     J2 241
 '@S9S_MB_2U_LIB.S9S_MB_2U(SCH_1):PAGE83_I177@PURE_QUANTA.SCONN288_ADR50017P087CC(CHIPS)':
 'CB2_B': CDS_PINID='CB2_B';
NET_NAME
'M_A_CPU0_SB_CB<3>'
 '@S9S_MB_2U_LIB.S9S_MB_2U(SCH_1):M_A_CPU0_SB_CB'<3>:
 C_SIGNAL='@s9s_mb_2u_lib.s9s_mb_2u(sch_1):m_a_cpu0_sb_cb(3)';
NODE_NAME     U2 E31
 '@S9S_MB_2U_LIB.S9S_MB_2U(SCH_1):PAGE20_I1@PURE_QUANTA.SOCKET4677_AZIF0045P001C01CS(CHIPS)':
 'DDR0_SB_ECC3': CDS_PINID='DDR0_SB_ECC3';
NODE_NAME     J1 243
 '@S9S_MB_2U_LIB.S9S_MB_2U(SCH_1):PAGE82_I198@PURE_QUANTA.SCONN288_ADR50017P130CC(CHIPS)':
 'CB3_B': CDS_PINID='CB3_B';
NODE_NAME     J2 243
 '@S9S_MB_2U_LIB.S9S_MB_2U(SCH_1):PAGE83_I177@PURE_QUANTA.SCONN288_ADR50017P087CC(CHIPS)':
 'CB3_B': CDS_PINID='CB3_B';
NET_NAME
'M_A_CPU0_SB_CB<4>'
 '@S9S_MB_2U_LIB.S9S_MB_2U(SCH_1):M_A_CPU0_SB_CB'<4>:
 C_SIGNAL='@s9s_mb_2u_lib.s9s_mb_2u(sch_1):m_a_cpu0_sb_cb(4)';
NODE_NAME     U2 C35
 '@S9S_MB_2U_LIB.S9S_MB_2U(SCH_1):PAGE20_I1@PURE_QUANTA.SOCKET4677_AZIF0045P001C01CS(CHIPS)':
 'DDR0_SB_ECC4': CDS_PINID='DDR0_SB_ECC4';
NODE_NAME     J1 89
 '@S9S_MB_2U_LIB.S9S_MB_2U(SCH_1):PAGE82_I198@PURE_QUANTA.SCONN288_ADR50017P130CC(CHIPS)':
 'CB4_B': CDS_PINID='CB4_B';
NODE_NAME     J2 89
 '@S9S_MB_2U_LIB.S9S_MB_2U(SCH_1):PAGE83_I177@PURE_QUANTA.SCONN288_ADR50017P087CC(CHIPS)':
 'CB4_B': CDS_PINID='CB4_B';
NET_NAME
'M_A_CPU0_SB_CB<5>'
 '@S9S_MB_2U_LIB.S9S_MB_2U(SCH_1):M_A_CPU0_SB_CB'<5>:
 C_SIGNAL='@s9s_mb_2u_lib.s9s_mb_2u(sch_1):m_a_cpu0_sb_cb(5)';
NODE_NAME     U2 B34
 '@S9S_MB_2U_LIB.S9S_MB_2U(SCH_1):PAGE20_I1@PURE_QUANTA.SOCKET4677_AZIF0045P001C01CS(CHIPS)':
 'DDR0_SB_ECC5': CDS_PINID='DDR0_SB_ECC5';
NODE_NAME     J1 91
 '@S9S_MB_2U_LIB.S9S_MB_2U(SCH_1):PAGE82_I198@PURE_QUANTA.SCONN288_ADR50017P130CC(CHIPS)':
 'CB5_B': CDS_PINID='CB5_B';
NODE_NAME     J2 91
 '@S9S_MB_2U_LIB.S9S_MB_2U(SCH_1):PAGE83_I177@PURE_QUANTA.SCONN288_ADR50017P087CC(CHIPS)':
 'CB5_B': CDS_PINID='CB5_B';
NET_NAME
'M_A_CPU0_SB_CB<6>'
 '@S9S_MB_2U_LIB.S9S_MB_2U(SCH_1):M_A_CPU0_SB_CB'<6>:
 C_SIGNAL='@s9s_mb_2u_lib.s9s_mb_2u(sch_1):m_a_cpu0_sb_cb(6)';
NODE_NAME     U2 E35
 '@S9S_MB_2U_LIB.S9S_MB_2U(SCH_1):PAGE20_I1@PURE_QUANTA.SOCKET4677_AZIF0045P001C01CS(CHIPS)':
 'DDR0_SB_ECC6': CDS_PINID='DDR0_SB_ECC6';
NODE_NAME     J1 234
 '@S9S_MB_2U_LIB.S9S_MB_2U(SCH_1):PAGE82_I198@PURE_QUANTA.SCONN288_ADR50017P130CC(CHIPS)':
 'CB6_B': CDS_PINID='CB6_B';
NODE_NAME     J2 234
 '@S9S_MB_2U_LIB.S9S_MB_2U(SCH_1):PAGE83_I177@PURE_QUANTA.SCONN288_ADR50017P087CC(CHIPS)':
 'CB6_B': CDS_PINID='CB6_B';
NET_NAME
'M_A_CPU0_SB_CB<7>'
 '@S9S_MB_2U_LIB.S9S_MB_2U(SCH_1):M_A_CPU0_SB_CB'<7>:
 C_SIGNAL='@s9s_mb_2u_lib.s9s_mb_2u(sch_1):m_a_cpu0_sb_cb(7)';
NODE_NAME     U2 F34
 '@S9S_MB_2U_LIB.S9S_MB_2U(SCH_1):PAGE20_I1@PURE_QUANTA.SOCKET4677_AZIF0045P001C01CS(CHIPS)':
 'DDR0_SB_ECC7': CDS_PINID='DDR0_SB_ECC7';
NODE_NAME     J1 236
 '@S9S_MB_2U_LIB.S9S_MB_2U(SCH_1):PAGE82_I198@PURE_QUANTA.SCONN288_ADR50017P130CC(CHIPS)':
 'CB7_B': CDS_PINID='CB7_B';
NODE_NAME     J2 236
 '@S9S_MB_2U_LIB.S9S_MB_2U(SCH_1):PAGE83_I177@PURE_QUANTA.SCONN288_ADR50017P087CC(CHIPS)':
 'CB7_B': CDS_PINID='CB7_B';
NET_NAME
'M_A_CPU0_SB_CS_N<0>'
 '@S9S_MB_2U_LIB.S9S_MB_2U(SCH_1):M_A_CPU0_SB_CS_N'<0>:
 C_SIGNAL='@s9s_mb_2u_lib.s9s_mb_2u(sch_1):m_a_cpu0_sb_cs_n(0)';
NODE_NAME     U2 B38
 '@S9S_MB_2U_LIB.S9S_MB_2U(SCH_1):PAGE20_I1@PURE_QUANTA.SOCKET4677_AZIF0045P001C01CS(CHIPS)':
 'DDR0_SB_CS_N0': CDS_PINID='DDR0_SB_CS_N0';
NODE_NAME     J1 84
 '@S9S_MB_2U_LIB.S9S_MB_2U(SCH_1):PAGE82_I198@PURE_QUANTA.SCONN288_ADR50017P130CC(CHIPS)':
 'CS0_B_N': CDS_PINID='CS0_B_N';
NET_NAME
'M_A_CPU0_SB_CS_N<1>'
 '@S9S_MB_2U_LIB.S9S_MB_2U(SCH_1):M_A_CPU0_SB_CS_N'<1>:
 C_SIGNAL='@s9s_mb_2u_lib.s9s_mb_2u(sch_1):m_a_cpu0_sb_cs_n(1)';
NODE_NAME     U2 C37
 '@S9S_MB_2U_LIB.S9S_MB_2U(SCH_1):PAGE20_I1@PURE_QUANTA.SOCKET4677_AZIF0045P001C01CS(CHIPS)':
 'DDR0_SB_CS_N1': CDS_PINID='DDR0_SB_CS_N1';
NODE_NAME     J1 229
 '@S9S_MB_2U_LIB.S9S_MB_2U(SCH_1):PAGE82_I198@PURE_QUANTA.SCONN288_ADR50017P130CC(CHIPS)':
 'CS1_B_N': CDS_PINID='CS1_B_N';
NET_NAME
'M_A_CPU0_SB_CS_N<2>'
 '@S9S_MB_2U_LIB.S9S_MB_2U(SCH_1):M_A_CPU0_SB_CS_N'<2>:
 C_SIGNAL='@s9s_mb_2u_lib.s9s_mb_2u(sch_1):m_a_cpu0_sb_cs_n(2)';
NODE_NAME     U2 F38
 '@S9S_MB_2U_LIB.S9S_MB_2U(SCH_1):PAGE20_I1@PURE_QUANTA.SOCKET4677_AZIF0045P001C01CS(CHIPS)':
 'DDR0_SB_CS_N2': CDS_PINID='DDR0_SB_CS_N2';
NODE_NAME     J2 84
 '@S9S_MB_2U_LIB.S9S_MB_2U(SCH_1):PAGE83_I177@PURE_QUANTA.SCONN288_ADR50017P087CC(CHIPS)':
 'CS0_B_N': CDS_PINID='CS0_B_N';
NET_NAME
'M_A_CPU0_SB_CS_N<3>'
 '@S9S_MB_2U_LIB.S9S_MB_2U(SCH_1):M_A_CPU0_SB_CS_N'<3>:
 C_SIGNAL='@s9s_mb_2u_lib.s9s_mb_2u(sch_1):m_a_cpu0_sb_cs_n(3)';
NODE_NAME     U2 E37
 '@S9S_MB_2U_LIB.S9S_MB_2U(SCH_1):PAGE20_I1@PURE_QUANTA.SOCKET4677_AZIF0045P001C01CS(CHIPS)':
 'DDR0_SB_CS_N3': CDS_PINID='DDR0_SB_CS_N3';
NODE_NAME     J2 229
 '@S9S_MB_2U_LIB.S9S_MB_2U(SCH_1):PAGE83_I177@PURE_QUANTA.SCONN288_ADR50017P087CC(CHIPS)':
 'CS1_B_N': CDS_PINID='CS1_B_N';
NET_NAME
'M_A_CPU0_SB_DQ<0>'
 '@S9S_MB_2U_LIB.S9S_MB_2U(SCH_1):M_A_CPU0_SB_DQ'<0>:
 C_SIGNAL='@s9s_mb_2u_lib.s9s_mb_2u(sch_1):m_a_cpu0_sb_dq(0)';
NODE_NAME     U2 K32
 '@S9S_MB_2U_LIB.S9S_MB_2U(SCH_1):PAGE20_I1@PURE_QUANTA.SOCKET4677_AZIF0045P001C01CS(CHIPS)':
 'DDR0_SB_DQ0': CDS_PINID='DDR0_SB_DQ0';
NODE_NAME     J1 100
 '@S9S_MB_2U_LIB.S9S_MB_2U(SCH_1):PAGE82_I198@PURE_QUANTA.SCONN288_ADR50017P130CC(CHIPS)':
 'DQ0_B': CDS_PINID='DQ0_B';
NODE_NAME     J2 100
 '@S9S_MB_2U_LIB.S9S_MB_2U(SCH_1):PAGE83_I177@PURE_QUANTA.SCONN288_ADR50017P087CC(CHIPS)':
 'DQ0_B': CDS_PINID='DQ0_B';
NET_NAME
'M_A_CPU0_SB_DQ<10>'
 '@S9S_MB_2U_LIB.S9S_MB_2U(SCH_1):M_A_CPU0_SB_DQ'<10>:
 C_SIGNAL='@s9s_mb_2u_lib.s9s_mb_2u(sch_1):m_a_cpu0_sb_dq(10)';
NODE_NAME     U2 E29
 '@S9S_MB_2U_LIB.S9S_MB_2U(SCH_1):PAGE20_I1@PURE_QUANTA.SOCKET4677_AZIF0045P001C01CS(CHIPS)':
 'DDR0_SB_DQ10': CDS_PINID='DDR0_SB_DQ10';
NODE_NAME     J1 256
 '@S9S_MB_2U_LIB.S9S_MB_2U(SCH_1):PAGE82_I198@PURE_QUANTA.SCONN288_ADR50017P130CC(CHIPS)':
 'DQ10_B': CDS_PINID='DQ10_B';
NODE_NAME     J2 256
 '@S9S_MB_2U_LIB.S9S_MB_2U(SCH_1):PAGE83_I177@PURE_QUANTA.SCONN288_ADR50017P087CC(CHIPS)':
 'DQ10_B': CDS_PINID='DQ10_B';
NET_NAME
'M_A_CPU0_SB_DQ<11>'
 '@S9S_MB_2U_LIB.S9S_MB_2U(SCH_1):M_A_CPU0_SB_DQ'<11>:
 C_SIGNAL='@s9s_mb_2u_lib.s9s_mb_2u(sch_1):m_a_cpu0_sb_dq(11)';
NODE_NAME     U2 F28
 '@S9S_MB_2U_LIB.S9S_MB_2U(SCH_1):PAGE20_I1@PURE_QUANTA.SOCKET4677_AZIF0045P001C01CS(CHIPS)':
 'DDR0_SB_DQ11': CDS_PINID='DDR0_SB_DQ11';
NODE_NAME     J1 258
 '@S9S_MB_2U_LIB.S9S_MB_2U(SCH_1):PAGE82_I198@PURE_QUANTA.SCONN288_ADR50017P130CC(CHIPS)':
 'DQ11_B': CDS_PINID='DQ11_B';
NODE_NAME     J2 258
 '@S9S_MB_2U_LIB.S9S_MB_2U(SCH_1):PAGE83_I177@PURE_QUANTA.SCONN288_ADR50017P087CC(CHIPS)':
 'DQ11_B': CDS_PINID='DQ11_B';
NET_NAME
'M_A_CPU0_SB_DQ<12>'
 '@S9S_MB_2U_LIB.S9S_MB_2U(SCH_1):M_A_CPU0_SB_DQ'<12>:
 C_SIGNAL='@s9s_mb_2u_lib.s9s_mb_2u(sch_1):m_a_cpu0_sb_dq(12)';
NODE_NAME     U2 B26
 '@S9S_MB_2U_LIB.S9S_MB_2U(SCH_1):PAGE20_I1@PURE_QUANTA.SOCKET4677_AZIF0045P001C01CS(CHIPS)':
 'DDR0_SB_DQ12': CDS_PINID='DDR0_SB_DQ12';
NODE_NAME     J1 118
 '@S9S_MB_2U_LIB.S9S_MB_2U(SCH_1):PAGE82_I198@PURE_QUANTA.SCONN288_ADR50017P130CC(CHIPS)':
 'DQ12_B': CDS_PINID='DQ12_B';
NODE_NAME     J2 118
 '@S9S_MB_2U_LIB.S9S_MB_2U(SCH_1):PAGE83_I177@PURE_QUANTA.SCONN288_ADR50017P087CC(CHIPS)':
 'DQ12_B': CDS_PINID='DQ12_B';
NET_NAME
'M_A_CPU0_SB_DQ<13>'
 '@S9S_MB_2U_LIB.S9S_MB_2U(SCH_1):M_A_CPU0_SB_DQ'<13>:
 C_SIGNAL='@s9s_mb_2u_lib.s9s_mb_2u(sch_1):m_a_cpu0_sb_dq(13)';
NODE_NAME     U2 C25
 '@S9S_MB_2U_LIB.S9S_MB_2U(SCH_1):PAGE20_I1@PURE_QUANTA.SOCKET4677_AZIF0045P001C01CS(CHIPS)':
 'DDR0_SB_DQ13': CDS_PINID='DDR0_SB_DQ13';
NODE_NAME     J1 120
 '@S9S_MB_2U_LIB.S9S_MB_2U(SCH_1):PAGE82_I198@PURE_QUANTA.SCONN288_ADR50017P130CC(CHIPS)':
 'DQ13_B': CDS_PINID='DQ13_B';
NODE_NAME     J2 120
 '@S9S_MB_2U_LIB.S9S_MB_2U(SCH_1):PAGE83_I177@PURE_QUANTA.SCONN288_ADR50017P087CC(CHIPS)':
 'DQ13_B': CDS_PINID='DQ13_B';
NET_NAME
'M_A_CPU0_SB_DQ<14>'
 '@S9S_MB_2U_LIB.S9S_MB_2U(SCH_1):M_A_CPU0_SB_DQ'<14>:
 C_SIGNAL='@s9s_mb_2u_lib.s9s_mb_2u(sch_1):m_a_cpu0_sb_dq(14)';
NODE_NAME     U2 F26
 '@S9S_MB_2U_LIB.S9S_MB_2U(SCH_1):PAGE20_I1@PURE_QUANTA.SOCKET4677_AZIF0045P001C01CS(CHIPS)':
 'DDR0_SB_DQ14': CDS_PINID='DDR0_SB_DQ14';
NODE_NAME     J1 263
 '@S9S_MB_2U_LIB.S9S_MB_2U(SCH_1):PAGE82_I198@PURE_QUANTA.SCONN288_ADR50017P130CC(CHIPS)':
 'DQ14_B': CDS_PINID='DQ14_B';
NODE_NAME     J2 263
 '@S9S_MB_2U_LIB.S9S_MB_2U(SCH_1):PAGE83_I177@PURE_QUANTA.SCONN288_ADR50017P087CC(CHIPS)':
 'DQ14_B': CDS_PINID='DQ14_B';
NET_NAME
'M_A_CPU0_SB_DQ<15>'
 '@S9S_MB_2U_LIB.S9S_MB_2U(SCH_1):M_A_CPU0_SB_DQ'<15>:
 C_SIGNAL='@s9s_mb_2u_lib.s9s_mb_2u(sch_1):m_a_cpu0_sb_dq(15)';
NODE_NAME     U2 E25
 '@S9S_MB_2U_LIB.S9S_MB_2U(SCH_1):PAGE20_I1@PURE_QUANTA.SOCKET4677_AZIF0045P001C01CS(CHIPS)':
 'DDR0_SB_DQ15': CDS_PINID='DDR0_SB_DQ15';
NODE_NAME     J1 265
 '@S9S_MB_2U_LIB.S9S_MB_2U(SCH_1):PAGE82_I198@PURE_QUANTA.SCONN288_ADR50017P130CC(CHIPS)':
 'DQ15_B': CDS_PINID='DQ15_B';
NODE_NAME     J2 265
 '@S9S_MB_2U_LIB.S9S_MB_2U(SCH_1):PAGE83_I177@PURE_QUANTA.SCONN288_ADR50017P087CC(CHIPS)':
 'DQ15_B': CDS_PINID='DQ15_B';
NET_NAME
'M_A_CPU0_SB_DQ<16>'
 '@S9S_MB_2U_LIB.S9S_MB_2U(SCH_1):M_A_CPU0_SB_DQ'<16>:
 C_SIGNAL='@s9s_mb_2u_lib.s9s_mb_2u(sch_1):m_a_cpu0_sb_dq(16)';
NODE_NAME     U2 C23
 '@S9S_MB_2U_LIB.S9S_MB_2U(SCH_1):PAGE20_I1@PURE_QUANTA.SOCKET4677_AZIF0045P001C01CS(CHIPS)':
 'DDR0_SB_DQ16': CDS_PINID='DDR0_SB_DQ16';
NODE_NAME     J1 122
 '@S9S_MB_2U_LIB.S9S_MB_2U(SCH_1):PAGE82_I198@PURE_QUANTA.SCONN288_ADR50017P130CC(CHIPS)':
 'DQ16_B': CDS_PINID='DQ16_B';
NODE_NAME     J2 122
 '@S9S_MB_2U_LIB.S9S_MB_2U(SCH_1):PAGE83_I177@PURE_QUANTA.SCONN288_ADR50017P087CC(CHIPS)':
 'DQ16_B': CDS_PINID='DQ16_B';
NET_NAME
'M_A_CPU0_SB_DQ<17>'
 '@S9S_MB_2U_LIB.S9S_MB_2U(SCH_1):M_A_CPU0_SB_DQ'<17>:
 C_SIGNAL='@s9s_mb_2u_lib.s9s_mb_2u(sch_1):m_a_cpu0_sb_dq(17)';
NODE_NAME     U2 B22
 '@S9S_MB_2U_LIB.S9S_MB_2U(SCH_1):PAGE20_I1@PURE_QUANTA.SOCKET4677_AZIF0045P001C01CS(CHIPS)':
 'DDR0_SB_DQ17': CDS_PINID='DDR0_SB_DQ17';
NODE_NAME     J1 124
 '@S9S_MB_2U_LIB.S9S_MB_2U(SCH_1):PAGE82_I198@PURE_QUANTA.SCONN288_ADR50017P130CC(CHIPS)':
 'DQ17_B': CDS_PINID='DQ17_B';
NODE_NAME     J2 124
 '@S9S_MB_2U_LIB.S9S_MB_2U(SCH_1):PAGE83_I177@PURE_QUANTA.SCONN288_ADR50017P087CC(CHIPS)':
 'DQ17_B': CDS_PINID='DQ17_B';
NET_NAME
'M_A_CPU0_SB_DQ<18>'
 '@S9S_MB_2U_LIB.S9S_MB_2U(SCH_1):M_A_CPU0_SB_DQ'<18>:
 C_SIGNAL='@s9s_mb_2u_lib.s9s_mb_2u(sch_1):m_a_cpu0_sb_dq(18)';
NODE_NAME     U2 E23
 '@S9S_MB_2U_LIB.S9S_MB_2U(SCH_1):PAGE20_I1@PURE_QUANTA.SOCKET4677_AZIF0045P001C01CS(CHIPS)':
 'DDR0_SB_DQ18': CDS_PINID='DDR0_SB_DQ18';
NODE_NAME     J1 267
 '@S9S_MB_2U_LIB.S9S_MB_2U(SCH_1):PAGE82_I198@PURE_QUANTA.SCONN288_ADR50017P130CC(CHIPS)':
 'DQ18_B': CDS_PINID='DQ18_B';
NODE_NAME     J2 267
 '@S9S_MB_2U_LIB.S9S_MB_2U(SCH_1):PAGE83_I177@PURE_QUANTA.SCONN288_ADR50017P087CC(CHIPS)':
 'DQ18_B': CDS_PINID='DQ18_B';
NET_NAME
'M_A_CPU0_SB_DQ<19>'
 '@S9S_MB_2U_LIB.S9S_MB_2U(SCH_1):M_A_CPU0_SB_DQ'<19>:
 C_SIGNAL='@s9s_mb_2u_lib.s9s_mb_2u(sch_1):m_a_cpu0_sb_dq(19)';
NODE_NAME     U2 F22
 '@S9S_MB_2U_LIB.S9S_MB_2U(SCH_1):PAGE20_I1@PURE_QUANTA.SOCKET4677_AZIF0045P001C01CS(CHIPS)':
 'DDR0_SB_DQ19': CDS_PINID='DDR0_SB_DQ19';
NODE_NAME     J1 269
 '@S9S_MB_2U_LIB.S9S_MB_2U(SCH_1):PAGE82_I198@PURE_QUANTA.SCONN288_ADR50017P130CC(CHIPS)':
 'DQ19_B': CDS_PINID='DQ19_B';
NODE_NAME     J2 269
 '@S9S_MB_2U_LIB.S9S_MB_2U(SCH_1):PAGE83_I177@PURE_QUANTA.SCONN288_ADR50017P087CC(CHIPS)':
 'DQ19_B': CDS_PINID='DQ19_B';
NET_NAME
'M_A_CPU0_SB_DQ<1>'
 '@S9S_MB_2U_LIB.S9S_MB_2U(SCH_1):M_A_CPU0_SB_DQ'<1>:
 C_SIGNAL='@s9s_mb_2u_lib.s9s_mb_2u(sch_1):m_a_cpu0_sb_dq(1)';
NODE_NAME     U2 J31
 '@S9S_MB_2U_LIB.S9S_MB_2U(SCH_1):PAGE20_I1@PURE_QUANTA.SOCKET4677_AZIF0045P001C01CS(CHIPS)':
 'DDR0_SB_DQ1': CDS_PINID='DDR0_SB_DQ1';
NODE_NAME     J1 102
 '@S9S_MB_2U_LIB.S9S_MB_2U(SCH_1):PAGE82_I198@PURE_QUANTA.SCONN288_ADR50017P130CC(CHIPS)':
 'DQ1_B': CDS_PINID='DQ1_B';
NODE_NAME     J2 102
 '@S9S_MB_2U_LIB.S9S_MB_2U(SCH_1):PAGE83_I177@PURE_QUANTA.SCONN288_ADR50017P087CC(CHIPS)':
 'DQ1_B': CDS_PINID='DQ1_B';
NET_NAME
'M_A_CPU0_SB_DQ<20>'
 '@S9S_MB_2U_LIB.S9S_MB_2U(SCH_1):M_A_CPU0_SB_DQ'<20>:
 C_SIGNAL='@s9s_mb_2u_lib.s9s_mb_2u(sch_1):m_a_cpu0_sb_dq(20)';
NODE_NAME     U2 B20
 '@S9S_MB_2U_LIB.S9S_MB_2U(SCH_1):PAGE20_I1@PURE_QUANTA.SOCKET4677_AZIF0045P001C01CS(CHIPS)':
 'DDR0_SB_DQ20': CDS_PINID='DDR0_SB_DQ20';
NODE_NAME     J1 129
 '@S9S_MB_2U_LIB.S9S_MB_2U(SCH_1):PAGE82_I198@PURE_QUANTA.SCONN288_ADR50017P130CC(CHIPS)':
 'DQ20_B': CDS_PINID='DQ20_B';
NODE_NAME     J2 129
 '@S9S_MB_2U_LIB.S9S_MB_2U(SCH_1):PAGE83_I177@PURE_QUANTA.SCONN288_ADR50017P087CC(CHIPS)':
 'DQ20_B': CDS_PINID='DQ20_B';
NET_NAME
'M_A_CPU0_SB_DQ<21>'
 '@S9S_MB_2U_LIB.S9S_MB_2U(SCH_1):M_A_CPU0_SB_DQ'<21>:
 C_SIGNAL='@s9s_mb_2u_lib.s9s_mb_2u(sch_1):m_a_cpu0_sb_dq(21)';
NODE_NAME     U2 C19
 '@S9S_MB_2U_LIB.S9S_MB_2U(SCH_1):PAGE20_I1@PURE_QUANTA.SOCKET4677_AZIF0045P001C01CS(CHIPS)':
 'DDR0_SB_DQ21': CDS_PINID='DDR0_SB_DQ21';
NODE_NAME     J1 131
 '@S9S_MB_2U_LIB.S9S_MB_2U(SCH_1):PAGE82_I198@PURE_QUANTA.SCONN288_ADR50017P130CC(CHIPS)':
 'DQ21_B': CDS_PINID='DQ21_B';
NODE_NAME     J2 131
 '@S9S_MB_2U_LIB.S9S_MB_2U(SCH_1):PAGE83_I177@PURE_QUANTA.SCONN288_ADR50017P087CC(CHIPS)':
 'DQ21_B': CDS_PINID='DQ21_B';
NET_NAME
'M_A_CPU0_SB_DQ<22>'
 '@S9S_MB_2U_LIB.S9S_MB_2U(SCH_1):M_A_CPU0_SB_DQ'<22>:
 C_SIGNAL='@s9s_mb_2u_lib.s9s_mb_2u(sch_1):m_a_cpu0_sb_dq(22)';
NODE_NAME     U2 F20
 '@S9S_MB_2U_LIB.S9S_MB_2U(SCH_1):PAGE20_I1@PURE_QUANTA.SOCKET4677_AZIF0045P001C01CS(CHIPS)':
 'DDR0_SB_DQ22': CDS_PINID='DDR0_SB_DQ22';
NODE_NAME     J1 274
 '@S9S_MB_2U_LIB.S9S_MB_2U(SCH_1):PAGE82_I198@PURE_QUANTA.SCONN288_ADR50017P130CC(CHIPS)':
 'DQ22_B': CDS_PINID='DQ22_B';
NODE_NAME     J2 274
 '@S9S_MB_2U_LIB.S9S_MB_2U(SCH_1):PAGE83_I177@PURE_QUANTA.SCONN288_ADR50017P087CC(CHIPS)':
 'DQ22_B': CDS_PINID='DQ22_B';
NET_NAME
'M_A_CPU0_SB_DQ<23>'
 '@S9S_MB_2U_LIB.S9S_MB_2U(SCH_1):M_A_CPU0_SB_DQ'<23>:
 C_SIGNAL='@s9s_mb_2u_lib.s9s_mb_2u(sch_1):m_a_cpu0_sb_dq(23)';
NODE_NAME     U2 E19
 '@S9S_MB_2U_LIB.S9S_MB_2U(SCH_1):PAGE20_I1@PURE_QUANTA.SOCKET4677_AZIF0045P001C01CS(CHIPS)':
 'DDR0_SB_DQ23': CDS_PINID='DDR0_SB_DQ23';
NODE_NAME     J1 276
 '@S9S_MB_2U_LIB.S9S_MB_2U(SCH_1):PAGE82_I198@PURE_QUANTA.SCONN288_ADR50017P130CC(CHIPS)':
 'DQ23_B': CDS_PINID='DQ23_B';
NODE_NAME     J2 276
 '@S9S_MB_2U_LIB.S9S_MB_2U(SCH_1):PAGE83_I177@PURE_QUANTA.SCONN288_ADR50017P087CC(CHIPS)':
 'DQ23_B': CDS_PINID='DQ23_B';
NET_NAME
'M_A_CPU0_SB_DQ<24>'
 '@S9S_MB_2U_LIB.S9S_MB_2U(SCH_1):M_A_CPU0_SB_DQ'<24>:
 C_SIGNAL='@s9s_mb_2u_lib.s9s_mb_2u(sch_1):m_a_cpu0_sb_dq(24)';
NODE_NAME     U2 C11
 '@S9S_MB_2U_LIB.S9S_MB_2U(SCH_1):PAGE20_I1@PURE_QUANTA.SOCKET4677_AZIF0045P001C01CS(CHIPS)':
 'DDR0_SB_DQ24': CDS_PINID='DDR0_SB_DQ24';
NODE_NAME     J1 133
 '@S9S_MB_2U_LIB.S9S_MB_2U(SCH_1):PAGE82_I198@PURE_QUANTA.SCONN288_ADR50017P130CC(CHIPS)':
 'DQ24_B': CDS_PINID='DQ24_B';
NODE_NAME     J2 133
 '@S9S_MB_2U_LIB.S9S_MB_2U(SCH_1):PAGE83_I177@PURE_QUANTA.SCONN288_ADR50017P087CC(CHIPS)':
 'DQ24_B': CDS_PINID='DQ24_B';
NET_NAME
'M_A_CPU0_SB_DQ<25>'
 '@S9S_MB_2U_LIB.S9S_MB_2U(SCH_1):M_A_CPU0_SB_DQ'<25>:
 C_SIGNAL='@s9s_mb_2u_lib.s9s_mb_2u(sch_1):m_a_cpu0_sb_dq(25)';
NODE_NAME     U2 B10
 '@S9S_MB_2U_LIB.S9S_MB_2U(SCH_1):PAGE20_I1@PURE_QUANTA.SOCKET4677_AZIF0045P001C01CS(CHIPS)':
 'DDR0_SB_DQ25': CDS_PINID='DDR0_SB_DQ25';
NODE_NAME     J1 135
 '@S9S_MB_2U_LIB.S9S_MB_2U(SCH_1):PAGE82_I198@PURE_QUANTA.SCONN288_ADR50017P130CC(CHIPS)':
 'DQ25_B': CDS_PINID='DQ25_B';
NODE_NAME     J2 135
 '@S9S_MB_2U_LIB.S9S_MB_2U(SCH_1):PAGE83_I177@PURE_QUANTA.SCONN288_ADR50017P087CC(CHIPS)':
 'DQ25_B': CDS_PINID='DQ25_B';
NET_NAME
'M_A_CPU0_SB_DQ<26>'
 '@S9S_MB_2U_LIB.S9S_MB_2U(SCH_1):M_A_CPU0_SB_DQ'<26>:
 C_SIGNAL='@s9s_mb_2u_lib.s9s_mb_2u(sch_1):m_a_cpu0_sb_dq(26)';
NODE_NAME     U2 E11
 '@S9S_MB_2U_LIB.S9S_MB_2U(SCH_1):PAGE20_I1@PURE_QUANTA.SOCKET4677_AZIF0045P001C01CS(CHIPS)':
 'DDR0_SB_DQ26': CDS_PINID='DDR0_SB_DQ26';
NODE_NAME     J1 278
 '@S9S_MB_2U_LIB.S9S_MB_2U(SCH_1):PAGE82_I198@PURE_QUANTA.SCONN288_ADR50017P130CC(CHIPS)':
 'DQ26_B': CDS_PINID='DQ26_B';
NODE_NAME     J2 278
 '@S9S_MB_2U_LIB.S9S_MB_2U(SCH_1):PAGE83_I177@PURE_QUANTA.SCONN288_ADR50017P087CC(CHIPS)':
 'DQ26_B': CDS_PINID='DQ26_B';
NET_NAME
'M_A_CPU0_SB_DQ<27>'
 '@S9S_MB_2U_LIB.S9S_MB_2U(SCH_1):M_A_CPU0_SB_DQ'<27>:
 C_SIGNAL='@s9s_mb_2u_lib.s9s_mb_2u(sch_1):m_a_cpu0_sb_dq(27)';
NODE_NAME     U2 F10
 '@S9S_MB_2U_LIB.S9S_MB_2U(SCH_1):PAGE20_I1@PURE_QUANTA.SOCKET4677_AZIF0045P001C01CS(CHIPS)':
 'DDR0_SB_DQ27': CDS_PINID='DDR0_SB_DQ27';
NODE_NAME     J1 280
 '@S9S_MB_2U_LIB.S9S_MB_2U(SCH_1):PAGE82_I198@PURE_QUANTA.SCONN288_ADR50017P130CC(CHIPS)':
 'DQ27_B': CDS_PINID='DQ27_B';
NODE_NAME     J2 280
 '@S9S_MB_2U_LIB.S9S_MB_2U(SCH_1):PAGE83_I177@PURE_QUANTA.SCONN288_ADR50017P087CC(CHIPS)':
 'DQ27_B': CDS_PINID='DQ27_B';
NET_NAME
'M_A_CPU0_SB_DQ<28>'
 '@S9S_MB_2U_LIB.S9S_MB_2U(SCH_1):M_A_CPU0_SB_DQ'<28>:
 C_SIGNAL='@s9s_mb_2u_lib.s9s_mb_2u(sch_1):m_a_cpu0_sb_dq(28)';
NODE_NAME     U2 B8
 '@S9S_MB_2U_LIB.S9S_MB_2U(SCH_1):PAGE20_I1@PURE_QUANTA.SOCKET4677_AZIF0045P001C01CS(CHIPS)':
 'DDR0_SB_DQ28': CDS_PINID='DDR0_SB_DQ28';
NODE_NAME     J1 140
 '@S9S_MB_2U_LIB.S9S_MB_2U(SCH_1):PAGE82_I198@PURE_QUANTA.SCONN288_ADR50017P130CC(CHIPS)':
 'DQ28_B': CDS_PINID='DQ28_B';
NODE_NAME     J2 140
 '@S9S_MB_2U_LIB.S9S_MB_2U(SCH_1):PAGE83_I177@PURE_QUANTA.SCONN288_ADR50017P087CC(CHIPS)':
 'DQ28_B': CDS_PINID='DQ28_B';
NET_NAME
'M_A_CPU0_SB_DQ<29>'
 '@S9S_MB_2U_LIB.S9S_MB_2U(SCH_1):M_A_CPU0_SB_DQ'<29>:
 C_SIGNAL='@s9s_mb_2u_lib.s9s_mb_2u(sch_1):m_a_cpu0_sb_dq(29)';
NODE_NAME     U2 C7
 '@S9S_MB_2U_LIB.S9S_MB_2U(SCH_1):PAGE20_I1@PURE_QUANTA.SOCKET4677_AZIF0045P001C01CS(CHIPS)':
 'DDR0_SB_DQ29': CDS_PINID='DDR0_SB_DQ29';
NODE_NAME     J1 142
 '@S9S_MB_2U_LIB.S9S_MB_2U(SCH_1):PAGE82_I198@PURE_QUANTA.SCONN288_ADR50017P130CC(CHIPS)':
 'DQ29_B': CDS_PINID='DQ29_B';
NODE_NAME     J2 142
 '@S9S_MB_2U_LIB.S9S_MB_2U(SCH_1):PAGE83_I177@PURE_QUANTA.SCONN288_ADR50017P087CC(CHIPS)':
 'DQ29_B': CDS_PINID='DQ29_B';
NET_NAME
'M_A_CPU0_SB_DQ<2>'
 '@S9S_MB_2U_LIB.S9S_MB_2U(SCH_1):M_A_CPU0_SB_DQ'<2>:
 C_SIGNAL='@s9s_mb_2u_lib.s9s_mb_2u(sch_1):m_a_cpu0_sb_dq(2)';
NODE_NAME     U2 M32
 '@S9S_MB_2U_LIB.S9S_MB_2U(SCH_1):PAGE20_I1@PURE_QUANTA.SOCKET4677_AZIF0045P001C01CS(CHIPS)':
 'DDR0_SB_DQ2': CDS_PINID='DDR0_SB_DQ2';
NODE_NAME     J1 245
 '@S9S_MB_2U_LIB.S9S_MB_2U(SCH_1):PAGE82_I198@PURE_QUANTA.SCONN288_ADR50017P130CC(CHIPS)':
 'DQ2_B': CDS_PINID='DQ2_B';
NODE_NAME     J2 245
 '@S9S_MB_2U_LIB.S9S_MB_2U(SCH_1):PAGE83_I177@PURE_QUANTA.SCONN288_ADR50017P087CC(CHIPS)':
 'DQ2_B': CDS_PINID='DQ2_B';
NET_NAME
'M_A_CPU0_SB_DQ<30>'
 '@S9S_MB_2U_LIB.S9S_MB_2U(SCH_1):M_A_CPU0_SB_DQ'<30>:
 C_SIGNAL='@s9s_mb_2u_lib.s9s_mb_2u(sch_1):m_a_cpu0_sb_dq(30)';
NODE_NAME     U2 F8
 '@S9S_MB_2U_LIB.S9S_MB_2U(SCH_1):PAGE20_I1@PURE_QUANTA.SOCKET4677_AZIF0045P001C01CS(CHIPS)':
 'DDR0_SB_DQ30': CDS_PINID='DDR0_SB_DQ30';
NODE_NAME     J1 285
 '@S9S_MB_2U_LIB.S9S_MB_2U(SCH_1):PAGE82_I198@PURE_QUANTA.SCONN288_ADR50017P130CC(CHIPS)':
 'DQ30_B': CDS_PINID='DQ30_B';
NODE_NAME     J2 285
 '@S9S_MB_2U_LIB.S9S_MB_2U(SCH_1):PAGE83_I177@PURE_QUANTA.SCONN288_ADR50017P087CC(CHIPS)':
 'DQ30_B': CDS_PINID='DQ30_B';
NET_NAME
'M_A_CPU0_SB_DQ<31>'
 '@S9S_MB_2U_LIB.S9S_MB_2U(SCH_1):M_A_CPU0_SB_DQ'<31>:
 C_SIGNAL='@s9s_mb_2u_lib.s9s_mb_2u(sch_1):m_a_cpu0_sb_dq(31)';
NODE_NAME     U2 E7
 '@S9S_MB_2U_LIB.S9S_MB_2U(SCH_1):PAGE20_I1@PURE_QUANTA.SOCKET4677_AZIF0045P001C01CS(CHIPS)':
 'DDR0_SB_DQ31': CDS_PINID='DDR0_SB_DQ31';
NODE_NAME     J1 287
 '@S9S_MB_2U_LIB.S9S_MB_2U(SCH_1):PAGE82_I198@PURE_QUANTA.SCONN288_ADR50017P130CC(CHIPS)':
 'DQ31_B': CDS_PINID='DQ31_B';
NODE_NAME     J2 287
 '@S9S_MB_2U_LIB.S9S_MB_2U(SCH_1):PAGE83_I177@PURE_QUANTA.SCONN288_ADR50017P087CC(CHIPS)':
 'DQ31_B': CDS_PINID='DQ31_B';
NET_NAME
'M_A_CPU0_SB_DQ<3>'
 '@S9S_MB_2U_LIB.S9S_MB_2U(SCH_1):M_A_CPU0_SB_DQ'<3>:
 C_SIGNAL='@s9s_mb_2u_lib.s9s_mb_2u(sch_1):m_a_cpu0_sb_dq(3)';
NODE_NAME     U2 N31
 '@S9S_MB_2U_LIB.S9S_MB_2U(SCH_1):PAGE20_I1@PURE_QUANTA.SOCKET4677_AZIF0045P001C01CS(CHIPS)':
 'DDR0_SB_DQ3': CDS_PINID='DDR0_SB_DQ3';
NODE_NAME     J1 247
 '@S9S_MB_2U_LIB.S9S_MB_2U(SCH_1):PAGE82_I198@PURE_QUANTA.SCONN288_ADR50017P130CC(CHIPS)':
 'DQ3_B': CDS_PINID='DQ3_B';
NODE_NAME     J2 247
 '@S9S_MB_2U_LIB.S9S_MB_2U(SCH_1):PAGE83_I177@PURE_QUANTA.SCONN288_ADR50017P087CC(CHIPS)':
 'DQ3_B': CDS_PINID='DQ3_B';
NET_NAME
'M_A_CPU0_SB_DQ<4>'
 '@S9S_MB_2U_LIB.S9S_MB_2U(SCH_1):M_A_CPU0_SB_DQ'<4>:
 C_SIGNAL='@s9s_mb_2u_lib.s9s_mb_2u(sch_1):m_a_cpu0_sb_dq(4)';
NODE_NAME     U2 J29
 '@S9S_MB_2U_LIB.S9S_MB_2U(SCH_1):PAGE20_I1@PURE_QUANTA.SOCKET4677_AZIF0045P001C01CS(CHIPS)':
 'DDR0_SB_DQ4': CDS_PINID='DDR0_SB_DQ4';
NODE_NAME     J1 107
 '@S9S_MB_2U_LIB.S9S_MB_2U(SCH_1):PAGE82_I198@PURE_QUANTA.SCONN288_ADR50017P130CC(CHIPS)':
 'DQ4_B': CDS_PINID='DQ4_B';
NODE_NAME     J2 107
 '@S9S_MB_2U_LIB.S9S_MB_2U(SCH_1):PAGE83_I177@PURE_QUANTA.SCONN288_ADR50017P087CC(CHIPS)':
 'DQ4_B': CDS_PINID='DQ4_B';
NET_NAME
'M_A_CPU0_SB_DQ<5>'
 '@S9S_MB_2U_LIB.S9S_MB_2U(SCH_1):M_A_CPU0_SB_DQ'<5>:
 C_SIGNAL='@s9s_mb_2u_lib.s9s_mb_2u(sch_1):m_a_cpu0_sb_dq(5)';
NODE_NAME     U2 K28
 '@S9S_MB_2U_LIB.S9S_MB_2U(SCH_1):PAGE20_I1@PURE_QUANTA.SOCKET4677_AZIF0045P001C01CS(CHIPS)':
 'DDR0_SB_DQ5': CDS_PINID='DDR0_SB_DQ5';
NODE_NAME     J1 109
 '@S9S_MB_2U_LIB.S9S_MB_2U(SCH_1):PAGE82_I198@PURE_QUANTA.SCONN288_ADR50017P130CC(CHIPS)':
 'DQ5_B': CDS_PINID='DQ5_B';
NODE_NAME     J2 109
 '@S9S_MB_2U_LIB.S9S_MB_2U(SCH_1):PAGE83_I177@PURE_QUANTA.SCONN288_ADR50017P087CC(CHIPS)':
 'DQ5_B': CDS_PINID='DQ5_B';
NET_NAME
'M_A_CPU0_SB_DQ<6>'
 '@S9S_MB_2U_LIB.S9S_MB_2U(SCH_1):M_A_CPU0_SB_DQ'<6>:
 C_SIGNAL='@s9s_mb_2u_lib.s9s_mb_2u(sch_1):m_a_cpu0_sb_dq(6)';
NODE_NAME     U2 N29
 '@S9S_MB_2U_LIB.S9S_MB_2U(SCH_1):PAGE20_I1@PURE_QUANTA.SOCKET4677_AZIF0045P001C01CS(CHIPS)':
 'DDR0_SB_DQ6': CDS_PINID='DDR0_SB_DQ6';
NODE_NAME     J1 252
 '@S9S_MB_2U_LIB.S9S_MB_2U(SCH_1):PAGE82_I198@PURE_QUANTA.SCONN288_ADR50017P130CC(CHIPS)':
 'DQ6_B': CDS_PINID='DQ6_B';
NODE_NAME     J2 252
 '@S9S_MB_2U_LIB.S9S_MB_2U(SCH_1):PAGE83_I177@PURE_QUANTA.SCONN288_ADR50017P087CC(CHIPS)':
 'DQ6_B': CDS_PINID='DQ6_B';
NET_NAME
'M_A_CPU0_SB_DQ<7>'
 '@S9S_MB_2U_LIB.S9S_MB_2U(SCH_1):M_A_CPU0_SB_DQ'<7>:
 C_SIGNAL='@s9s_mb_2u_lib.s9s_mb_2u(sch_1):m_a_cpu0_sb_dq(7)';
NODE_NAME     U2 M28
 '@S9S_MB_2U_LIB.S9S_MB_2U(SCH_1):PAGE20_I1@PURE_QUANTA.SOCKET4677_AZIF0045P001C01CS(CHIPS)':
 'DDR0_SB_DQ7': CDS_PINID='DDR0_SB_DQ7';
NODE_NAME     J1 254
 '@S9S_MB_2U_LIB.S9S_MB_2U(SCH_1):PAGE82_I198@PURE_QUANTA.SCONN288_ADR50017P130CC(CHIPS)':
 'DQ7_B': CDS_PINID='DQ7_B';
NODE_NAME     J2 254
 '@S9S_MB_2U_LIB.S9S_MB_2U(SCH_1):PAGE83_I177@PURE_QUANTA.SCONN288_ADR50017P087CC(CHIPS)':
 'DQ7_B': CDS_PINID='DQ7_B';
NET_NAME
'M_A_CPU0_SB_DQ<8>'
 '@S9S_MB_2U_LIB.S9S_MB_2U(SCH_1):M_A_CPU0_SB_DQ'<8>:
 C_SIGNAL='@s9s_mb_2u_lib.s9s_mb_2u(sch_1):m_a_cpu0_sb_dq(8)';
NODE_NAME     U2 C29
 '@S9S_MB_2U_LIB.S9S_MB_2U(SCH_1):PAGE20_I1@PURE_QUANTA.SOCKET4677_AZIF0045P001C01CS(CHIPS)':
 'DDR0_SB_DQ8': CDS_PINID='DDR0_SB_DQ8';
NODE_NAME     J1 111
 '@S9S_MB_2U_LIB.S9S_MB_2U(SCH_1):PAGE82_I198@PURE_QUANTA.SCONN288_ADR50017P130CC(CHIPS)':
 'DQ8_B': CDS_PINID='DQ8_B';
NODE_NAME     J2 111
 '@S9S_MB_2U_LIB.S9S_MB_2U(SCH_1):PAGE83_I177@PURE_QUANTA.SCONN288_ADR50017P087CC(CHIPS)':
 'DQ8_B': CDS_PINID='DQ8_B';
NET_NAME
'M_A_CPU0_SB_DQ<9>'
 '@S9S_MB_2U_LIB.S9S_MB_2U(SCH_1):M_A_CPU0_SB_DQ'<9>:
 C_SIGNAL='@s9s_mb_2u_lib.s9s_mb_2u(sch_1):m_a_cpu0_sb_dq(9)';
NODE_NAME     U2 B28
 '@S9S_MB_2U_LIB.S9S_MB_2U(SCH_1):PAGE20_I1@PURE_QUANTA.SOCKET4677_AZIF0045P001C01CS(CHIPS)':
 'DDR0_SB_DQ9': CDS_PINID='DDR0_SB_DQ9';
NODE_NAME     J1 113
 '@S9S_MB_2U_LIB.S9S_MB_2U(SCH_1):PAGE82_I198@PURE_QUANTA.SCONN288_ADR50017P130CC(CHIPS)':
 'DQ9_B': CDS_PINID='DQ9_B';
NODE_NAME     J2 113
 '@S9S_MB_2U_LIB.S9S_MB_2U(SCH_1):PAGE83_I177@PURE_QUANTA.SCONN288_ADR50017P087CC(CHIPS)':
 'DQ9_B': CDS_PINID='DQ9_B';
NET_NAME
'M_A_CPU0_SB_DQS_DN<0>'
 '@S9S_MB_2U_LIB.S9S_MB_2U(SCH_1):M_A_CPU0_SB_DQS_DN'<0>:
 C_SIGNAL='@s9s_mb_2u_lib.s9s_mb_2u(sch_1):m_a_cpu0_sb_dqs_dn(0)';
NODE_NAME     U2 H30
 '@S9S_MB_2U_LIB.S9S_MB_2U(SCH_1):PAGE20_I1@PURE_QUANTA.SOCKET4677_AZIF0045P001C01CS(CHIPS)':
 'DDR0_SB_DQS_DN0': CDS_PINID='DDR0_SB_DQS_DN0';
NODE_NAME     J1 105
 '@S9S_MB_2U_LIB.S9S_MB_2U(SCH_1):PAGE82_I202@PURE_QUANTA.SCONN288_ADR50017P130CC(CHIPS)':
 'DQS0_B_C': CDS_PINID='DQS0_B_C';
NODE_NAME     J2 105
 '@S9S_MB_2U_LIB.S9S_MB_2U(SCH_1):PAGE83_I181@PURE_QUANTA.SCONN288_ADR50017P087CC(CHIPS)':
 'DQS0_B_C': CDS_PINID='DQS0_B_C';
NET_NAME
'M_A_CPU0_SB_DQS_DN<1>'
 '@S9S_MB_2U_LIB.S9S_MB_2U(SCH_1):M_A_CPU0_SB_DQS_DN'<1>:
 C_SIGNAL='@s9s_mb_2u_lib.s9s_mb_2u(sch_1):m_a_cpu0_sb_dqs_dn(1)';
NODE_NAME     U2 A27
 '@S9S_MB_2U_LIB.S9S_MB_2U(SCH_1):PAGE20_I1@PURE_QUANTA.SOCKET4677_AZIF0045P001C01CS(CHIPS)':
 'DDR0_SB_DQS_DN1': CDS_PINID='DDR0_SB_DQS_DN1';
NODE_NAME     J1 116
 '@S9S_MB_2U_LIB.S9S_MB_2U(SCH_1):PAGE82_I202@PURE_QUANTA.SCONN288_ADR50017P130CC(CHIPS)':
 'DQS1_B_C': CDS_PINID='DQS1_B_C';
NODE_NAME     J2 116
 '@S9S_MB_2U_LIB.S9S_MB_2U(SCH_1):PAGE83_I181@PURE_QUANTA.SCONN288_ADR50017P087CC(CHIPS)':
 'DQS1_B_C': CDS_PINID='DQS1_B_C';
NET_NAME
'M_A_CPU0_SB_DQS_DN<2>'
 '@S9S_MB_2U_LIB.S9S_MB_2U(SCH_1):M_A_CPU0_SB_DQS_DN'<2>:
 C_SIGNAL='@s9s_mb_2u_lib.s9s_mb_2u(sch_1):m_a_cpu0_sb_dqs_dn(2)';
NODE_NAME     U2 A21
 '@S9S_MB_2U_LIB.S9S_MB_2U(SCH_1):PAGE20_I1@PURE_QUANTA.SOCKET4677_AZIF0045P001C01CS(CHIPS)':
 'DDR0_SB_DQS_DN2': CDS_PINID='DDR0_SB_DQS_DN2';
NODE_NAME     J1 127
 '@S9S_MB_2U_LIB.S9S_MB_2U(SCH_1):PAGE82_I202@PURE_QUANTA.SCONN288_ADR50017P130CC(CHIPS)':
 'DQS2_B_C': CDS_PINID='DQS2_B_C';
NODE_NAME     J2 127
 '@S9S_MB_2U_LIB.S9S_MB_2U(SCH_1):PAGE83_I181@PURE_QUANTA.SCONN288_ADR50017P087CC(CHIPS)':
 'DQS2_B_C': CDS_PINID='DQS2_B_C';
NET_NAME
'M_A_CPU0_SB_DQS_DN<3>'
 '@S9S_MB_2U_LIB.S9S_MB_2U(SCH_1):M_A_CPU0_SB_DQS_DN'<3>:
 C_SIGNAL='@s9s_mb_2u_lib.s9s_mb_2u(sch_1):m_a_cpu0_sb_dqs_dn(3)';
NODE_NAME     U2 A9
 '@S9S_MB_2U_LIB.S9S_MB_2U(SCH_1):PAGE20_I1@PURE_QUANTA.SOCKET4677_AZIF0045P001C01CS(CHIPS)':
 'DDR0_SB_DQS_DN3': CDS_PINID='DDR0_SB_DQS_DN3';
NODE_NAME     J1 138
 '@S9S_MB_2U_LIB.S9S_MB_2U(SCH_1):PAGE82_I202@PURE_QUANTA.SCONN288_ADR50017P130CC(CHIPS)':
 'DQS3_B_C': CDS_PINID='DQS3_B_C';
NODE_NAME     J2 138
 '@S9S_MB_2U_LIB.S9S_MB_2U(SCH_1):PAGE83_I181@PURE_QUANTA.SCONN288_ADR50017P087CC(CHIPS)':
 'DQS3_B_C': CDS_PINID='DQS3_B_C';
NET_NAME
'M_A_CPU0_SB_DQS_DN<4>'
 '@S9S_MB_2U_LIB.S9S_MB_2U(SCH_1):M_A_CPU0_SB_DQS_DN'<4>:
 C_SIGNAL='@s9s_mb_2u_lib.s9s_mb_2u(sch_1):m_a_cpu0_sb_dqs_dn(4)';
NODE_NAME     U2 G33
 '@S9S_MB_2U_LIB.S9S_MB_2U(SCH_1):PAGE20_I1@PURE_QUANTA.SOCKET4677_AZIF0045P001C01CS(CHIPS)':
 'DDR0_SB_DQS_DN4': CDS_PINID='DDR0_SB_DQS_DN4';
NODE_NAME     J1 238
 '@S9S_MB_2U_LIB.S9S_MB_2U(SCH_1):PAGE82_I202@PURE_QUANTA.SCONN288_ADR50017P130CC(CHIPS)':
 'DQS4_B_C': CDS_PINID='DQS4_B_C';
NODE_NAME     J2 238
 '@S9S_MB_2U_LIB.S9S_MB_2U(SCH_1):PAGE83_I181@PURE_QUANTA.SCONN288_ADR50017P087CC(CHIPS)':
 'DQS4_B_C': CDS_PINID='DQS4_B_C';
NET_NAME
'M_A_CPU0_SB_DQS_DN<5>'
 '@S9S_MB_2U_LIB.S9S_MB_2U(SCH_1):M_A_CPU0_SB_DQS_DN'<5>:
 C_SIGNAL='@s9s_mb_2u_lib.s9s_mb_2u(sch_1):m_a_cpu0_sb_dqs_dn(5)';
NODE_NAME     U2 M30
 '@S9S_MB_2U_LIB.S9S_MB_2U(SCH_1):PAGE20_I1@PURE_QUANTA.SOCKET4677_AZIF0045P001C01CS(CHIPS)':
 'DDR0_SB_DQS_DN5': CDS_PINID='DDR0_SB_DQS_DN5';
NODE_NAME     J1 249
 '@S9S_MB_2U_LIB.S9S_MB_2U(SCH_1):PAGE82_I202@PURE_QUANTA.SCONN288_ADR50017P130CC(CHIPS)':
 'DQS5_B_C||TDQS5_B_C': CDS_PINID='\dqs5_b_c||tdqs5_b_c\';
NODE_NAME     J2 249
 '@S9S_MB_2U_LIB.S9S_MB_2U(SCH_1):PAGE83_I181@PURE_QUANTA.SCONN288_ADR50017P087CC(CHIPS)':
 'DQS5_B_C||TDQS5_B_C': CDS_PINID='\dqs5_b_c||tdqs5_b_c\';
NET_NAME
'M_A_CPU0_SB_DQS_DN<6>'
 '@S9S_MB_2U_LIB.S9S_MB_2U(SCH_1):M_A_CPU0_SB_DQS_DN'<6>:
 C_SIGNAL='@s9s_mb_2u_lib.s9s_mb_2u(sch_1):m_a_cpu0_sb_dqs_dn(6)';
NODE_NAME     U2 G27
 '@S9S_MB_2U_LIB.S9S_MB_2U(SCH_1):PAGE20_I1@PURE_QUANTA.SOCKET4677_AZIF0045P001C01CS(CHIPS)':
 'DDR0_SB_DQS_DN6': CDS_PINID='DDR0_SB_DQS_DN6';
NODE_NAME     J1 260
 '@S9S_MB_2U_LIB.S9S_MB_2U(SCH_1):PAGE82_I202@PURE_QUANTA.SCONN288_ADR50017P130CC(CHIPS)':
 'DQS6_B_C||TDQS6_B_C': CDS_PINID='\dqs6_b_c||tdqs6_b_c\';
NODE_NAME     J2 260
 '@S9S_MB_2U_LIB.S9S_MB_2U(SCH_1):PAGE83_I181@PURE_QUANTA.SCONN288_ADR50017P087CC(CHIPS)':
 'DQS6_B_C||TDQS6_B_C': CDS_PINID='\dqs6_b_c||tdqs6_b_c\';
NET_NAME
'M_A_CPU0_SB_DQS_DN<7>'
 '@S9S_MB_2U_LIB.S9S_MB_2U(SCH_1):M_A_CPU0_SB_DQS_DN'<7>:
 C_SIGNAL='@s9s_mb_2u_lib.s9s_mb_2u(sch_1):m_a_cpu0_sb_dqs_dn(7)';
NODE_NAME     U2 G21
 '@S9S_MB_2U_LIB.S9S_MB_2U(SCH_1):PAGE20_I1@PURE_QUANTA.SOCKET4677_AZIF0045P001C01CS(CHIPS)':
 'DDR0_SB_DQS_DN7': CDS_PINID='DDR0_SB_DQS_DN7';
NODE_NAME     J1 271
 '@S9S_MB_2U_LIB.S9S_MB_2U(SCH_1):PAGE82_I202@PURE_QUANTA.SCONN288_ADR50017P130CC(CHIPS)':
 'DQS7_B_C||TDQS7_B_C': CDS_PINID='\dqs7_b_c||tdqs7_b_c\';
NODE_NAME     J2 271
 '@S9S_MB_2U_LIB.S9S_MB_2U(SCH_1):PAGE83_I181@PURE_QUANTA.SCONN288_ADR50017P087CC(CHIPS)':
 'DQS7_B_C||TDQS7_B_C': CDS_PINID='\dqs7_b_c||tdqs7_b_c\';
NET_NAME
'M_A_CPU0_SB_DQS_DN<8>'
 '@S9S_MB_2U_LIB.S9S_MB_2U(SCH_1):M_A_CPU0_SB_DQS_DN'<8>:
 C_SIGNAL='@s9s_mb_2u_lib.s9s_mb_2u(sch_1):m_a_cpu0_sb_dqs_dn(8)';
NODE_NAME     U2 G9
 '@S9S_MB_2U_LIB.S9S_MB_2U(SCH_1):PAGE20_I1@PURE_QUANTA.SOCKET4677_AZIF0045P001C01CS(CHIPS)':
 'DDR0_SB_DQS_DN8': CDS_PINID='DDR0_SB_DQS_DN8';
NODE_NAME     J1 282
 '@S9S_MB_2U_LIB.S9S_MB_2U(SCH_1):PAGE82_I202@PURE_QUANTA.SCONN288_ADR50017P130CC(CHIPS)':
 'DQS8_B_C||TDQS8_B_C': CDS_PINID='\dqs8_b_c||tdqs8_b_c\';
NODE_NAME     J2 282
 '@S9S_MB_2U_LIB.S9S_MB_2U(SCH_1):PAGE83_I181@PURE_QUANTA.SCONN288_ADR50017P087CC(CHIPS)':
 'DQS8_B_C||TDQS8_B_C': CDS_PINID='\dqs8_b_c||tdqs8_b_c\';
NET_NAME
'M_A_CPU0_SB_DQS_DN<9>'
 '@S9S_MB_2U_LIB.S9S_MB_2U(SCH_1):M_A_CPU0_SB_DQS_DN'<9>:
 C_SIGNAL='@s9s_mb_2u_lib.s9s_mb_2u(sch_1):m_a_cpu0_sb_dqs_dn(9)';
NODE_NAME     U2 A33
 '@S9S_MB_2U_LIB.S9S_MB_2U(SCH_1):PAGE20_I1@PURE_QUANTA.SOCKET4677_AZIF0045P001C01CS(CHIPS)':
 'DDR0_SB_DQS_DN9': CDS_PINID='DDR0_SB_DQS_DN9';
NODE_NAME     J1 94
 '@S9S_MB_2U_LIB.S9S_MB_2U(SCH_1):PAGE82_I202@PURE_QUANTA.SCONN288_ADR50017P130CC(CHIPS)':
 'DQS9_B_C||TDQS9_B_C': CDS_PINID='\dqs9_b_c||tdqs9_b_c\';
NODE_NAME     J2 94
 '@S9S_MB_2U_LIB.S9S_MB_2U(SCH_1):PAGE83_I181@PURE_QUANTA.SCONN288_ADR50017P087CC(CHIPS)':
 'DQS9_B_C||TDQS9_B_C': CDS_PINID='\dqs9_b_c||tdqs9_b_c\';
NET_NAME
'M_A_CPU0_SB_DQS_DP<0>'
 '@S9S_MB_2U_LIB.S9S_MB_2U(SCH_1):M_A_CPU0_SB_DQS_DP'<0>:
 C_SIGNAL='@s9s_mb_2u_lib.s9s_mb_2u(sch_1):m_a_cpu0_sb_dqs_dp(0)';
NODE_NAME     U2 K30
 '@S9S_MB_2U_LIB.S9S_MB_2U(SCH_1):PAGE20_I1@PURE_QUANTA.SOCKET4677_AZIF0045P001C01CS(CHIPS)':
 'DDR0_SB_DQS_DP0': CDS_PINID='DDR0_SB_DQS_DP0';
NODE_NAME     J1 104
 '@S9S_MB_2U_LIB.S9S_MB_2U(SCH_1):PAGE82_I202@PURE_QUANTA.SCONN288_ADR50017P130CC(CHIPS)':
 'DQS0_B_T': CDS_PINID='DQS0_B_T';
NODE_NAME     J2 104
 '@S9S_MB_2U_LIB.S9S_MB_2U(SCH_1):PAGE83_I181@PURE_QUANTA.SCONN288_ADR50017P087CC(CHIPS)':
 'DQS0_B_T': CDS_PINID='DQS0_B_T';
NET_NAME
'M_A_CPU0_SB_DQS_DP<1>'
 '@S9S_MB_2U_LIB.S9S_MB_2U(SCH_1):M_A_CPU0_SB_DQS_DP'<1>:
 C_SIGNAL='@s9s_mb_2u_lib.s9s_mb_2u(sch_1):m_a_cpu0_sb_dqs_dp(1)';
NODE_NAME     U2 C27
 '@S9S_MB_2U_LIB.S9S_MB_2U(SCH_1):PAGE20_I1@PURE_QUANTA.SOCKET4677_AZIF0045P001C01CS(CHIPS)':
 'DDR0_SB_DQS_DP1': CDS_PINID='DDR0_SB_DQS_DP1';
NODE_NAME     J1 115
 '@S9S_MB_2U_LIB.S9S_MB_2U(SCH_1):PAGE82_I202@PURE_QUANTA.SCONN288_ADR50017P130CC(CHIPS)':
 'DQS1_B_T': CDS_PINID='DQS1_B_T';
NODE_NAME     J2 115
 '@S9S_MB_2U_LIB.S9S_MB_2U(SCH_1):PAGE83_I181@PURE_QUANTA.SCONN288_ADR50017P087CC(CHIPS)':
 'DQS1_B_T': CDS_PINID='DQS1_B_T';
NET_NAME
'M_A_CPU0_SB_DQS_DP<2>'
 '@S9S_MB_2U_LIB.S9S_MB_2U(SCH_1):M_A_CPU0_SB_DQS_DP'<2>:
 C_SIGNAL='@s9s_mb_2u_lib.s9s_mb_2u(sch_1):m_a_cpu0_sb_dqs_dp(2)';
NODE_NAME     U2 C21
 '@S9S_MB_2U_LIB.S9S_MB_2U(SCH_1):PAGE20_I1@PURE_QUANTA.SOCKET4677_AZIF0045P001C01CS(CHIPS)':
 'DDR0_SB_DQS_DP2': CDS_PINID='DDR0_SB_DQS_DP2';
NODE_NAME     J1 126
 '@S9S_MB_2U_LIB.S9S_MB_2U(SCH_1):PAGE82_I202@PURE_QUANTA.SCONN288_ADR50017P130CC(CHIPS)':
 'DQS2_B_T': CDS_PINID='DQS2_B_T';
NODE_NAME     J2 126
 '@S9S_MB_2U_LIB.S9S_MB_2U(SCH_1):PAGE83_I181@PURE_QUANTA.SCONN288_ADR50017P087CC(CHIPS)':
 'DQS2_B_T': CDS_PINID='DQS2_B_T';
NET_NAME
'M_A_CPU0_SB_DQS_DP<3>'
 '@S9S_MB_2U_LIB.S9S_MB_2U(SCH_1):M_A_CPU0_SB_DQS_DP'<3>:
 C_SIGNAL='@s9s_mb_2u_lib.s9s_mb_2u(sch_1):m_a_cpu0_sb_dqs_dp(3)';
NODE_NAME     U2 C9
 '@S9S_MB_2U_LIB.S9S_MB_2U(SCH_1):PAGE20_I1@PURE_QUANTA.SOCKET4677_AZIF0045P001C01CS(CHIPS)':
 'DDR0_SB_DQS_DP3': CDS_PINID='DDR0_SB_DQS_DP3';
NODE_NAME     J1 137
 '@S9S_MB_2U_LIB.S9S_MB_2U(SCH_1):PAGE82_I202@PURE_QUANTA.SCONN288_ADR50017P130CC(CHIPS)':
 'DQS3_B_T': CDS_PINID='DQS3_B_T';
NODE_NAME     J2 137
 '@S9S_MB_2U_LIB.S9S_MB_2U(SCH_1):PAGE83_I181@PURE_QUANTA.SCONN288_ADR50017P087CC(CHIPS)':
 'DQS3_B_T': CDS_PINID='DQS3_B_T';
NET_NAME
'M_A_CPU0_SB_DQS_DP<4>'
 '@S9S_MB_2U_LIB.S9S_MB_2U(SCH_1):M_A_CPU0_SB_DQS_DP'<4>:
 C_SIGNAL='@s9s_mb_2u_lib.s9s_mb_2u(sch_1):m_a_cpu0_sb_dqs_dp(4)';
NODE_NAME     U2 E33
 '@S9S_MB_2U_LIB.S9S_MB_2U(SCH_1):PAGE20_I1@PURE_QUANTA.SOCKET4677_AZIF0045P001C01CS(CHIPS)':
 'DDR0_SB_DQS_DP4': CDS_PINID='DDR0_SB_DQS_DP4';
NODE_NAME     J1 239
 '@S9S_MB_2U_LIB.S9S_MB_2U(SCH_1):PAGE82_I202@PURE_QUANTA.SCONN288_ADR50017P130CC(CHIPS)':
 'DQS4_B_T': CDS_PINID='DQS4_B_T';
NODE_NAME     J2 239
 '@S9S_MB_2U_LIB.S9S_MB_2U(SCH_1):PAGE83_I181@PURE_QUANTA.SCONN288_ADR50017P087CC(CHIPS)':
 'DQS4_B_T': CDS_PINID='DQS4_B_T';
NET_NAME
'M_A_CPU0_SB_DQS_DP<5>'
 '@S9S_MB_2U_LIB.S9S_MB_2U(SCH_1):M_A_CPU0_SB_DQS_DP'<5>:
 C_SIGNAL='@s9s_mb_2u_lib.s9s_mb_2u(sch_1):m_a_cpu0_sb_dqs_dp(5)';
NODE_NAME     U2 P30
 '@S9S_MB_2U_LIB.S9S_MB_2U(SCH_1):PAGE20_I1@PURE_QUANTA.SOCKET4677_AZIF0045P001C01CS(CHIPS)':
 'DDR0_SB_DQS_DP5': CDS_PINID='DDR0_SB_DQS_DP5';
NODE_NAME     J1 250
 '@S9S_MB_2U_LIB.S9S_MB_2U(SCH_1):PAGE82_I202@PURE_QUANTA.SCONN288_ADR50017P130CC(CHIPS)':
 'DQS5_B_T||TDQS5_B_T': CDS_PINID='\dqs5_b_t||tdqs5_b_t\';
NODE_NAME     J2 250
 '@S9S_MB_2U_LIB.S9S_MB_2U(SCH_1):PAGE83_I181@PURE_QUANTA.SCONN288_ADR50017P087CC(CHIPS)':
 'DQS5_B_T||TDQS5_B_T': CDS_PINID='\dqs5_b_t||tdqs5_b_t\';
NET_NAME
'M_A_CPU0_SB_DQS_DP<6>'
 '@S9S_MB_2U_LIB.S9S_MB_2U(SCH_1):M_A_CPU0_SB_DQS_DP'<6>:
 C_SIGNAL='@s9s_mb_2u_lib.s9s_mb_2u(sch_1):m_a_cpu0_sb_dqs_dp(6)';
NODE_NAME     U2 E27
 '@S9S_MB_2U_LIB.S9S_MB_2U(SCH_1):PAGE20_I1@PURE_QUANTA.SOCKET4677_AZIF0045P001C01CS(CHIPS)':
 'DDR0_SB_DQS_DP6': CDS_PINID='DDR0_SB_DQS_DP6';
NODE_NAME     J1 261
 '@S9S_MB_2U_LIB.S9S_MB_2U(SCH_1):PAGE82_I202@PURE_QUANTA.SCONN288_ADR50017P130CC(CHIPS)':
 'DQS6_B_T||TDQS6_B_T': CDS_PINID='\dqs6_b_t||tdqs6_b_t\';
NODE_NAME     J2 261
 '@S9S_MB_2U_LIB.S9S_MB_2U(SCH_1):PAGE83_I181@PURE_QUANTA.SCONN288_ADR50017P087CC(CHIPS)':
 'DQS6_B_T||TDQS6_B_T': CDS_PINID='\dqs6_b_t||tdqs6_b_t\';
NET_NAME
'M_A_CPU0_SB_DQS_DP<7>'
 '@S9S_MB_2U_LIB.S9S_MB_2U(SCH_1):M_A_CPU0_SB_DQS_DP'<7>:
 C_SIGNAL='@s9s_mb_2u_lib.s9s_mb_2u(sch_1):m_a_cpu0_sb_dqs_dp(7)';
NODE_NAME     U2 E21
 '@S9S_MB_2U_LIB.S9S_MB_2U(SCH_1):PAGE20_I1@PURE_QUANTA.SOCKET4677_AZIF0045P001C01CS(CHIPS)':
 'DDR0_SB_DQS_DP7': CDS_PINID='DDR0_SB_DQS_DP7';
NODE_NAME     J1 272
 '@S9S_MB_2U_LIB.S9S_MB_2U(SCH_1):PAGE82_I202@PURE_QUANTA.SCONN288_ADR50017P130CC(CHIPS)':
 'DQS7_B_T||TDQS7_B_T': CDS_PINID='\dqs7_b_t||tdqs7_b_t\';
NODE_NAME     J2 272
 '@S9S_MB_2U_LIB.S9S_MB_2U(SCH_1):PAGE83_I181@PURE_QUANTA.SCONN288_ADR50017P087CC(CHIPS)':
 'DQS7_B_T||TDQS7_B_T': CDS_PINID='\dqs7_b_t||tdqs7_b_t\';
NET_NAME
'M_A_CPU0_SB_DQS_DP<8>'
 '@S9S_MB_2U_LIB.S9S_MB_2U(SCH_1):M_A_CPU0_SB_DQS_DP'<8>:
 C_SIGNAL='@s9s_mb_2u_lib.s9s_mb_2u(sch_1):m_a_cpu0_sb_dqs_dp(8)';
NODE_NAME     U2 E9
 '@S9S_MB_2U_LIB.S9S_MB_2U(SCH_1):PAGE20_I1@PURE_QUANTA.SOCKET4677_AZIF0045P001C01CS(CHIPS)':
 'DDR0_SB_DQS_DP8': CDS_PINID='DDR0_SB_DQS_DP8';
NODE_NAME     J1 283
 '@S9S_MB_2U_LIB.S9S_MB_2U(SCH_1):PAGE82_I202@PURE_QUANTA.SCONN288_ADR50017P130CC(CHIPS)':
 'DQS8_B_T||TDQS8_B_T': CDS_PINID='\dqs8_b_t||tdqs8_b_t\';
NODE_NAME     J2 283
 '@S9S_MB_2U_LIB.S9S_MB_2U(SCH_1):PAGE83_I181@PURE_QUANTA.SCONN288_ADR50017P087CC(CHIPS)':
 'DQS8_B_T||TDQS8_B_T': CDS_PINID='\dqs8_b_t||tdqs8_b_t\';
NET_NAME
'M_A_CPU0_SB_DQS_DP<9>'
 '@S9S_MB_2U_LIB.S9S_MB_2U(SCH_1):M_A_CPU0_SB_DQS_DP'<9>:
 C_SIGNAL='@s9s_mb_2u_lib.s9s_mb_2u(sch_1):m_a_cpu0_sb_dqs_dp(9)';
NODE_NAME     U2 C33
 '@S9S_MB_2U_LIB.S9S_MB_2U(SCH_1):PAGE20_I1@PURE_QUANTA.SOCKET4677_AZIF0045P001C01CS(CHIPS)':
 'DDR0_SB_DQS_DP9': CDS_PINID='DDR0_SB_DQS_DP9';
NODE_NAME     J1 93
 '@S9S_MB_2U_LIB.S9S_MB_2U(SCH_1):PAGE82_I202@PURE_QUANTA.SCONN288_ADR50017P130CC(CHIPS)':
 'DQS9_B_T||TDQS9_B_T||DBI4_B_N': CDS_PINID='\dqs9_b_t||tdqs9_b_t||dbi4_b_n\';
NODE_NAME     J2 93
 '@S9S_MB_2U_LIB.S9S_MB_2U(SCH_1):PAGE83_I181@PURE_QUANTA.SCONN288_ADR50017P087CC(CHIPS)':
 'DQS9_B_T||TDQS9_B_T||DBI4_B_N': CDS_PINID='\dqs9_b_t||tdqs9_b_t||dbi4_b_n\';
NET_NAME
'M_A_CPU0_SB_PAR'
 '@S9S_MB_2U_LIB.S9S_MB_2U(SCH_1):M_A_CPU0_SB_PAR':
 C_SIGNAL='@s9s_mb_2u_lib.s9s_mb_2u(sch_1):m_a_cpu0_sb_par';
NODE_NAME     U2 G39
 '@S9S_MB_2U_LIB.S9S_MB_2U(SCH_1):PAGE20_I1@PURE_QUANTA.SOCKET4677_AZIF0045P001C01CS(CHIPS)':
 'DDR0_SB_PAR': CDS_PINID='DDR0_SB_PAR';
NODE_NAME     J1 227
 '@S9S_MB_2U_LIB.S9S_MB_2U(SCH_1):PAGE82_I198@PURE_QUANTA.SCONN288_ADR50017P130CC(CHIPS)':
 'PAR_B': CDS_PINID='PAR_B';
NODE_NAME     J2 227
 '@S9S_MB_2U_LIB.S9S_MB_2U(SCH_1):PAGE83_I177@PURE_QUANTA.SCONN288_ADR50017P087CC(CHIPS)':
 'PAR_B': CDS_PINID='PAR_B';
NET_NAME
'M_A_CPU0_SB_RSP<0>'
 '@S9S_MB_2U_LIB.S9S_MB_2U(SCH_1):M_A_CPU0_SB_RSP'<0>:
 C_SIGNAL='@s9s_mb_2u_lib.s9s_mb_2u(sch_1):m_a_cpu0_sb_rsp(0)';
NODE_NAME     U2 AV44
 '@S9S_MB_2U_LIB.S9S_MB_2U(SCH_1):PAGE20_I1@PURE_QUANTA.SOCKET4677_AZIF0045P001C01CS(CHIPS)':
 'DDR0_B_RSP0': CDS_PINID='DDR0_B_RSP0';
NODE_NAME     J1 87
 '@S9S_MB_2U_LIB.S9S_MB_2U(SCH_1):PAGE82_I198@PURE_QUANTA.SCONN288_ADR50017P130CC(CHIPS)':
 'LBS||RSP_B_N': CDS_PINID='\lbs||rsp_b_n\';
NET_NAME
'M_A_CPU0_SB_RSP<1>'
 '@S9S_MB_2U_LIB.S9S_MB_2U(SCH_1):M_A_CPU0_SB_RSP'<1>:
 C_SIGNAL='@s9s_mb_2u_lib.s9s_mb_2u(sch_1):m_a_cpu0_sb_rsp(1)';
NODE_NAME     U2 AV42
 '@S9S_MB_2U_LIB.S9S_MB_2U(SCH_1):PAGE20_I1@PURE_QUANTA.SOCKET4677_AZIF0045P001C01CS(CHIPS)':
 'DDR0_B_RSP1': CDS_PINID='DDR0_B_RSP1';
NODE_NAME     J2 87
 '@S9S_MB_2U_LIB.S9S_MB_2U(SCH_1):PAGE83_I177@PURE_QUANTA.SCONN288_ADR50017P087CC(CHIPS)':
 'LBS||RSP_B_N': CDS_PINID='\lbs||rsp_b_n\';
NET_NAME
'M_A_CPU1_ALERT_N'
 '@S9S_MB_2U_LIB.S9S_MB_2U(SCH_1):M_A_CPU1_ALERT_N':
 C_SIGNAL='@s9s_mb_2u_lib.s9s_mb_2u(sch_1):m_a_cpu1_alert_n';
NODE_NAME     U1 AT49
 '@S9S_MB_2U_LIB.S9S_MB_2U(SCH_1):PAGE51_I2@PURE_QUANTA.SOCKET4677_AZIF0045P001C01CS(CHIPS)':
 'DDR0_ALERT_N': CDS_PINID='DDR0_ALERT_N';
NODE_NAME     J17 62
 '@S9S_MB_2U_LIB.S9S_MB_2U(SCH_1):PAGE98_I12@PURE_QUANTA.SCONN288_ADR50017P130CC(CHIPS)':
 'ALERT_N': CDS_PINID='ALERT_N';
NODE_NAME     J18 62
 '@S9S_MB_2U_LIB.S9S_MB_2U(SCH_1):PAGE99_I24@PURE_QUANTA.SCONN288_ADR50017P087CC(CHIPS)':
 'ALERT_N': CDS_PINID='ALERT_N';
NET_NAME
'M_A_CPU1_CLK_DN<0>'
 '@S9S_MB_2U_LIB.S9S_MB_2U(SCH_1):M_A_CPU1_CLK_DN'<0>:
 C_SIGNAL='@s9s_mb_2u_lib.s9s_mb_2u(sch_1):m_a_cpu1_clk_dn(0)';
NODE_NAME     U1 B44
 '@S9S_MB_2U_LIB.S9S_MB_2U(SCH_1):PAGE51_I2@PURE_QUANTA.SOCKET4677_AZIF0045P001C01CS(CHIPS)':
 'DDR0_CLK_DN0': CDS_PINID='DDR0_CLK_DN0';
NODE_NAME     J17 218
 '@S9S_MB_2U_LIB.S9S_MB_2U(SCH_1):PAGE98_I12@PURE_QUANTA.SCONN288_ADR50017P130CC(CHIPS)':
 'CK_C': CDS_PINID='CK_C';
NET_NAME
'M_A_CPU1_CLK_DN<1>'
 '@S9S_MB_2U_LIB.S9S_MB_2U(SCH_1):M_A_CPU1_CLK_DN'<1>:
 C_SIGNAL='@s9s_mb_2u_lib.s9s_mb_2u(sch_1):m_a_cpu1_clk_dn(1)';
NODE_NAME     U1 G45
 '@S9S_MB_2U_LIB.S9S_MB_2U(SCH_1):PAGE51_I2@PURE_QUANTA.SOCKET4677_AZIF0045P001C01CS(CHIPS)':
 'DDR0_CLK_DN1': CDS_PINID='DDR0_CLK_DN1';
NODE_NAME     J18 218
 '@S9S_MB_2U_LIB.S9S_MB_2U(SCH_1):PAGE99_I24@PURE_QUANTA.SCONN288_ADR50017P087CC(CHIPS)':
 'CK_C': CDS_PINID='CK_C';
NET_NAME
'M_A_CPU1_CLK_DP<0>'
 '@S9S_MB_2U_LIB.S9S_MB_2U(SCH_1):M_A_CPU1_CLK_DP'<0>:
 C_SIGNAL='@s9s_mb_2u_lib.s9s_mb_2u(sch_1):m_a_cpu1_clk_dp(0)';
NODE_NAME     U1 C43
 '@S9S_MB_2U_LIB.S9S_MB_2U(SCH_1):PAGE51_I2@PURE_QUANTA.SOCKET4677_AZIF0045P001C01CS(CHIPS)':
 'DDR0_CLK_DP0': CDS_PINID='DDR0_CLK_DP0';
NODE_NAME     J17 217
 '@S9S_MB_2U_LIB.S9S_MB_2U(SCH_1):PAGE98_I12@PURE_QUANTA.SCONN288_ADR50017P130CC(CHIPS)':
 'CK_T': CDS_PINID='CK_T';
NET_NAME
'M_A_CPU1_CLK_DP<1>'
 '@S9S_MB_2U_LIB.S9S_MB_2U(SCH_1):M_A_CPU1_CLK_DP'<1>:
 C_SIGNAL='@s9s_mb_2u_lib.s9s_mb_2u(sch_1):m_a_cpu1_clk_dp(1)';
NODE_NAME     U1 E45
 '@S9S_MB_2U_LIB.S9S_MB_2U(SCH_1):PAGE51_I2@PURE_QUANTA.SOCKET4677_AZIF0045P001C01CS(CHIPS)':
 'DDR0_CLK_DP1': CDS_PINID='DDR0_CLK_DP1';
NODE_NAME     J18 217
 '@S9S_MB_2U_LIB.S9S_MB_2U(SCH_1):PAGE99_I24@PURE_QUANTA.SCONN288_ADR50017P087CC(CHIPS)':
 'CK_T': CDS_PINID='CK_T';
NET_NAME
'M_A_CPU1_SA_CA<0>'
 '@S9S_MB_2U_LIB.S9S_MB_2U(SCH_1):M_A_CPU1_SA_CA'<0>:
 C_SIGNAL='@s9s_mb_2u_lib.s9s_mb_2u(sch_1):m_a_cpu1_sa_ca(0)';
NODE_NAME     U1 A52
 '@S9S_MB_2U_LIB.S9S_MB_2U(SCH_1):PAGE51_I2@PURE_QUANTA.SOCKET4677_AZIF0045P001C01CS(CHIPS)':
 'DDR0_SA_CA0': CDS_PINID='DDR0_SA_CA0';
NODE_NAME     J17 66
 '@S9S_MB_2U_LIB.S9S_MB_2U(SCH_1):PAGE98_I12@PURE_QUANTA.SCONN288_ADR50017P130CC(CHIPS)':
 'CA0_A': CDS_PINID='CA0_A';
NODE_NAME     J18 66
 '@S9S_MB_2U_LIB.S9S_MB_2U(SCH_1):PAGE99_I24@PURE_QUANTA.SCONN288_ADR50017P087CC(CHIPS)':
 'CA0_A': CDS_PINID='CA0_A';
NET_NAME
'M_A_CPU1_SA_CA<1>'
 '@S9S_MB_2U_LIB.S9S_MB_2U(SCH_1):M_A_CPU1_SA_CA'<1>:
 C_SIGNAL='@s9s_mb_2u_lib.s9s_mb_2u(sch_1):m_a_cpu1_sa_ca(1)';
NODE_NAME     U1 G52
 '@S9S_MB_2U_LIB.S9S_MB_2U(SCH_1):PAGE51_I2@PURE_QUANTA.SOCKET4677_AZIF0045P001C01CS(CHIPS)':
 'DDR0_SA_CA1': CDS_PINID='DDR0_SA_CA1';
NODE_NAME     J17 211
 '@S9S_MB_2U_LIB.S9S_MB_2U(SCH_1):PAGE98_I12@PURE_QUANTA.SCONN288_ADR50017P130CC(CHIPS)':
 'CA1_A': CDS_PINID='CA1_A';
NODE_NAME     J18 211
 '@S9S_MB_2U_LIB.S9S_MB_2U(SCH_1):PAGE99_I24@PURE_QUANTA.SCONN288_ADR50017P087CC(CHIPS)':
 'CA1_A': CDS_PINID='CA1_A';
NET_NAME
'M_A_CPU1_SA_CA<2>'
 '@S9S_MB_2U_LIB.S9S_MB_2U(SCH_1):M_A_CPU1_SA_CA'<2>:
 C_SIGNAL='@s9s_mb_2u_lib.s9s_mb_2u(sch_1):m_a_cpu1_sa_ca(2)';
NODE_NAME     U1 B51
 '@S9S_MB_2U_LIB.S9S_MB_2U(SCH_1):PAGE51_I2@PURE_QUANTA.SOCKET4677_AZIF0045P001C01CS(CHIPS)':
 'DDR0_SA_CA2': CDS_PINID='DDR0_SA_CA2';
NODE_NAME     J17 68
 '@S9S_MB_2U_LIB.S9S_MB_2U(SCH_1):PAGE98_I12@PURE_QUANTA.SCONN288_ADR50017P130CC(CHIPS)':
 'CA2_A': CDS_PINID='CA2_A';
NODE_NAME     J18 68
 '@S9S_MB_2U_LIB.S9S_MB_2U(SCH_1):PAGE99_I24@PURE_QUANTA.SCONN288_ADR50017P087CC(CHIPS)':
 'CA2_A': CDS_PINID='CA2_A';
NET_NAME
'M_A_CPU1_SA_CA<3>'
 '@S9S_MB_2U_LIB.S9S_MB_2U(SCH_1):M_A_CPU1_SA_CA'<3>:
 C_SIGNAL='@s9s_mb_2u_lib.s9s_mb_2u(sch_1):m_a_cpu1_sa_ca(3)';
NODE_NAME     U1 F51
 '@S9S_MB_2U_LIB.S9S_MB_2U(SCH_1):PAGE51_I2@PURE_QUANTA.SOCKET4677_AZIF0045P001C01CS(CHIPS)':
 'DDR0_SA_CA3': CDS_PINID='DDR0_SA_CA3';
NODE_NAME     J17 213
 '@S9S_MB_2U_LIB.S9S_MB_2U(SCH_1):PAGE98_I12@PURE_QUANTA.SCONN288_ADR50017P130CC(CHIPS)':
 'CA3_A': CDS_PINID='CA3_A';
NODE_NAME     J18 213
 '@S9S_MB_2U_LIB.S9S_MB_2U(SCH_1):PAGE99_I24@PURE_QUANTA.SCONN288_ADR50017P087CC(CHIPS)':
 'CA3_A': CDS_PINID='CA3_A';
NET_NAME
'M_A_CPU1_SA_CA<4>'
 '@S9S_MB_2U_LIB.S9S_MB_2U(SCH_1):M_A_CPU1_SA_CA'<4>:
 C_SIGNAL='@s9s_mb_2u_lib.s9s_mb_2u(sch_1):m_a_cpu1_sa_ca(4)';
NODE_NAME     U1 C50
 '@S9S_MB_2U_LIB.S9S_MB_2U(SCH_1):PAGE51_I2@PURE_QUANTA.SOCKET4677_AZIF0045P001C01CS(CHIPS)':
 'DDR0_SA_CA4': CDS_PINID='DDR0_SA_CA4';
NODE_NAME     J17 70
 '@S9S_MB_2U_LIB.S9S_MB_2U(SCH_1):PAGE98_I12@PURE_QUANTA.SCONN288_ADR50017P130CC(CHIPS)':
 'CA4_A': CDS_PINID='CA4_A';
NODE_NAME     J18 70
 '@S9S_MB_2U_LIB.S9S_MB_2U(SCH_1):PAGE99_I24@PURE_QUANTA.SCONN288_ADR50017P087CC(CHIPS)':
 'CA4_A': CDS_PINID='CA4_A';
NET_NAME
'M_A_CPU1_SA_CA<5>'
 '@S9S_MB_2U_LIB.S9S_MB_2U(SCH_1):M_A_CPU1_SA_CA'<5>:
 C_SIGNAL='@s9s_mb_2u_lib.s9s_mb_2u(sch_1):m_a_cpu1_sa_ca(5)';
NODE_NAME     U1 E50
 '@S9S_MB_2U_LIB.S9S_MB_2U(SCH_1):PAGE51_I2@PURE_QUANTA.SOCKET4677_AZIF0045P001C01CS(CHIPS)':
 'DDR0_SA_CA5': CDS_PINID='DDR0_SA_CA5';
NODE_NAME     J17 215
 '@S9S_MB_2U_LIB.S9S_MB_2U(SCH_1):PAGE98_I12@PURE_QUANTA.SCONN288_ADR50017P130CC(CHIPS)':
 'CA5_A': CDS_PINID='CA5_A';
NODE_NAME     J18 215
 '@S9S_MB_2U_LIB.S9S_MB_2U(SCH_1):PAGE99_I24@PURE_QUANTA.SCONN288_ADR50017P087CC(CHIPS)':
 'CA5_A': CDS_PINID='CA5_A';
NET_NAME
'M_A_CPU1_SA_CA<6>'
 '@S9S_MB_2U_LIB.S9S_MB_2U(SCH_1):M_A_CPU1_SA_CA'<6>:
 C_SIGNAL='@s9s_mb_2u_lib.s9s_mb_2u(sch_1):m_a_cpu1_sa_ca(6)';
NODE_NAME     U1 C48
 '@S9S_MB_2U_LIB.S9S_MB_2U(SCH_1):PAGE51_I2@PURE_QUANTA.SOCKET4677_AZIF0045P001C01CS(CHIPS)':
 'DDR0_SA_CA6': CDS_PINID='DDR0_SA_CA6';
NODE_NAME     J17 72
 '@S9S_MB_2U_LIB.S9S_MB_2U(SCH_1):PAGE98_I12@PURE_QUANTA.SCONN288_ADR50017P130CC(CHIPS)':
 'CA6_A': CDS_PINID='CA6_A';
NODE_NAME     J18 72
 '@S9S_MB_2U_LIB.S9S_MB_2U(SCH_1):PAGE99_I24@PURE_QUANTA.SCONN288_ADR50017P087CC(CHIPS)':
 'CA6_A': CDS_PINID='CA6_A';
NET_NAME
'M_A_CPU1_SA_CB<0>'
 '@S9S_MB_2U_LIB.S9S_MB_2U(SCH_1):M_A_CPU1_SA_CB'<0>:
 C_SIGNAL='@s9s_mb_2u_lib.s9s_mb_2u(sch_1):m_a_cpu1_sa_cb(0)';
NODE_NAME     U1 C60
 '@S9S_MB_2U_LIB.S9S_MB_2U(SCH_1):PAGE51_I2@PURE_QUANTA.SOCKET4677_AZIF0045P001C01CS(CHIPS)':
 'DDR0_SA_ECC0': CDS_PINID='DDR0_SA_ECC0';
NODE_NAME     J17 51
 '@S9S_MB_2U_LIB.S9S_MB_2U(SCH_1):PAGE98_I12@PURE_QUANTA.SCONN288_ADR50017P130CC(CHIPS)':
 'CB0_A': CDS_PINID='CB0_A';
NODE_NAME     J18 51
 '@S9S_MB_2U_LIB.S9S_MB_2U(SCH_1):PAGE99_I24@PURE_QUANTA.SCONN288_ADR50017P087CC(CHIPS)':
 'CB0_A': CDS_PINID='CB0_A';
NET_NAME
'M_A_CPU1_SA_CB<1>'
 '@S9S_MB_2U_LIB.S9S_MB_2U(SCH_1):M_A_CPU1_SA_CB'<1>:
 C_SIGNAL='@s9s_mb_2u_lib.s9s_mb_2u(sch_1):m_a_cpu1_sa_cb(1)';
NODE_NAME     U1 B59
 '@S9S_MB_2U_LIB.S9S_MB_2U(SCH_1):PAGE51_I2@PURE_QUANTA.SOCKET4677_AZIF0045P001C01CS(CHIPS)':
 'DDR0_SA_ECC1': CDS_PINID='DDR0_SA_ECC1';
NODE_NAME     J17 53
 '@S9S_MB_2U_LIB.S9S_MB_2U(SCH_1):PAGE98_I12@PURE_QUANTA.SCONN288_ADR50017P130CC(CHIPS)':
 'CB1_A': CDS_PINID='CB1_A';
NODE_NAME     J18 53
 '@S9S_MB_2U_LIB.S9S_MB_2U(SCH_1):PAGE99_I24@PURE_QUANTA.SCONN288_ADR50017P087CC(CHIPS)':
 'CB1_A': CDS_PINID='CB1_A';
NET_NAME
'M_A_CPU1_SA_CB<2>'
 '@S9S_MB_2U_LIB.S9S_MB_2U(SCH_1):M_A_CPU1_SA_CB'<2>:
 C_SIGNAL='@s9s_mb_2u_lib.s9s_mb_2u(sch_1):m_a_cpu1_sa_cb(2)';
NODE_NAME     U1 E60
 '@S9S_MB_2U_LIB.S9S_MB_2U(SCH_1):PAGE51_I2@PURE_QUANTA.SOCKET4677_AZIF0045P001C01CS(CHIPS)':
 'DDR0_SA_ECC2': CDS_PINID='DDR0_SA_ECC2';
NODE_NAME     J17 196
 '@S9S_MB_2U_LIB.S9S_MB_2U(SCH_1):PAGE98_I12@PURE_QUANTA.SCONN288_ADR50017P130CC(CHIPS)':
 'CB2_A': CDS_PINID='CB2_A';
NODE_NAME     J18 196
 '@S9S_MB_2U_LIB.S9S_MB_2U(SCH_1):PAGE99_I24@PURE_QUANTA.SCONN288_ADR50017P087CC(CHIPS)':
 'CB2_A': CDS_PINID='CB2_A';
NET_NAME
'M_A_CPU1_SA_CB<3>'
 '@S9S_MB_2U_LIB.S9S_MB_2U(SCH_1):M_A_CPU1_SA_CB'<3>:
 C_SIGNAL='@s9s_mb_2u_lib.s9s_mb_2u(sch_1):m_a_cpu1_sa_cb(3)';
NODE_NAME     U1 F59
 '@S9S_MB_2U_LIB.S9S_MB_2U(SCH_1):PAGE51_I2@PURE_QUANTA.SOCKET4677_AZIF0045P001C01CS(CHIPS)':
 'DDR0_SA_ECC3': CDS_PINID='DDR0_SA_ECC3';
NODE_NAME     J17 198
 '@S9S_MB_2U_LIB.S9S_MB_2U(SCH_1):PAGE98_I12@PURE_QUANTA.SCONN288_ADR50017P130CC(CHIPS)':
 'CB3_A': CDS_PINID='CB3_A';
NODE_NAME     J18 198
 '@S9S_MB_2U_LIB.S9S_MB_2U(SCH_1):PAGE99_I24@PURE_QUANTA.SCONN288_ADR50017P087CC(CHIPS)':
 'CB3_A': CDS_PINID='CB3_A';
NET_NAME
'M_A_CPU1_SA_CB<4>'
 '@S9S_MB_2U_LIB.S9S_MB_2U(SCH_1):M_A_CPU1_SA_CB'<4>:
 C_SIGNAL='@s9s_mb_2u_lib.s9s_mb_2u(sch_1):m_a_cpu1_sa_cb(4)';
NODE_NAME     U1 B57
 '@S9S_MB_2U_LIB.S9S_MB_2U(SCH_1):PAGE51_I2@PURE_QUANTA.SOCKET4677_AZIF0045P001C01CS(CHIPS)':
 'DDR0_SA_ECC4': CDS_PINID='DDR0_SA_ECC4';
NODE_NAME     J17 58
 '@S9S_MB_2U_LIB.S9S_MB_2U(SCH_1):PAGE98_I12@PURE_QUANTA.SCONN288_ADR50017P130CC(CHIPS)':
 'CB4_A': CDS_PINID='CB4_A';
NODE_NAME     J18 58
 '@S9S_MB_2U_LIB.S9S_MB_2U(SCH_1):PAGE99_I24@PURE_QUANTA.SCONN288_ADR50017P087CC(CHIPS)':
 'CB4_A': CDS_PINID='CB4_A';
NET_NAME
'M_A_CPU1_SA_CB<5>'
 '@S9S_MB_2U_LIB.S9S_MB_2U(SCH_1):M_A_CPU1_SA_CB'<5>:
 C_SIGNAL='@s9s_mb_2u_lib.s9s_mb_2u(sch_1):m_a_cpu1_sa_cb(5)';
NODE_NAME     U1 C56
 '@S9S_MB_2U_LIB.S9S_MB_2U(SCH_1):PAGE51_I2@PURE_QUANTA.SOCKET4677_AZIF0045P001C01CS(CHIPS)':
 'DDR0_SA_ECC5': CDS_PINID='DDR0_SA_ECC5';
NODE_NAME     J17 60
 '@S9S_MB_2U_LIB.S9S_MB_2U(SCH_1):PAGE98_I12@PURE_QUANTA.SCONN288_ADR50017P130CC(CHIPS)':
 'CB5_A': CDS_PINID='CB5_A';
NODE_NAME     J18 60
 '@S9S_MB_2U_LIB.S9S_MB_2U(SCH_1):PAGE99_I24@PURE_QUANTA.SCONN288_ADR50017P087CC(CHIPS)':
 'CB5_A': CDS_PINID='CB5_A';
NET_NAME
'M_A_CPU1_SA_CB<6>'
 '@S9S_MB_2U_LIB.S9S_MB_2U(SCH_1):M_A_CPU1_SA_CB'<6>:
 C_SIGNAL='@s9s_mb_2u_lib.s9s_mb_2u(sch_1):m_a_cpu1_sa_cb(6)';
NODE_NAME     U1 F57
 '@S9S_MB_2U_LIB.S9S_MB_2U(SCH_1):PAGE51_I2@PURE_QUANTA.SOCKET4677_AZIF0045P001C01CS(CHIPS)':
 'DDR0_SA_ECC6': CDS_PINID='DDR0_SA_ECC6';
NODE_NAME     J17 203
 '@S9S_MB_2U_LIB.S9S_MB_2U(SCH_1):PAGE98_I12@PURE_QUANTA.SCONN288_ADR50017P130CC(CHIPS)':
 'CB6_A': CDS_PINID='CB6_A';
NODE_NAME     J18 203
 '@S9S_MB_2U_LIB.S9S_MB_2U(SCH_1):PAGE99_I24@PURE_QUANTA.SCONN288_ADR50017P087CC(CHIPS)':
 'CB6_A': CDS_PINID='CB6_A';
NET_NAME
'M_A_CPU1_SA_CB<7>'
 '@S9S_MB_2U_LIB.S9S_MB_2U(SCH_1):M_A_CPU1_SA_CB'<7>:
 C_SIGNAL='@s9s_mb_2u_lib.s9s_mb_2u(sch_1):m_a_cpu1_sa_cb(7)';
NODE_NAME     U1 E56
 '@S9S_MB_2U_LIB.S9S_MB_2U(SCH_1):PAGE51_I2@PURE_QUANTA.SOCKET4677_AZIF0045P001C01CS(CHIPS)':
 'DDR0_SA_ECC7': CDS_PINID='DDR0_SA_ECC7';
NODE_NAME     J17 205
 '@S9S_MB_2U_LIB.S9S_MB_2U(SCH_1):PAGE98_I12@PURE_QUANTA.SCONN288_ADR50017P130CC(CHIPS)':
 'CB7_A': CDS_PINID='CB7_A';
NODE_NAME     J18 205
 '@S9S_MB_2U_LIB.S9S_MB_2U(SCH_1):PAGE99_I24@PURE_QUANTA.SCONN288_ADR50017P087CC(CHIPS)':
 'CB7_A': CDS_PINID='CB7_A';
NET_NAME
'M_A_CPU1_SA_CS_N<0>'
 '@S9S_MB_2U_LIB.S9S_MB_2U(SCH_1):M_A_CPU1_SA_CS_N'<0>:
 C_SIGNAL='@s9s_mb_2u_lib.s9s_mb_2u(sch_1):m_a_cpu1_sa_cs_n(0)';
NODE_NAME     U1 C54
 '@S9S_MB_2U_LIB.S9S_MB_2U(SCH_1):PAGE51_I2@PURE_QUANTA.SOCKET4677_AZIF0045P001C01CS(CHIPS)':
 'DDR0_SA_CS_N0': CDS_PINID='DDR0_SA_CS_N0';
NODE_NAME     J17 64
 '@S9S_MB_2U_LIB.S9S_MB_2U(SCH_1):PAGE98_I12@PURE_QUANTA.SCONN288_ADR50017P130CC(CHIPS)':
 'CS0_A_N': CDS_PINID='CS0_A_N';
NET_NAME
'M_A_CPU1_SA_CS_N<1>'
 '@S9S_MB_2U_LIB.S9S_MB_2U(SCH_1):M_A_CPU1_SA_CS_N'<1>:
 C_SIGNAL='@s9s_mb_2u_lib.s9s_mb_2u(sch_1):m_a_cpu1_sa_cs_n(1)';
NODE_NAME     U1 B53
 '@S9S_MB_2U_LIB.S9S_MB_2U(SCH_1):PAGE51_I2@PURE_QUANTA.SOCKET4677_AZIF0045P001C01CS(CHIPS)':
 'DDR0_SA_CS_N1': CDS_PINID='DDR0_SA_CS_N1';
NODE_NAME     J17 209
 '@S9S_MB_2U_LIB.S9S_MB_2U(SCH_1):PAGE98_I12@PURE_QUANTA.SCONN288_ADR50017P130CC(CHIPS)':
 'CS1_A_N': CDS_PINID='CS1_A_N';
NET_NAME
'M_A_CPU1_SA_CS_N<2>'
 '@S9S_MB_2U_LIB.S9S_MB_2U(SCH_1):M_A_CPU1_SA_CS_N'<2>:
 C_SIGNAL='@s9s_mb_2u_lib.s9s_mb_2u(sch_1):m_a_cpu1_sa_cs_n(2)';
NODE_NAME     U1 E54
 '@S9S_MB_2U_LIB.S9S_MB_2U(SCH_1):PAGE51_I2@PURE_QUANTA.SOCKET4677_AZIF0045P001C01CS(CHIPS)':
 'DDR0_SA_CS_N2': CDS_PINID='DDR0_SA_CS_N2';
NODE_NAME     J18 64
 '@S9S_MB_2U_LIB.S9S_MB_2U(SCH_1):PAGE99_I24@PURE_QUANTA.SCONN288_ADR50017P087CC(CHIPS)':
 'CS0_A_N': CDS_PINID='CS0_A_N';
NET_NAME
'M_A_CPU1_SA_CS_N<3>'
 '@S9S_MB_2U_LIB.S9S_MB_2U(SCH_1):M_A_CPU1_SA_CS_N'<3>:
 C_SIGNAL='@s9s_mb_2u_lib.s9s_mb_2u(sch_1):m_a_cpu1_sa_cs_n(3)';
NODE_NAME     U1 F53
 '@S9S_MB_2U_LIB.S9S_MB_2U(SCH_1):PAGE51_I2@PURE_QUANTA.SOCKET4677_AZIF0045P001C01CS(CHIPS)':
 'DDR0_SA_CS_N3': CDS_PINID='DDR0_SA_CS_N3';
NODE_NAME     J18 209
 '@S9S_MB_2U_LIB.S9S_MB_2U(SCH_1):PAGE99_I24@PURE_QUANTA.SCONN288_ADR50017P087CC(CHIPS)':
 'CS1_A_N': CDS_PINID='CS1_A_N';
NET_NAME
'M_A_CPU1_SA_DQ<0>'
 '@S9S_MB_2U_LIB.S9S_MB_2U(SCH_1):M_A_CPU1_SA_DQ'<0>:
 C_SIGNAL='@s9s_mb_2u_lib.s9s_mb_2u(sch_1):m_a_cpu1_sa_dq(0)';
NODE_NAME     U1 B81
 '@S9S_MB_2U_LIB.S9S_MB_2U(SCH_1):PAGE51_I2@PURE_QUANTA.SOCKET4677_AZIF0045P001C01CS(CHIPS)':
 'DDR0_SA_DQ0': CDS_PINID='DDR0_SA_DQ0';
NODE_NAME     J17 7
 '@S9S_MB_2U_LIB.S9S_MB_2U(SCH_1):PAGE98_I12@PURE_QUANTA.SCONN288_ADR50017P130CC(CHIPS)':
 'DQ0_A': CDS_PINID='DQ0_A';
NODE_NAME     J18 7
 '@S9S_MB_2U_LIB.S9S_MB_2U(SCH_1):PAGE99_I24@PURE_QUANTA.SCONN288_ADR50017P087CC(CHIPS)':
 'DQ0_A': CDS_PINID='DQ0_A';
NET_NAME
'M_A_CPU1_SA_DQ<10>'
 '@S9S_MB_2U_LIB.S9S_MB_2U(SCH_1):M_A_CPU1_SA_DQ'<10>:
 C_SIGNAL='@s9s_mb_2u_lib.s9s_mb_2u(sch_1):m_a_cpu1_sa_dq(10)';
NODE_NAME     U1 M69
 '@S9S_MB_2U_LIB.S9S_MB_2U(SCH_1):PAGE51_I2@PURE_QUANTA.SOCKET4677_AZIF0045P001C01CS(CHIPS)':
 'DDR0_SA_DQ10': CDS_PINID='DDR0_SA_DQ10';
NODE_NAME     J17 163
 '@S9S_MB_2U_LIB.S9S_MB_2U(SCH_1):PAGE98_I12@PURE_QUANTA.SCONN288_ADR50017P130CC(CHIPS)':
 'DQ10_A': CDS_PINID='DQ10_A';
NODE_NAME     J18 163
 '@S9S_MB_2U_LIB.S9S_MB_2U(SCH_1):PAGE99_I24@PURE_QUANTA.SCONN288_ADR50017P087CC(CHIPS)':
 'DQ10_A': CDS_PINID='DQ10_A';
NET_NAME
'M_A_CPU1_SA_DQ<11>'
 '@S9S_MB_2U_LIB.S9S_MB_2U(SCH_1):M_A_CPU1_SA_DQ'<11>:
 C_SIGNAL='@s9s_mb_2u_lib.s9s_mb_2u(sch_1):m_a_cpu1_sa_dq(11)';
NODE_NAME     U1 N68
 '@S9S_MB_2U_LIB.S9S_MB_2U(SCH_1):PAGE51_I2@PURE_QUANTA.SOCKET4677_AZIF0045P001C01CS(CHIPS)':
 'DDR0_SA_DQ11': CDS_PINID='DDR0_SA_DQ11';
NODE_NAME     J17 165
 '@S9S_MB_2U_LIB.S9S_MB_2U(SCH_1):PAGE98_I12@PURE_QUANTA.SCONN288_ADR50017P130CC(CHIPS)':
 'DQ11_A': CDS_PINID='DQ11_A';
NODE_NAME     J18 165
 '@S9S_MB_2U_LIB.S9S_MB_2U(SCH_1):PAGE99_I24@PURE_QUANTA.SCONN288_ADR50017P087CC(CHIPS)':
 'DQ11_A': CDS_PINID='DQ11_A';
NET_NAME
'M_A_CPU1_SA_DQ<12>'
 '@S9S_MB_2U_LIB.S9S_MB_2U(SCH_1):M_A_CPU1_SA_DQ'<12>:
 C_SIGNAL='@s9s_mb_2u_lib.s9s_mb_2u(sch_1):m_a_cpu1_sa_dq(12)';
NODE_NAME     U1 J66
 '@S9S_MB_2U_LIB.S9S_MB_2U(SCH_1):PAGE51_I2@PURE_QUANTA.SOCKET4677_AZIF0045P001C01CS(CHIPS)':
 'DDR0_SA_DQ12': CDS_PINID='DDR0_SA_DQ12';
NODE_NAME     J17 25
 '@S9S_MB_2U_LIB.S9S_MB_2U(SCH_1):PAGE98_I12@PURE_QUANTA.SCONN288_ADR50017P130CC(CHIPS)':
 'DQ12_A': CDS_PINID='DQ12_A';
NODE_NAME     J18 25
 '@S9S_MB_2U_LIB.S9S_MB_2U(SCH_1):PAGE99_I24@PURE_QUANTA.SCONN288_ADR50017P087CC(CHIPS)':
 'DQ12_A': CDS_PINID='DQ12_A';
NET_NAME
'M_A_CPU1_SA_DQ<13>'
 '@S9S_MB_2U_LIB.S9S_MB_2U(SCH_1):M_A_CPU1_SA_DQ'<13>:
 C_SIGNAL='@s9s_mb_2u_lib.s9s_mb_2u(sch_1):m_a_cpu1_sa_dq(13)';
NODE_NAME     U1 K65
 '@S9S_MB_2U_LIB.S9S_MB_2U(SCH_1):PAGE51_I2@PURE_QUANTA.SOCKET4677_AZIF0045P001C01CS(CHIPS)':
 'DDR0_SA_DQ13': CDS_PINID='DDR0_SA_DQ13';
NODE_NAME     J17 27
 '@S9S_MB_2U_LIB.S9S_MB_2U(SCH_1):PAGE98_I12@PURE_QUANTA.SCONN288_ADR50017P130CC(CHIPS)':
 'DQ13_A': CDS_PINID='DQ13_A';
NODE_NAME     J18 27
 '@S9S_MB_2U_LIB.S9S_MB_2U(SCH_1):PAGE99_I24@PURE_QUANTA.SCONN288_ADR50017P087CC(CHIPS)':
 'DQ13_A': CDS_PINID='DQ13_A';
NET_NAME
'M_A_CPU1_SA_DQ<14>'
 '@S9S_MB_2U_LIB.S9S_MB_2U(SCH_1):M_A_CPU1_SA_DQ'<14>:
 C_SIGNAL='@s9s_mb_2u_lib.s9s_mb_2u(sch_1):m_a_cpu1_sa_dq(14)';
NODE_NAME     U1 N66
 '@S9S_MB_2U_LIB.S9S_MB_2U(SCH_1):PAGE51_I2@PURE_QUANTA.SOCKET4677_AZIF0045P001C01CS(CHIPS)':
 'DDR0_SA_DQ14': CDS_PINID='DDR0_SA_DQ14';
NODE_NAME     J17 170
 '@S9S_MB_2U_LIB.S9S_MB_2U(SCH_1):PAGE98_I12@PURE_QUANTA.SCONN288_ADR50017P130CC(CHIPS)':
 'DQ14_A': CDS_PINID='DQ14_A';
NODE_NAME     J18 170
 '@S9S_MB_2U_LIB.S9S_MB_2U(SCH_1):PAGE99_I24@PURE_QUANTA.SCONN288_ADR50017P087CC(CHIPS)':
 'DQ14_A': CDS_PINID='DQ14_A';
NET_NAME
'M_A_CPU1_SA_DQ<15>'
 '@S9S_MB_2U_LIB.S9S_MB_2U(SCH_1):M_A_CPU1_SA_DQ'<15>:
 C_SIGNAL='@s9s_mb_2u_lib.s9s_mb_2u(sch_1):m_a_cpu1_sa_dq(15)';
NODE_NAME     U1 M65
 '@S9S_MB_2U_LIB.S9S_MB_2U(SCH_1):PAGE51_I2@PURE_QUANTA.SOCKET4677_AZIF0045P001C01CS(CHIPS)':
 'DDR0_SA_DQ15': CDS_PINID='DDR0_SA_DQ15';
NODE_NAME     J17 172
 '@S9S_MB_2U_LIB.S9S_MB_2U(SCH_1):PAGE98_I12@PURE_QUANTA.SCONN288_ADR50017P130CC(CHIPS)':
 'DQ15_A': CDS_PINID='DQ15_A';
NODE_NAME     J18 172
 '@S9S_MB_2U_LIB.S9S_MB_2U(SCH_1):PAGE99_I24@PURE_QUANTA.SCONN288_ADR50017P087CC(CHIPS)':
 'DQ15_A': CDS_PINID='DQ15_A';
NET_NAME
'M_A_CPU1_SA_DQ<16>'
 '@S9S_MB_2U_LIB.S9S_MB_2U(SCH_1):M_A_CPU1_SA_DQ'<16>:
 C_SIGNAL='@s9s_mb_2u_lib.s9s_mb_2u(sch_1):m_a_cpu1_sa_dq(16)';
NODE_NAME     U1 B73
 '@S9S_MB_2U_LIB.S9S_MB_2U(SCH_1):PAGE51_I2@PURE_QUANTA.SOCKET4677_AZIF0045P001C01CS(CHIPS)':
 'DDR0_SA_DQ16': CDS_PINID='DDR0_SA_DQ16';
NODE_NAME     J17 29
 '@S9S_MB_2U_LIB.S9S_MB_2U(SCH_1):PAGE98_I12@PURE_QUANTA.SCONN288_ADR50017P130CC(CHIPS)':
 'DQ16_A': CDS_PINID='DQ16_A';
NODE_NAME     J18 29
 '@S9S_MB_2U_LIB.S9S_MB_2U(SCH_1):PAGE99_I24@PURE_QUANTA.SCONN288_ADR50017P087CC(CHIPS)':
 'DQ16_A': CDS_PINID='DQ16_A';
NET_NAME
'M_A_CPU1_SA_DQ<17>'
 '@S9S_MB_2U_LIB.S9S_MB_2U(SCH_1):M_A_CPU1_SA_DQ'<17>:
 C_SIGNAL='@s9s_mb_2u_lib.s9s_mb_2u(sch_1):m_a_cpu1_sa_dq(17)';
NODE_NAME     U1 E72
 '@S9S_MB_2U_LIB.S9S_MB_2U(SCH_1):PAGE51_I2@PURE_QUANTA.SOCKET4677_AZIF0045P001C01CS(CHIPS)':
 'DDR0_SA_DQ17': CDS_PINID='DDR0_SA_DQ17';
NODE_NAME     J17 31
 '@S9S_MB_2U_LIB.S9S_MB_2U(SCH_1):PAGE98_I12@PURE_QUANTA.SCONN288_ADR50017P130CC(CHIPS)':
 'DQ17_A': CDS_PINID='DQ17_A';
NODE_NAME     J18 31
 '@S9S_MB_2U_LIB.S9S_MB_2U(SCH_1):PAGE99_I24@PURE_QUANTA.SCONN288_ADR50017P087CC(CHIPS)':
 'DQ17_A': CDS_PINID='DQ17_A';
NET_NAME
'M_A_CPU1_SA_DQ<18>'
 '@S9S_MB_2U_LIB.S9S_MB_2U(SCH_1):M_A_CPU1_SA_DQ'<18>:
 C_SIGNAL='@s9s_mb_2u_lib.s9s_mb_2u(sch_1):m_a_cpu1_sa_dq(18)';
NODE_NAME     U1 D73
 '@S9S_MB_2U_LIB.S9S_MB_2U(SCH_1):PAGE51_I2@PURE_QUANTA.SOCKET4677_AZIF0045P001C01CS(CHIPS)':
 'DDR0_SA_DQ18': CDS_PINID='DDR0_SA_DQ18';
NODE_NAME     J17 174
 '@S9S_MB_2U_LIB.S9S_MB_2U(SCH_1):PAGE98_I12@PURE_QUANTA.SCONN288_ADR50017P130CC(CHIPS)':
 'DQ18_A': CDS_PINID='DQ18_A';
NODE_NAME     J18 174
 '@S9S_MB_2U_LIB.S9S_MB_2U(SCH_1):PAGE99_I24@PURE_QUANTA.SCONN288_ADR50017P087CC(CHIPS)':
 'DQ18_A': CDS_PINID='DQ18_A';
NET_NAME
'M_A_CPU1_SA_DQ<19>'
 '@S9S_MB_2U_LIB.S9S_MB_2U(SCH_1):M_A_CPU1_SA_DQ'<19>:
 C_SIGNAL='@s9s_mb_2u_lib.s9s_mb_2u(sch_1):m_a_cpu1_sa_dq(19)';
NODE_NAME     U1 F71
 '@S9S_MB_2U_LIB.S9S_MB_2U(SCH_1):PAGE51_I2@PURE_QUANTA.SOCKET4677_AZIF0045P001C01CS(CHIPS)':
 'DDR0_SA_DQ19': CDS_PINID='DDR0_SA_DQ19';
NODE_NAME     J17 176
 '@S9S_MB_2U_LIB.S9S_MB_2U(SCH_1):PAGE98_I12@PURE_QUANTA.SCONN288_ADR50017P130CC(CHIPS)':
 'DQ19_A': CDS_PINID='DQ19_A';
NODE_NAME     J18 176
 '@S9S_MB_2U_LIB.S9S_MB_2U(SCH_1):PAGE99_I24@PURE_QUANTA.SCONN288_ADR50017P087CC(CHIPS)':
 'DQ19_A': CDS_PINID='DQ19_A';
NET_NAME
'M_A_CPU1_SA_DQ<1>'
 '@S9S_MB_2U_LIB.S9S_MB_2U(SCH_1):M_A_CPU1_SA_DQ'<1>:
 C_SIGNAL='@s9s_mb_2u_lib.s9s_mb_2u(sch_1):m_a_cpu1_sa_dq(1)';
NODE_NAME     U1 B79
 '@S9S_MB_2U_LIB.S9S_MB_2U(SCH_1):PAGE51_I2@PURE_QUANTA.SOCKET4677_AZIF0045P001C01CS(CHIPS)':
 'DDR0_SA_DQ1': CDS_PINID='DDR0_SA_DQ1';
NODE_NAME     J17 9
 '@S9S_MB_2U_LIB.S9S_MB_2U(SCH_1):PAGE98_I12@PURE_QUANTA.SCONN288_ADR50017P130CC(CHIPS)':
 'DQ1_A': CDS_PINID='DQ1_A';
NODE_NAME     J18 9
 '@S9S_MB_2U_LIB.S9S_MB_2U(SCH_1):PAGE99_I24@PURE_QUANTA.SCONN288_ADR50017P087CC(CHIPS)':
 'DQ1_A': CDS_PINID='DQ1_A';
NET_NAME
'M_A_CPU1_SA_DQ<20>'
 '@S9S_MB_2U_LIB.S9S_MB_2U(SCH_1):M_A_CPU1_SA_DQ'<20>:
 C_SIGNAL='@s9s_mb_2u_lib.s9s_mb_2u(sch_1):m_a_cpu1_sa_dq(20)';
NODE_NAME     U1 B69
 '@S9S_MB_2U_LIB.S9S_MB_2U(SCH_1):PAGE51_I2@PURE_QUANTA.SOCKET4677_AZIF0045P001C01CS(CHIPS)':
 'DDR0_SA_DQ20': CDS_PINID='DDR0_SA_DQ20';
NODE_NAME     J17 36
 '@S9S_MB_2U_LIB.S9S_MB_2U(SCH_1):PAGE98_I12@PURE_QUANTA.SCONN288_ADR50017P130CC(CHIPS)':
 'DQ20_A': CDS_PINID='DQ20_A';
NODE_NAME     J18 36
 '@S9S_MB_2U_LIB.S9S_MB_2U(SCH_1):PAGE99_I24@PURE_QUANTA.SCONN288_ADR50017P087CC(CHIPS)':
 'DQ20_A': CDS_PINID='DQ20_A';
NET_NAME
'M_A_CPU1_SA_DQ<21>'
 '@S9S_MB_2U_LIB.S9S_MB_2U(SCH_1):M_A_CPU1_SA_DQ'<21>:
 C_SIGNAL='@s9s_mb_2u_lib.s9s_mb_2u(sch_1):m_a_cpu1_sa_dq(21)';
NODE_NAME     U1 C68
 '@S9S_MB_2U_LIB.S9S_MB_2U(SCH_1):PAGE51_I2@PURE_QUANTA.SOCKET4677_AZIF0045P001C01CS(CHIPS)':
 'DDR0_SA_DQ21': CDS_PINID='DDR0_SA_DQ21';
NODE_NAME     J17 38
 '@S9S_MB_2U_LIB.S9S_MB_2U(SCH_1):PAGE98_I12@PURE_QUANTA.SCONN288_ADR50017P130CC(CHIPS)':
 'DQ21_A': CDS_PINID='DQ21_A';
NODE_NAME     J18 38
 '@S9S_MB_2U_LIB.S9S_MB_2U(SCH_1):PAGE99_I24@PURE_QUANTA.SCONN288_ADR50017P087CC(CHIPS)':
 'DQ21_A': CDS_PINID='DQ21_A';
NET_NAME
'M_A_CPU1_SA_DQ<22>'
 '@S9S_MB_2U_LIB.S9S_MB_2U(SCH_1):M_A_CPU1_SA_DQ'<22>:
 C_SIGNAL='@s9s_mb_2u_lib.s9s_mb_2u(sch_1):m_a_cpu1_sa_dq(22)';
NODE_NAME     U1 F69
 '@S9S_MB_2U_LIB.S9S_MB_2U(SCH_1):PAGE51_I2@PURE_QUANTA.SOCKET4677_AZIF0045P001C01CS(CHIPS)':
 'DDR0_SA_DQ22': CDS_PINID='DDR0_SA_DQ22';
NODE_NAME     J17 181
 '@S9S_MB_2U_LIB.S9S_MB_2U(SCH_1):PAGE98_I12@PURE_QUANTA.SCONN288_ADR50017P130CC(CHIPS)':
 'DQ22_A': CDS_PINID='DQ22_A';
NODE_NAME     J18 181
 '@S9S_MB_2U_LIB.S9S_MB_2U(SCH_1):PAGE99_I24@PURE_QUANTA.SCONN288_ADR50017P087CC(CHIPS)':
 'DQ22_A': CDS_PINID='DQ22_A';
NET_NAME
'M_A_CPU1_SA_DQ<23>'
 '@S9S_MB_2U_LIB.S9S_MB_2U(SCH_1):M_A_CPU1_SA_DQ'<23>:
 C_SIGNAL='@s9s_mb_2u_lib.s9s_mb_2u(sch_1):m_a_cpu1_sa_dq(23)';
NODE_NAME     U1 E68
 '@S9S_MB_2U_LIB.S9S_MB_2U(SCH_1):PAGE51_I2@PURE_QUANTA.SOCKET4677_AZIF0045P001C01CS(CHIPS)':
 'DDR0_SA_DQ23': CDS_PINID='DDR0_SA_DQ23';
NODE_NAME     J17 183
 '@S9S_MB_2U_LIB.S9S_MB_2U(SCH_1):PAGE98_I12@PURE_QUANTA.SCONN288_ADR50017P130CC(CHIPS)':
 'DQ23_A': CDS_PINID='DQ23_A';
NODE_NAME     J18 183
 '@S9S_MB_2U_LIB.S9S_MB_2U(SCH_1):PAGE99_I24@PURE_QUANTA.SCONN288_ADR50017P087CC(CHIPS)':
 'DQ23_A': CDS_PINID='DQ23_A';
NET_NAME
'M_A_CPU1_SA_DQ<24>'
 '@S9S_MB_2U_LIB.S9S_MB_2U(SCH_1):M_A_CPU1_SA_DQ'<24>:
 C_SIGNAL='@s9s_mb_2u_lib.s9s_mb_2u(sch_1):m_a_cpu1_sa_dq(24)';
NODE_NAME     U1 C66
 '@S9S_MB_2U_LIB.S9S_MB_2U(SCH_1):PAGE51_I2@PURE_QUANTA.SOCKET4677_AZIF0045P001C01CS(CHIPS)':
 'DDR0_SA_DQ24': CDS_PINID='DDR0_SA_DQ24';
NODE_NAME     J17 40
 '@S9S_MB_2U_LIB.S9S_MB_2U(SCH_1):PAGE98_I12@PURE_QUANTA.SCONN288_ADR50017P130CC(CHIPS)':
 'DQ24_A': CDS_PINID='DQ24_A';
NODE_NAME     J18 40
 '@S9S_MB_2U_LIB.S9S_MB_2U(SCH_1):PAGE99_I24@PURE_QUANTA.SCONN288_ADR50017P087CC(CHIPS)':
 'DQ24_A': CDS_PINID='DQ24_A';
NET_NAME
'M_A_CPU1_SA_DQ<25>'
 '@S9S_MB_2U_LIB.S9S_MB_2U(SCH_1):M_A_CPU1_SA_DQ'<25>:
 C_SIGNAL='@s9s_mb_2u_lib.s9s_mb_2u(sch_1):m_a_cpu1_sa_dq(25)';
NODE_NAME     U1 B65
 '@S9S_MB_2U_LIB.S9S_MB_2U(SCH_1):PAGE51_I2@PURE_QUANTA.SOCKET4677_AZIF0045P001C01CS(CHIPS)':
 'DDR0_SA_DQ25': CDS_PINID='DDR0_SA_DQ25';
NODE_NAME     J17 42
 '@S9S_MB_2U_LIB.S9S_MB_2U(SCH_1):PAGE98_I12@PURE_QUANTA.SCONN288_ADR50017P130CC(CHIPS)':
 'DQ25_A': CDS_PINID='DQ25_A';
NODE_NAME     J18 42
 '@S9S_MB_2U_LIB.S9S_MB_2U(SCH_1):PAGE99_I24@PURE_QUANTA.SCONN288_ADR50017P087CC(CHIPS)':
 'DQ25_A': CDS_PINID='DQ25_A';
NET_NAME
'M_A_CPU1_SA_DQ<26>'
 '@S9S_MB_2U_LIB.S9S_MB_2U(SCH_1):M_A_CPU1_SA_DQ'<26>:
 C_SIGNAL='@s9s_mb_2u_lib.s9s_mb_2u(sch_1):m_a_cpu1_sa_dq(26)';
NODE_NAME     U1 E66
 '@S9S_MB_2U_LIB.S9S_MB_2U(SCH_1):PAGE51_I2@PURE_QUANTA.SOCKET4677_AZIF0045P001C01CS(CHIPS)':
 'DDR0_SA_DQ26': CDS_PINID='DDR0_SA_DQ26';
NODE_NAME     J17 185
 '@S9S_MB_2U_LIB.S9S_MB_2U(SCH_1):PAGE98_I12@PURE_QUANTA.SCONN288_ADR50017P130CC(CHIPS)':
 'DQ26_A': CDS_PINID='DQ26_A';
NODE_NAME     J18 185
 '@S9S_MB_2U_LIB.S9S_MB_2U(SCH_1):PAGE99_I24@PURE_QUANTA.SCONN288_ADR50017P087CC(CHIPS)':
 'DQ26_A': CDS_PINID='DQ26_A';
NET_NAME
'M_A_CPU1_SA_DQ<27>'
 '@S9S_MB_2U_LIB.S9S_MB_2U(SCH_1):M_A_CPU1_SA_DQ'<27>:
 C_SIGNAL='@s9s_mb_2u_lib.s9s_mb_2u(sch_1):m_a_cpu1_sa_dq(27)';
NODE_NAME     U1 F65
 '@S9S_MB_2U_LIB.S9S_MB_2U(SCH_1):PAGE51_I2@PURE_QUANTA.SOCKET4677_AZIF0045P001C01CS(CHIPS)':
 'DDR0_SA_DQ27': CDS_PINID='DDR0_SA_DQ27';
NODE_NAME     J17 187
 '@S9S_MB_2U_LIB.S9S_MB_2U(SCH_1):PAGE98_I12@PURE_QUANTA.SCONN288_ADR50017P130CC(CHIPS)':
 'DQ27_A': CDS_PINID='DQ27_A';
NODE_NAME     J18 187
 '@S9S_MB_2U_LIB.S9S_MB_2U(SCH_1):PAGE99_I24@PURE_QUANTA.SCONN288_ADR50017P087CC(CHIPS)':
 'DQ27_A': CDS_PINID='DQ27_A';
NET_NAME
'M_A_CPU1_SA_DQ<28>'
 '@S9S_MB_2U_LIB.S9S_MB_2U(SCH_1):M_A_CPU1_SA_DQ'<28>:
 C_SIGNAL='@s9s_mb_2u_lib.s9s_mb_2u(sch_1):m_a_cpu1_sa_dq(28)';
NODE_NAME     U1 B63
 '@S9S_MB_2U_LIB.S9S_MB_2U(SCH_1):PAGE51_I2@PURE_QUANTA.SOCKET4677_AZIF0045P001C01CS(CHIPS)':
 'DDR0_SA_DQ28': CDS_PINID='DDR0_SA_DQ28';
NODE_NAME     J17 47
 '@S9S_MB_2U_LIB.S9S_MB_2U(SCH_1):PAGE98_I12@PURE_QUANTA.SCONN288_ADR50017P130CC(CHIPS)':
 'DQ28_A': CDS_PINID='DQ28_A';
NODE_NAME     J18 47
 '@S9S_MB_2U_LIB.S9S_MB_2U(SCH_1):PAGE99_I24@PURE_QUANTA.SCONN288_ADR50017P087CC(CHIPS)':
 'DQ28_A': CDS_PINID='DQ28_A';
NET_NAME
'M_A_CPU1_SA_DQ<29>'
 '@S9S_MB_2U_LIB.S9S_MB_2U(SCH_1):M_A_CPU1_SA_DQ'<29>:
 C_SIGNAL='@s9s_mb_2u_lib.s9s_mb_2u(sch_1):m_a_cpu1_sa_dq(29)';
NODE_NAME     U1 C62
 '@S9S_MB_2U_LIB.S9S_MB_2U(SCH_1):PAGE51_I2@PURE_QUANTA.SOCKET4677_AZIF0045P001C01CS(CHIPS)':
 'DDR0_SA_DQ29': CDS_PINID='DDR0_SA_DQ29';
NODE_NAME     J17 49
 '@S9S_MB_2U_LIB.S9S_MB_2U(SCH_1):PAGE98_I12@PURE_QUANTA.SCONN288_ADR50017P130CC(CHIPS)':
 'DQ29_A': CDS_PINID='DQ29_A';
NODE_NAME     J18 49
 '@S9S_MB_2U_LIB.S9S_MB_2U(SCH_1):PAGE99_I24@PURE_QUANTA.SCONN288_ADR50017P087CC(CHIPS)':
 'DQ29_A': CDS_PINID='DQ29_A';
NET_NAME
'M_A_CPU1_SA_DQ<2>'
 '@S9S_MB_2U_LIB.S9S_MB_2U(SCH_1):M_A_CPU1_SA_DQ'<2>:
 C_SIGNAL='@s9s_mb_2u_lib.s9s_mb_2u(sch_1):m_a_cpu1_sa_dq(2)';
NODE_NAME     U1 M77
 '@S9S_MB_2U_LIB.S9S_MB_2U(SCH_1):PAGE51_I2@PURE_QUANTA.SOCKET4677_AZIF0045P001C01CS(CHIPS)':
 'DDR0_SA_DQ2': CDS_PINID='DDR0_SA_DQ2';
NODE_NAME     J17 152
 '@S9S_MB_2U_LIB.S9S_MB_2U(SCH_1):PAGE98_I12@PURE_QUANTA.SCONN288_ADR50017P130CC(CHIPS)':
 'DQ2_A': CDS_PINID='DQ2_A';
NODE_NAME     J18 152
 '@S9S_MB_2U_LIB.S9S_MB_2U(SCH_1):PAGE99_I24@PURE_QUANTA.SCONN288_ADR50017P087CC(CHIPS)':
 'DQ2_A': CDS_PINID='DQ2_A';
NET_NAME
'M_A_CPU1_SA_DQ<30>'
 '@S9S_MB_2U_LIB.S9S_MB_2U(SCH_1):M_A_CPU1_SA_DQ'<30>:
 C_SIGNAL='@s9s_mb_2u_lib.s9s_mb_2u(sch_1):m_a_cpu1_sa_dq(30)';
NODE_NAME     U1 F63
 '@S9S_MB_2U_LIB.S9S_MB_2U(SCH_1):PAGE51_I2@PURE_QUANTA.SOCKET4677_AZIF0045P001C01CS(CHIPS)':
 'DDR0_SA_DQ30': CDS_PINID='DDR0_SA_DQ30';
NODE_NAME     J17 192
 '@S9S_MB_2U_LIB.S9S_MB_2U(SCH_1):PAGE98_I12@PURE_QUANTA.SCONN288_ADR50017P130CC(CHIPS)':
 'DQ30_A': CDS_PINID='DQ30_A';
NODE_NAME     J18 192
 '@S9S_MB_2U_LIB.S9S_MB_2U(SCH_1):PAGE99_I24@PURE_QUANTA.SCONN288_ADR50017P087CC(CHIPS)':
 'DQ30_A': CDS_PINID='DQ30_A';
NET_NAME
'M_A_CPU1_SA_DQ<31>'
 '@S9S_MB_2U_LIB.S9S_MB_2U(SCH_1):M_A_CPU1_SA_DQ'<31>:
 C_SIGNAL='@s9s_mb_2u_lib.s9s_mb_2u(sch_1):m_a_cpu1_sa_dq(31)';
NODE_NAME     U1 E62
 '@S9S_MB_2U_LIB.S9S_MB_2U(SCH_1):PAGE51_I2@PURE_QUANTA.SOCKET4677_AZIF0045P001C01CS(CHIPS)':
 'DDR0_SA_DQ31': CDS_PINID='DDR0_SA_DQ31';
NODE_NAME     J17 194
 '@S9S_MB_2U_LIB.S9S_MB_2U(SCH_1):PAGE98_I12@PURE_QUANTA.SCONN288_ADR50017P130CC(CHIPS)':
 'DQ31_A': CDS_PINID='DQ31_A';
NODE_NAME     J18 194
 '@S9S_MB_2U_LIB.S9S_MB_2U(SCH_1):PAGE99_I24@PURE_QUANTA.SCONN288_ADR50017P087CC(CHIPS)':
 'DQ31_A': CDS_PINID='DQ31_A';
NET_NAME
'M_A_CPU1_SA_DQ<3>'
 '@S9S_MB_2U_LIB.S9S_MB_2U(SCH_1):M_A_CPU1_SA_DQ'<3>:
 C_SIGNAL='@s9s_mb_2u_lib.s9s_mb_2u(sch_1):m_a_cpu1_sa_dq(3)';
NODE_NAME     U1 G78
 '@S9S_MB_2U_LIB.S9S_MB_2U(SCH_1):PAGE51_I2@PURE_QUANTA.SOCKET4677_AZIF0045P001C01CS(CHIPS)':
 'DDR0_SA_DQ3': CDS_PINID='DDR0_SA_DQ3';
NODE_NAME     J17 154
 '@S9S_MB_2U_LIB.S9S_MB_2U(SCH_1):PAGE98_I12@PURE_QUANTA.SCONN288_ADR50017P130CC(CHIPS)':
 'DQ3_A': CDS_PINID='DQ3_A';
NODE_NAME     J18 154
 '@S9S_MB_2U_LIB.S9S_MB_2U(SCH_1):PAGE99_I24@PURE_QUANTA.SCONN288_ADR50017P087CC(CHIPS)':
 'DQ3_A': CDS_PINID='DQ3_A';
NET_NAME
'M_A_CPU1_SA_DQ<4>'
 '@S9S_MB_2U_LIB.S9S_MB_2U(SCH_1):M_A_CPU1_SA_DQ'<4>:
 C_SIGNAL='@s9s_mb_2u_lib.s9s_mb_2u(sch_1):m_a_cpu1_sa_dq(4)';
NODE_NAME     U1 C76
 '@S9S_MB_2U_LIB.S9S_MB_2U(SCH_1):PAGE51_I2@PURE_QUANTA.SOCKET4677_AZIF0045P001C01CS(CHIPS)':
 'DDR0_SA_DQ4': CDS_PINID='DDR0_SA_DQ4';
NODE_NAME     J17 14
 '@S9S_MB_2U_LIB.S9S_MB_2U(SCH_1):PAGE98_I12@PURE_QUANTA.SCONN288_ADR50017P130CC(CHIPS)':
 'DQ4_A': CDS_PINID='DQ4_A';
NODE_NAME     J18 14
 '@S9S_MB_2U_LIB.S9S_MB_2U(SCH_1):PAGE99_I24@PURE_QUANTA.SCONN288_ADR50017P087CC(CHIPS)':
 'DQ4_A': CDS_PINID='DQ4_A';
NET_NAME
'M_A_CPU1_SA_DQ<5>'
 '@S9S_MB_2U_LIB.S9S_MB_2U(SCH_1):M_A_CPU1_SA_DQ'<5>:
 C_SIGNAL='@s9s_mb_2u_lib.s9s_mb_2u(sch_1):m_a_cpu1_sa_dq(5)';
NODE_NAME     U1 D75
 '@S9S_MB_2U_LIB.S9S_MB_2U(SCH_1):PAGE51_I2@PURE_QUANTA.SOCKET4677_AZIF0045P001C01CS(CHIPS)':
 'DDR0_SA_DQ5': CDS_PINID='DDR0_SA_DQ5';
NODE_NAME     J17 16
 '@S9S_MB_2U_LIB.S9S_MB_2U(SCH_1):PAGE98_I12@PURE_QUANTA.SCONN288_ADR50017P130CC(CHIPS)':
 'DQ5_A': CDS_PINID='DQ5_A';
NODE_NAME     J18 16
 '@S9S_MB_2U_LIB.S9S_MB_2U(SCH_1):PAGE99_I24@PURE_QUANTA.SCONN288_ADR50017P087CC(CHIPS)':
 'DQ5_A': CDS_PINID='DQ5_A';
NET_NAME
'M_A_CPU1_SA_DQ<6>'
 '@S9S_MB_2U_LIB.S9S_MB_2U(SCH_1):M_A_CPU1_SA_DQ'<6>:
 C_SIGNAL='@s9s_mb_2u_lib.s9s_mb_2u(sch_1):m_a_cpu1_sa_dq(6)';
NODE_NAME     U1 G76
 '@S9S_MB_2U_LIB.S9S_MB_2U(SCH_1):PAGE51_I2@PURE_QUANTA.SOCKET4677_AZIF0045P001C01CS(CHIPS)':
 'DDR0_SA_DQ6': CDS_PINID='DDR0_SA_DQ6';
NODE_NAME     J17 159
 '@S9S_MB_2U_LIB.S9S_MB_2U(SCH_1):PAGE98_I12@PURE_QUANTA.SCONN288_ADR50017P130CC(CHIPS)':
 'DQ6_A': CDS_PINID='DQ6_A';
NODE_NAME     J18 159
 '@S9S_MB_2U_LIB.S9S_MB_2U(SCH_1):PAGE99_I24@PURE_QUANTA.SCONN288_ADR50017P087CC(CHIPS)':
 'DQ6_A': CDS_PINID='DQ6_A';
NET_NAME
'M_A_CPU1_SA_DQ<7>'
 '@S9S_MB_2U_LIB.S9S_MB_2U(SCH_1):M_A_CPU1_SA_DQ'<7>:
 C_SIGNAL='@s9s_mb_2u_lib.s9s_mb_2u(sch_1):m_a_cpu1_sa_dq(7)';
NODE_NAME     U1 F75
 '@S9S_MB_2U_LIB.S9S_MB_2U(SCH_1):PAGE51_I2@PURE_QUANTA.SOCKET4677_AZIF0045P001C01CS(CHIPS)':
 'DDR0_SA_DQ7': CDS_PINID='DDR0_SA_DQ7';
NODE_NAME     J17 161
 '@S9S_MB_2U_LIB.S9S_MB_2U(SCH_1):PAGE98_I12@PURE_QUANTA.SCONN288_ADR50017P130CC(CHIPS)':
 'DQ7_A': CDS_PINID='DQ7_A';
NODE_NAME     J18 161
 '@S9S_MB_2U_LIB.S9S_MB_2U(SCH_1):PAGE99_I24@PURE_QUANTA.SCONN288_ADR50017P087CC(CHIPS)':
 'DQ7_A': CDS_PINID='DQ7_A';
NET_NAME
'M_A_CPU1_SA_DQ<8>'
 '@S9S_MB_2U_LIB.S9S_MB_2U(SCH_1):M_A_CPU1_SA_DQ'<8>:
 C_SIGNAL='@s9s_mb_2u_lib.s9s_mb_2u(sch_1):m_a_cpu1_sa_dq(8)';
NODE_NAME     U1 K69
 '@S9S_MB_2U_LIB.S9S_MB_2U(SCH_1):PAGE51_I2@PURE_QUANTA.SOCKET4677_AZIF0045P001C01CS(CHIPS)':
 'DDR0_SA_DQ8': CDS_PINID='DDR0_SA_DQ8';
NODE_NAME     J17 18
 '@S9S_MB_2U_LIB.S9S_MB_2U(SCH_1):PAGE98_I12@PURE_QUANTA.SCONN288_ADR50017P130CC(CHIPS)':
 'DQ8_A': CDS_PINID='DQ8_A';
NODE_NAME     J18 18
 '@S9S_MB_2U_LIB.S9S_MB_2U(SCH_1):PAGE99_I24@PURE_QUANTA.SCONN288_ADR50017P087CC(CHIPS)':
 'DQ8_A': CDS_PINID='DQ8_A';
NET_NAME
'M_A_CPU1_SA_DQ<9>'
 '@S9S_MB_2U_LIB.S9S_MB_2U(SCH_1):M_A_CPU1_SA_DQ'<9>:
 C_SIGNAL='@s9s_mb_2u_lib.s9s_mb_2u(sch_1):m_a_cpu1_sa_dq(9)';
NODE_NAME     U1 J68
 '@S9S_MB_2U_LIB.S9S_MB_2U(SCH_1):PAGE51_I2@PURE_QUANTA.SOCKET4677_AZIF0045P001C01CS(CHIPS)':
 'DDR0_SA_DQ9': CDS_PINID='DDR0_SA_DQ9';
NODE_NAME     J17 20
 '@S9S_MB_2U_LIB.S9S_MB_2U(SCH_1):PAGE98_I12@PURE_QUANTA.SCONN288_ADR50017P130CC(CHIPS)':
 'DQ9_A': CDS_PINID='DQ9_A';
NODE_NAME     J18 20
 '@S9S_MB_2U_LIB.S9S_MB_2U(SCH_1):PAGE99_I24@PURE_QUANTA.SCONN288_ADR50017P087CC(CHIPS)':
 'DQ9_A': CDS_PINID='DQ9_A';
NET_NAME
'M_A_CPU1_SA_DQS_DN<0>'
 '@S9S_MB_2U_LIB.S9S_MB_2U(SCH_1):M_A_CPU1_SA_DQS_DN'<0>:
 C_SIGNAL='@s9s_mb_2u_lib.s9s_mb_2u(sch_1):m_a_cpu1_sa_dqs_dn(0)';
NODE_NAME     U1 B77
 '@S9S_MB_2U_LIB.S9S_MB_2U(SCH_1):PAGE51_I2@PURE_QUANTA.SOCKET4677_AZIF0045P001C01CS(CHIPS)':
 'DDR0_SA_DQS_DN0': CDS_PINID='DDR0_SA_DQS_DN0';
NODE_NAME     J17 12
 '@S9S_MB_2U_LIB.S9S_MB_2U(SCH_1):PAGE98_I178@PURE_QUANTA.SCONN288_ADR50017P130CC(CHIPS)':
 'DQS0_A_C': CDS_PINID='DQS0_A_C';
NODE_NAME     J18 12
 '@S9S_MB_2U_LIB.S9S_MB_2U(SCH_1):PAGE99_I178@PURE_QUANTA.SCONN288_ADR50017P087CC(CHIPS)':
 'DQS0_A_C': CDS_PINID='DQS0_A_C';
NET_NAME
'M_A_CPU1_SA_DQS_DN<1>'
 '@S9S_MB_2U_LIB.S9S_MB_2U(SCH_1):M_A_CPU1_SA_DQS_DN'<1>:
 C_SIGNAL='@s9s_mb_2u_lib.s9s_mb_2u(sch_1):m_a_cpu1_sa_dqs_dn(1)';
NODE_NAME     U1 H67
 '@S9S_MB_2U_LIB.S9S_MB_2U(SCH_1):PAGE51_I2@PURE_QUANTA.SOCKET4677_AZIF0045P001C01CS(CHIPS)':
 'DDR0_SA_DQS_DN1': CDS_PINID='DDR0_SA_DQS_DN1';
NODE_NAME     J17 23
 '@S9S_MB_2U_LIB.S9S_MB_2U(SCH_1):PAGE98_I178@PURE_QUANTA.SCONN288_ADR50017P130CC(CHIPS)':
 'DQS1_A_C': CDS_PINID='DQS1_A_C';
NODE_NAME     J18 23
 '@S9S_MB_2U_LIB.S9S_MB_2U(SCH_1):PAGE99_I178@PURE_QUANTA.SCONN288_ADR50017P087CC(CHIPS)':
 'DQS1_A_C': CDS_PINID='DQS1_A_C';
NET_NAME
'M_A_CPU1_SA_DQS_DN<2>'
 '@S9S_MB_2U_LIB.S9S_MB_2U(SCH_1):M_A_CPU1_SA_DQS_DN'<2>:
 C_SIGNAL='@s9s_mb_2u_lib.s9s_mb_2u(sch_1):m_a_cpu1_sa_dqs_dn(2)';
NODE_NAME     U1 B71
 '@S9S_MB_2U_LIB.S9S_MB_2U(SCH_1):PAGE51_I2@PURE_QUANTA.SOCKET4677_AZIF0045P001C01CS(CHIPS)':
 'DDR0_SA_DQS_DN2': CDS_PINID='DDR0_SA_DQS_DN2';
NODE_NAME     J17 34
 '@S9S_MB_2U_LIB.S9S_MB_2U(SCH_1):PAGE98_I178@PURE_QUANTA.SCONN288_ADR50017P130CC(CHIPS)':
 'DQS2_A_C': CDS_PINID='DQS2_A_C';
NODE_NAME     J18 34
 '@S9S_MB_2U_LIB.S9S_MB_2U(SCH_1):PAGE99_I178@PURE_QUANTA.SCONN288_ADR50017P087CC(CHIPS)':
 'DQS2_A_C': CDS_PINID='DQS2_A_C';
NET_NAME
'M_A_CPU1_SA_DQS_DN<3>'
 '@S9S_MB_2U_LIB.S9S_MB_2U(SCH_1):M_A_CPU1_SA_DQS_DN'<3>:
 C_SIGNAL='@s9s_mb_2u_lib.s9s_mb_2u(sch_1):m_a_cpu1_sa_dqs_dn(3)';
NODE_NAME     U1 A64
 '@S9S_MB_2U_LIB.S9S_MB_2U(SCH_1):PAGE51_I2@PURE_QUANTA.SOCKET4677_AZIF0045P001C01CS(CHIPS)':
 'DDR0_SA_DQS_DN3': CDS_PINID='DDR0_SA_DQS_DN3';
NODE_NAME     J17 45
 '@S9S_MB_2U_LIB.S9S_MB_2U(SCH_1):PAGE98_I178@PURE_QUANTA.SCONN288_ADR50017P130CC(CHIPS)':
 'DQS3_A_C': CDS_PINID='DQS3_A_C';
NODE_NAME     J18 45
 '@S9S_MB_2U_LIB.S9S_MB_2U(SCH_1):PAGE99_I178@PURE_QUANTA.SCONN288_ADR50017P087CC(CHIPS)':
 'DQS3_A_C': CDS_PINID='DQS3_A_C';
NET_NAME
'M_A_CPU1_SA_DQS_DN<4>'
 '@S9S_MB_2U_LIB.S9S_MB_2U(SCH_1):M_A_CPU1_SA_DQS_DN'<4>:
 C_SIGNAL='@s9s_mb_2u_lib.s9s_mb_2u(sch_1):m_a_cpu1_sa_dqs_dn(4)';
NODE_NAME     U1 A58
 '@S9S_MB_2U_LIB.S9S_MB_2U(SCH_1):PAGE51_I2@PURE_QUANTA.SOCKET4677_AZIF0045P001C01CS(CHIPS)':
 'DDR0_SA_DQS_DN4': CDS_PINID='DDR0_SA_DQS_DN4';
NODE_NAME     J17 56
 '@S9S_MB_2U_LIB.S9S_MB_2U(SCH_1):PAGE98_I178@PURE_QUANTA.SCONN288_ADR50017P130CC(CHIPS)':
 'DQS4_A_C': CDS_PINID='DQS4_A_C';
NODE_NAME     J18 56
 '@S9S_MB_2U_LIB.S9S_MB_2U(SCH_1):PAGE99_I178@PURE_QUANTA.SCONN288_ADR50017P087CC(CHIPS)':
 'DQS4_A_C': CDS_PINID='DQS4_A_C';
NET_NAME
'M_A_CPU1_SA_DQS_DN<5>'
 '@S9S_MB_2U_LIB.S9S_MB_2U(SCH_1):M_A_CPU1_SA_DQS_DN'<5>:
 C_SIGNAL='@s9s_mb_2u_lib.s9s_mb_2u(sch_1):m_a_cpu1_sa_dqs_dn(5)';
NODE_NAME     U1 H77
 '@S9S_MB_2U_LIB.S9S_MB_2U(SCH_1):PAGE51_I2@PURE_QUANTA.SOCKET4677_AZIF0045P001C01CS(CHIPS)':
 'DDR0_SA_DQS_DN5': CDS_PINID='DDR0_SA_DQS_DN5';
NODE_NAME     J17 156
 '@S9S_MB_2U_LIB.S9S_MB_2U(SCH_1):PAGE98_I178@PURE_QUANTA.SCONN288_ADR50017P130CC(CHIPS)':
 'DQS5_A_C||TDQS5_A_C||DQS5_A_T||TDQS5_A_T': CDS_PINID='\dqs5_a_c||tdqs5_a_c||dqs5_a_t||tdqs5_a_t\';
NODE_NAME     J18 156
 '@S9S_MB_2U_LIB.S9S_MB_2U(SCH_1):PAGE99_I178@PURE_QUANTA.SCONN288_ADR50017P087CC(CHIPS)':
 'DQS5_A_C||TDQS5_A_C||DQS5_A_T||TDQS5_A_T': CDS_PINID='\dqs5_a_c||tdqs5_a_c||dqs5_a_t||tdqs5_a_t\';
NET_NAME
'M_A_CPU1_SA_DQS_DN<6>'
 '@S9S_MB_2U_LIB.S9S_MB_2U(SCH_1):M_A_CPU1_SA_DQS_DN'<6>:
 C_SIGNAL='@s9s_mb_2u_lib.s9s_mb_2u(sch_1):m_a_cpu1_sa_dqs_dn(6)';
NODE_NAME     U1 P67
 '@S9S_MB_2U_LIB.S9S_MB_2U(SCH_1):PAGE51_I2@PURE_QUANTA.SOCKET4677_AZIF0045P001C01CS(CHIPS)':
 'DDR0_SA_DQS_DN6': CDS_PINID='DDR0_SA_DQS_DN6';
NODE_NAME     J17 167
 '@S9S_MB_2U_LIB.S9S_MB_2U(SCH_1):PAGE98_I178@PURE_QUANTA.SCONN288_ADR50017P130CC(CHIPS)':
 'DQS6_A_C||TDQS6_A_C||DQS6_A_T||TDQS6_A_T': CDS_PINID='\dqs6_a_c||tdqs6_a_c||dqs6_a_t||tdqs6_a_t\';
NODE_NAME     J18 167
 '@S9S_MB_2U_LIB.S9S_MB_2U(SCH_1):PAGE99_I178@PURE_QUANTA.SCONN288_ADR50017P087CC(CHIPS)':
 'DQS6_A_C||TDQS6_A_C||DQS6_A_T||TDQS6_A_T': CDS_PINID='\dqs6_a_c||tdqs6_a_c||dqs6_a_t||tdqs6_a_t\';
NET_NAME
'M_A_CPU1_SA_DQS_DN<7>'
 '@S9S_MB_2U_LIB.S9S_MB_2U(SCH_1):M_A_CPU1_SA_DQS_DN'<7>:
 C_SIGNAL='@s9s_mb_2u_lib.s9s_mb_2u(sch_1):m_a_cpu1_sa_dqs_dn(7)';
NODE_NAME     U1 G70
 '@S9S_MB_2U_LIB.S9S_MB_2U(SCH_1):PAGE51_I2@PURE_QUANTA.SOCKET4677_AZIF0045P001C01CS(CHIPS)':
 'DDR0_SA_DQS_DN7': CDS_PINID='DDR0_SA_DQS_DN7';
NODE_NAME     J17 178
 '@S9S_MB_2U_LIB.S9S_MB_2U(SCH_1):PAGE98_I178@PURE_QUANTA.SCONN288_ADR50017P130CC(CHIPS)':
 'DQS7_A_C||TDQS7_A_C': CDS_PINID='\dqs7_a_c||tdqs7_a_c\';
NODE_NAME     J18 178
 '@S9S_MB_2U_LIB.S9S_MB_2U(SCH_1):PAGE99_I178@PURE_QUANTA.SCONN288_ADR50017P087CC(CHIPS)':
 'DQS7_A_C||TDQS7_A_C': CDS_PINID='\dqs7_a_c||tdqs7_a_c\';
NET_NAME
'M_A_CPU1_SA_DQS_DN<8>'
 '@S9S_MB_2U_LIB.S9S_MB_2U(SCH_1):M_A_CPU1_SA_DQS_DN'<8>:
 C_SIGNAL='@s9s_mb_2u_lib.s9s_mb_2u(sch_1):m_a_cpu1_sa_dqs_dn(8)';
NODE_NAME     U1 G64
 '@S9S_MB_2U_LIB.S9S_MB_2U(SCH_1):PAGE51_I2@PURE_QUANTA.SOCKET4677_AZIF0045P001C01CS(CHIPS)':
 'DDR0_SA_DQS_DN8': CDS_PINID='DDR0_SA_DQS_DN8';
NODE_NAME     J17 189
 '@S9S_MB_2U_LIB.S9S_MB_2U(SCH_1):PAGE98_I178@PURE_QUANTA.SCONN288_ADR50017P130CC(CHIPS)':
 'DQS8_A_C||TDQS8_A_C': CDS_PINID='\dqs8_a_c||tdqs8_a_c\';
NODE_NAME     J18 189
 '@S9S_MB_2U_LIB.S9S_MB_2U(SCH_1):PAGE99_I178@PURE_QUANTA.SCONN288_ADR50017P087CC(CHIPS)':
 'DQS8_A_C||TDQS8_A_C': CDS_PINID='\dqs8_a_c||tdqs8_a_c\';
NET_NAME
'M_A_CPU1_SA_DQS_DN<9>'
 '@S9S_MB_2U_LIB.S9S_MB_2U(SCH_1):M_A_CPU1_SA_DQS_DN'<9>:
 C_SIGNAL='@s9s_mb_2u_lib.s9s_mb_2u(sch_1):m_a_cpu1_sa_dqs_dn(9)';
NODE_NAME     U1 G58
 '@S9S_MB_2U_LIB.S9S_MB_2U(SCH_1):PAGE51_I2@PURE_QUANTA.SOCKET4677_AZIF0045P001C01CS(CHIPS)':
 'DDR0_SA_DQS_DN9': CDS_PINID='DDR0_SA_DQS_DN9';
NODE_NAME     J17 200
 '@S9S_MB_2U_LIB.S9S_MB_2U(SCH_1):PAGE98_I178@PURE_QUANTA.SCONN288_ADR50017P130CC(CHIPS)':
 'DQS9_A_C||TDQS9_A_C': CDS_PINID='\dqs9_a_c||tdqs9_a_c\';
NODE_NAME     J18 200
 '@S9S_MB_2U_LIB.S9S_MB_2U(SCH_1):PAGE99_I178@PURE_QUANTA.SCONN288_ADR50017P087CC(CHIPS)':
 'DQS9_A_C||TDQS9_A_C': CDS_PINID='\dqs9_a_c||tdqs9_a_c\';
NET_NAME
'M_A_CPU1_SA_DQS_DP<0>'
 '@S9S_MB_2U_LIB.S9S_MB_2U(SCH_1):M_A_CPU1_SA_DQS_DP'<0>:
 C_SIGNAL='@s9s_mb_2u_lib.s9s_mb_2u(sch_1):m_a_cpu1_sa_dqs_dp(0)';
NODE_NAME     U1 D77
 '@S9S_MB_2U_LIB.S9S_MB_2U(SCH_1):PAGE51_I2@PURE_QUANTA.SOCKET4677_AZIF0045P001C01CS(CHIPS)':
 'DDR0_SA_DQS_DP0': CDS_PINID='DDR0_SA_DQS_DP0';
NODE_NAME     J17 11
 '@S9S_MB_2U_LIB.S9S_MB_2U(SCH_1):PAGE98_I178@PURE_QUANTA.SCONN288_ADR50017P130CC(CHIPS)':
 'DQS0_A_T': CDS_PINID='DQS0_A_T';
NODE_NAME     J18 11
 '@S9S_MB_2U_LIB.S9S_MB_2U(SCH_1):PAGE99_I178@PURE_QUANTA.SCONN288_ADR50017P087CC(CHIPS)':
 'DQS0_A_T': CDS_PINID='DQS0_A_T';
NET_NAME
'M_A_CPU1_SA_DQS_DP<1>'
 '@S9S_MB_2U_LIB.S9S_MB_2U(SCH_1):M_A_CPU1_SA_DQS_DP'<1>:
 C_SIGNAL='@s9s_mb_2u_lib.s9s_mb_2u(sch_1):m_a_cpu1_sa_dqs_dp(1)';
NODE_NAME     U1 K67
 '@S9S_MB_2U_LIB.S9S_MB_2U(SCH_1):PAGE51_I2@PURE_QUANTA.SOCKET4677_AZIF0045P001C01CS(CHIPS)':
 'DDR0_SA_DQS_DP1': CDS_PINID='DDR0_SA_DQS_DP1';
NODE_NAME     J17 22
 '@S9S_MB_2U_LIB.S9S_MB_2U(SCH_1):PAGE98_I178@PURE_QUANTA.SCONN288_ADR50017P130CC(CHIPS)':
 'DQS1_A_T': CDS_PINID='DQS1_A_T';
NODE_NAME     J18 22
 '@S9S_MB_2U_LIB.S9S_MB_2U(SCH_1):PAGE99_I178@PURE_QUANTA.SCONN288_ADR50017P087CC(CHIPS)':
 'DQS1_A_T': CDS_PINID='DQS1_A_T';
NET_NAME
'M_A_CPU1_SA_DQS_DP<2>'
 '@S9S_MB_2U_LIB.S9S_MB_2U(SCH_1):M_A_CPU1_SA_DQS_DP'<2>:
 C_SIGNAL='@s9s_mb_2u_lib.s9s_mb_2u(sch_1):m_a_cpu1_sa_dqs_dp(2)';
NODE_NAME     U1 C70
 '@S9S_MB_2U_LIB.S9S_MB_2U(SCH_1):PAGE51_I2@PURE_QUANTA.SOCKET4677_AZIF0045P001C01CS(CHIPS)':
 'DDR0_SA_DQS_DP2': CDS_PINID='DDR0_SA_DQS_DP2';
NODE_NAME     J17 33
 '@S9S_MB_2U_LIB.S9S_MB_2U(SCH_1):PAGE98_I178@PURE_QUANTA.SCONN288_ADR50017P130CC(CHIPS)':
 'DQS2_A_T': CDS_PINID='DQS2_A_T';
NODE_NAME     J18 33
 '@S9S_MB_2U_LIB.S9S_MB_2U(SCH_1):PAGE99_I178@PURE_QUANTA.SCONN288_ADR50017P087CC(CHIPS)':
 'DQS2_A_T': CDS_PINID='DQS2_A_T';
NET_NAME
'M_A_CPU1_SA_DQS_DP<3>'
 '@S9S_MB_2U_LIB.S9S_MB_2U(SCH_1):M_A_CPU1_SA_DQS_DP'<3>:
 C_SIGNAL='@s9s_mb_2u_lib.s9s_mb_2u(sch_1):m_a_cpu1_sa_dqs_dp(3)';
NODE_NAME     U1 C64
 '@S9S_MB_2U_LIB.S9S_MB_2U(SCH_1):PAGE51_I2@PURE_QUANTA.SOCKET4677_AZIF0045P001C01CS(CHIPS)':
 'DDR0_SA_DQS_DP3': CDS_PINID='DDR0_SA_DQS_DP3';
NODE_NAME     J17 44
 '@S9S_MB_2U_LIB.S9S_MB_2U(SCH_1):PAGE98_I178@PURE_QUANTA.SCONN288_ADR50017P130CC(CHIPS)':
 'DQS3_A_T': CDS_PINID='DQS3_A_T';
NODE_NAME     J18 44
 '@S9S_MB_2U_LIB.S9S_MB_2U(SCH_1):PAGE99_I178@PURE_QUANTA.SCONN288_ADR50017P087CC(CHIPS)':
 'DQS3_A_T': CDS_PINID='DQS3_A_T';
NET_NAME
'M_A_CPU1_SA_DQS_DP<4>'
 '@S9S_MB_2U_LIB.S9S_MB_2U(SCH_1):M_A_CPU1_SA_DQS_DP'<4>:
 C_SIGNAL='@s9s_mb_2u_lib.s9s_mb_2u(sch_1):m_a_cpu1_sa_dqs_dp(4)';
NODE_NAME     U1 C58
 '@S9S_MB_2U_LIB.S9S_MB_2U(SCH_1):PAGE51_I2@PURE_QUANTA.SOCKET4677_AZIF0045P001C01CS(CHIPS)':
 'DDR0_SA_DQS_DP4': CDS_PINID='DDR0_SA_DQS_DP4';
NODE_NAME     J17 55
 '@S9S_MB_2U_LIB.S9S_MB_2U(SCH_1):PAGE98_I178@PURE_QUANTA.SCONN288_ADR50017P130CC(CHIPS)':
 'DQS4_A_T': CDS_PINID='DQS4_A_T';
NODE_NAME     J18 55
 '@S9S_MB_2U_LIB.S9S_MB_2U(SCH_1):PAGE99_I178@PURE_QUANTA.SCONN288_ADR50017P087CC(CHIPS)':
 'DQS4_A_T': CDS_PINID='DQS4_A_T';
NET_NAME
'M_A_CPU1_SA_DQS_DP<5>'
 '@S9S_MB_2U_LIB.S9S_MB_2U(SCH_1):M_A_CPU1_SA_DQS_DP'<5>:
 C_SIGNAL='@s9s_mb_2u_lib.s9s_mb_2u(sch_1):m_a_cpu1_sa_dqs_dp(5)';
NODE_NAME     U1 F77
 '@S9S_MB_2U_LIB.S9S_MB_2U(SCH_1):PAGE51_I2@PURE_QUANTA.SOCKET4677_AZIF0045P001C01CS(CHIPS)':
 'DDR0_SA_DQS_DP5': CDS_PINID='DDR0_SA_DQS_DP5';
NODE_NAME     J17 157
 '@S9S_MB_2U_LIB.S9S_MB_2U(SCH_1):PAGE98_I178@PURE_QUANTA.SCONN288_ADR50017P130CC(CHIPS)':
 'DQS5_A_T||TDQS5_A_T': CDS_PINID='\dqs5_a_t||tdqs5_a_t\';
NODE_NAME     J18 157
 '@S9S_MB_2U_LIB.S9S_MB_2U(SCH_1):PAGE99_I178@PURE_QUANTA.SCONN288_ADR50017P087CC(CHIPS)':
 'DQS5_A_T||TDQS5_A_T': CDS_PINID='\dqs5_a_t||tdqs5_a_t\';
NET_NAME
'M_A_CPU1_SA_DQS_DP<6>'
 '@S9S_MB_2U_LIB.S9S_MB_2U(SCH_1):M_A_CPU1_SA_DQS_DP'<6>:
 C_SIGNAL='@s9s_mb_2u_lib.s9s_mb_2u(sch_1):m_a_cpu1_sa_dqs_dp(6)';
NODE_NAME     U1 M67
 '@S9S_MB_2U_LIB.S9S_MB_2U(SCH_1):PAGE51_I2@PURE_QUANTA.SOCKET4677_AZIF0045P001C01CS(CHIPS)':
 'DDR0_SA_DQS_DP6': CDS_PINID='DDR0_SA_DQS_DP6';
NODE_NAME     J17 168
 '@S9S_MB_2U_LIB.S9S_MB_2U(SCH_1):PAGE98_I178@PURE_QUANTA.SCONN288_ADR50017P130CC(CHIPS)':
 'DQS6_A_T||TDQS6_A_T': CDS_PINID='\dqs6_a_t||tdqs6_a_t\';
NODE_NAME     J18 168
 '@S9S_MB_2U_LIB.S9S_MB_2U(SCH_1):PAGE99_I178@PURE_QUANTA.SCONN288_ADR50017P087CC(CHIPS)':
 'DQS6_A_T||TDQS6_A_T': CDS_PINID='\dqs6_a_t||tdqs6_a_t\';
NET_NAME
'M_A_CPU1_SA_DQS_DP<7>'
 '@S9S_MB_2U_LIB.S9S_MB_2U(SCH_1):M_A_CPU1_SA_DQS_DP'<7>:
 C_SIGNAL='@s9s_mb_2u_lib.s9s_mb_2u(sch_1):m_a_cpu1_sa_dqs_dp(7)';
NODE_NAME     U1 E70
 '@S9S_MB_2U_LIB.S9S_MB_2U(SCH_1):PAGE51_I2@PURE_QUANTA.SOCKET4677_AZIF0045P001C01CS(CHIPS)':
 'DDR0_SA_DQS_DP7': CDS_PINID='DDR0_SA_DQS_DP7';
NODE_NAME     J17 179
 '@S9S_MB_2U_LIB.S9S_MB_2U(SCH_1):PAGE98_I178@PURE_QUANTA.SCONN288_ADR50017P130CC(CHIPS)':
 'DQS7_A_T||TDQS7_A_T': CDS_PINID='\dqs7_a_t||tdqs7_a_t\';
NODE_NAME     J18 179
 '@S9S_MB_2U_LIB.S9S_MB_2U(SCH_1):PAGE99_I178@PURE_QUANTA.SCONN288_ADR50017P087CC(CHIPS)':
 'DQS7_A_T||TDQS7_A_T': CDS_PINID='\dqs7_a_t||tdqs7_a_t\';
NET_NAME
'M_A_CPU1_SA_DQS_DP<8>'
 '@S9S_MB_2U_LIB.S9S_MB_2U(SCH_1):M_A_CPU1_SA_DQS_DP'<8>:
 C_SIGNAL='@s9s_mb_2u_lib.s9s_mb_2u(sch_1):m_a_cpu1_sa_dqs_dp(8)';
NODE_NAME     U1 E64
 '@S9S_MB_2U_LIB.S9S_MB_2U(SCH_1):PAGE51_I2@PURE_QUANTA.SOCKET4677_AZIF0045P001C01CS(CHIPS)':
 'DDR0_SA_DQS_DP8': CDS_PINID='DDR0_SA_DQS_DP8';
NODE_NAME     J17 190
 '@S9S_MB_2U_LIB.S9S_MB_2U(SCH_1):PAGE98_I178@PURE_QUANTA.SCONN288_ADR50017P130CC(CHIPS)':
 'DQS8_A_T||TDQS8_A_T': CDS_PINID='\dqs8_a_t||tdqs8_a_t\';
NODE_NAME     J18 190
 '@S9S_MB_2U_LIB.S9S_MB_2U(SCH_1):PAGE99_I178@PURE_QUANTA.SCONN288_ADR50017P087CC(CHIPS)':
 'DQS8_A_T||TDQS8_A_T': CDS_PINID='\dqs8_a_t||tdqs8_a_t\';
NET_NAME
'M_A_CPU1_SA_DQS_DP<9>'
 '@S9S_MB_2U_LIB.S9S_MB_2U(SCH_1):M_A_CPU1_SA_DQS_DP'<9>:
 C_SIGNAL='@s9s_mb_2u_lib.s9s_mb_2u(sch_1):m_a_cpu1_sa_dqs_dp(9)';
NODE_NAME     U1 E58
 '@S9S_MB_2U_LIB.S9S_MB_2U(SCH_1):PAGE51_I2@PURE_QUANTA.SOCKET4677_AZIF0045P001C01CS(CHIPS)':
 'DDR0_SA_DQS_DP9': CDS_PINID='DDR0_SA_DQS_DP9';
NODE_NAME     J17 201
 '@S9S_MB_2U_LIB.S9S_MB_2U(SCH_1):PAGE98_I178@PURE_QUANTA.SCONN288_ADR50017P130CC(CHIPS)':
 'DQS9_A_T||TDQS9_A_T': CDS_PINID='\dqs9_a_t||tdqs9_a_t\';
NODE_NAME     J18 201
 '@S9S_MB_2U_LIB.S9S_MB_2U(SCH_1):PAGE99_I178@PURE_QUANTA.SCONN288_ADR50017P087CC(CHIPS)':
 'DQS9_A_T||TDQS9_A_T': CDS_PINID='\dqs9_a_t||tdqs9_a_t\';
NET_NAME
'M_A_CPU1_SA_PAR'
 '@S9S_MB_2U_LIB.S9S_MB_2U(SCH_1):M_A_CPU1_SA_PAR':
 C_SIGNAL='@s9s_mb_2u_lib.s9s_mb_2u(sch_1):m_a_cpu1_sa_par';
NODE_NAME     U1 E48
 '@S9S_MB_2U_LIB.S9S_MB_2U(SCH_1):PAGE51_I2@PURE_QUANTA.SOCKET4677_AZIF0045P001C01CS(CHIPS)':
 'DDR0_SA_PAR': CDS_PINID='DDR0_SA_PAR';
NODE_NAME     J17 74
 '@S9S_MB_2U_LIB.S9S_MB_2U(SCH_1):PAGE98_I12@PURE_QUANTA.SCONN288_ADR50017P130CC(CHIPS)':
 'PAR_A': CDS_PINID='PAR_A';
NODE_NAME     J18 74
 '@S9S_MB_2U_LIB.S9S_MB_2U(SCH_1):PAGE99_I24@PURE_QUANTA.SCONN288_ADR50017P087CC(CHIPS)':
 'PAR_A': CDS_PINID='PAR_A';
NET_NAME
'M_A_CPU1_SA_RSP<0>'
 '@S9S_MB_2U_LIB.S9S_MB_2U(SCH_1):M_A_CPU1_SA_RSP'<0>:
 C_SIGNAL='@s9s_mb_2u_lib.s9s_mb_2u(sch_1):m_a_cpu1_sa_rsp(0)';
NODE_NAME     U1 AT42
 '@S9S_MB_2U_LIB.S9S_MB_2U(SCH_1):PAGE51_I2@PURE_QUANTA.SOCKET4677_AZIF0045P001C01CS(CHIPS)':
 'DDR0_A_RSP0': CDS_PINID='DDR0_A_RSP0';
NODE_NAME     J17 86
 '@S9S_MB_2U_LIB.S9S_MB_2U(SCH_1):PAGE98_I12@PURE_QUANTA.SCONN288_ADR50017P130CC(CHIPS)':
 'LBD||RSP_A_N': CDS_PINID='\lbd||rsp_a_n\';
NET_NAME
'M_A_CPU1_SA_RSP<1>'
 '@S9S_MB_2U_LIB.S9S_MB_2U(SCH_1):M_A_CPU1_SA_RSP'<1>:
 C_SIGNAL='@s9s_mb_2u_lib.s9s_mb_2u(sch_1):m_a_cpu1_sa_rsp(1)';
NODE_NAME     U1 AU43
 '@S9S_MB_2U_LIB.S9S_MB_2U(SCH_1):PAGE51_I2@PURE_QUANTA.SOCKET4677_AZIF0045P001C01CS(CHIPS)':
 'DDR0_A_RSP1': CDS_PINID='DDR0_A_RSP1';
NODE_NAME     J18 86
 '@S9S_MB_2U_LIB.S9S_MB_2U(SCH_1):PAGE99_I24@PURE_QUANTA.SCONN288_ADR50017P087CC(CHIPS)':
 'LBD||RSP_A_N': CDS_PINID='\lbd||rsp_a_n\';
NET_NAME
'M_A_CPU1_SB_CA<0>'
 '@S9S_MB_2U_LIB.S9S_MB_2U(SCH_1):M_A_CPU1_SB_CA'<0>:
 C_SIGNAL='@s9s_mb_2u_lib.s9s_mb_2u(sch_1):m_a_cpu1_sb_ca(0)';
NODE_NAME     U1 E43
 '@S9S_MB_2U_LIB.S9S_MB_2U(SCH_1):PAGE51_I2@PURE_QUANTA.SOCKET4677_AZIF0045P001C01CS(CHIPS)':
 'DDR0_SB_CA0': CDS_PINID='DDR0_SB_CA0';
NODE_NAME     J17 76
 '@S9S_MB_2U_LIB.S9S_MB_2U(SCH_1):PAGE98_I12@PURE_QUANTA.SCONN288_ADR50017P130CC(CHIPS)':
 'CA0_B': CDS_PINID='CA0_B';
NODE_NAME     J18 76
 '@S9S_MB_2U_LIB.S9S_MB_2U(SCH_1):PAGE99_I24@PURE_QUANTA.SCONN288_ADR50017P087CC(CHIPS)':
 'CA0_B': CDS_PINID='CA0_B';
NET_NAME
'M_A_CPU1_SB_CA<1>'
 '@S9S_MB_2U_LIB.S9S_MB_2U(SCH_1):M_A_CPU1_SB_CA'<1>:
 C_SIGNAL='@s9s_mb_2u_lib.s9s_mb_2u(sch_1):m_a_cpu1_sb_ca(1)';
NODE_NAME     U1 F44
 '@S9S_MB_2U_LIB.S9S_MB_2U(SCH_1):PAGE51_I2@PURE_QUANTA.SOCKET4677_AZIF0045P001C01CS(CHIPS)':
 'DDR0_SB_CA1': CDS_PINID='DDR0_SB_CA1';
NODE_NAME     J17 221
 '@S9S_MB_2U_LIB.S9S_MB_2U(SCH_1):PAGE98_I12@PURE_QUANTA.SCONN288_ADR50017P130CC(CHIPS)':
 'CA1_B': CDS_PINID='CA1_B';
NODE_NAME     J18 221
 '@S9S_MB_2U_LIB.S9S_MB_2U(SCH_1):PAGE99_I24@PURE_QUANTA.SCONN288_ADR50017P087CC(CHIPS)':
 'CA1_B': CDS_PINID='CA1_B';
NET_NAME
'M_A_CPU1_SB_CA<2>'
 '@S9S_MB_2U_LIB.S9S_MB_2U(SCH_1):M_A_CPU1_SB_CA'<2>:
 C_SIGNAL='@s9s_mb_2u_lib.s9s_mb_2u(sch_1):m_a_cpu1_sb_ca(2)';
NODE_NAME     U1 C41
 '@S9S_MB_2U_LIB.S9S_MB_2U(SCH_1):PAGE51_I2@PURE_QUANTA.SOCKET4677_AZIF0045P001C01CS(CHIPS)':
 'DDR0_SB_CA2': CDS_PINID='DDR0_SB_CA2';
NODE_NAME     J17 78
 '@S9S_MB_2U_LIB.S9S_MB_2U(SCH_1):PAGE98_I12@PURE_QUANTA.SCONN288_ADR50017P130CC(CHIPS)':
 'CA2_B': CDS_PINID='CA2_B';
NODE_NAME     J18 78
 '@S9S_MB_2U_LIB.S9S_MB_2U(SCH_1):PAGE99_I24@PURE_QUANTA.SCONN288_ADR50017P087CC(CHIPS)':
 'CA2_B': CDS_PINID='CA2_B';
NET_NAME
'M_A_CPU1_SB_CA<3>'
 '@S9S_MB_2U_LIB.S9S_MB_2U(SCH_1):M_A_CPU1_SB_CA'<3>:
 C_SIGNAL='@s9s_mb_2u_lib.s9s_mb_2u(sch_1):m_a_cpu1_sb_ca(3)';
NODE_NAME     U1 E41
 '@S9S_MB_2U_LIB.S9S_MB_2U(SCH_1):PAGE51_I2@PURE_QUANTA.SOCKET4677_AZIF0045P001C01CS(CHIPS)':
 'DDR0_SB_CA3': CDS_PINID='DDR0_SB_CA3';
NODE_NAME     J17 223
 '@S9S_MB_2U_LIB.S9S_MB_2U(SCH_1):PAGE98_I12@PURE_QUANTA.SCONN288_ADR50017P130CC(CHIPS)':
 'CA3_B': CDS_PINID='CA3_B';
NODE_NAME     J18 223
 '@S9S_MB_2U_LIB.S9S_MB_2U(SCH_1):PAGE99_I24@PURE_QUANTA.SCONN288_ADR50017P087CC(CHIPS)':
 'CA3_B': CDS_PINID='CA3_B';
NET_NAME
'M_A_CPU1_SB_CA<4>'
 '@S9S_MB_2U_LIB.S9S_MB_2U(SCH_1):M_A_CPU1_SB_CA'<4>:
 C_SIGNAL='@s9s_mb_2u_lib.s9s_mb_2u(sch_1):m_a_cpu1_sb_ca(4)';
NODE_NAME     U1 B40
 '@S9S_MB_2U_LIB.S9S_MB_2U(SCH_1):PAGE51_I2@PURE_QUANTA.SOCKET4677_AZIF0045P001C01CS(CHIPS)':
 'DDR0_SB_CA4': CDS_PINID='DDR0_SB_CA4';
NODE_NAME     J17 80
 '@S9S_MB_2U_LIB.S9S_MB_2U(SCH_1):PAGE98_I12@PURE_QUANTA.SCONN288_ADR50017P130CC(CHIPS)':
 'CA4_B': CDS_PINID='CA4_B';
NODE_NAME     J18 80
 '@S9S_MB_2U_LIB.S9S_MB_2U(SCH_1):PAGE99_I24@PURE_QUANTA.SCONN288_ADR50017P087CC(CHIPS)':
 'CA4_B': CDS_PINID='CA4_B';
NET_NAME
'M_A_CPU1_SB_CA<5>'
 '@S9S_MB_2U_LIB.S9S_MB_2U(SCH_1):M_A_CPU1_SB_CA'<5>:
 C_SIGNAL='@s9s_mb_2u_lib.s9s_mb_2u(sch_1):m_a_cpu1_sb_ca(5)';
NODE_NAME     U1 F40
 '@S9S_MB_2U_LIB.S9S_MB_2U(SCH_1):PAGE51_I2@PURE_QUANTA.SOCKET4677_AZIF0045P001C01CS(CHIPS)':
 'DDR0_SB_CA5': CDS_PINID='DDR0_SB_CA5';
NODE_NAME     J17 225
 '@S9S_MB_2U_LIB.S9S_MB_2U(SCH_1):PAGE98_I12@PURE_QUANTA.SCONN288_ADR50017P130CC(CHIPS)':
 'CA5_B': CDS_PINID='CA5_B';
NODE_NAME     J18 225
 '@S9S_MB_2U_LIB.S9S_MB_2U(SCH_1):PAGE99_I24@PURE_QUANTA.SCONN288_ADR50017P087CC(CHIPS)':
 'CA5_B': CDS_PINID='CA5_B';
NET_NAME
'M_A_CPU1_SB_CA<6>'
 '@S9S_MB_2U_LIB.S9S_MB_2U(SCH_1):M_A_CPU1_SB_CA'<6>:
 C_SIGNAL='@s9s_mb_2u_lib.s9s_mb_2u(sch_1):m_a_cpu1_sb_ca(6)';
NODE_NAME     U1 A39
 '@S9S_MB_2U_LIB.S9S_MB_2U(SCH_1):PAGE51_I2@PURE_QUANTA.SOCKET4677_AZIF0045P001C01CS(CHIPS)':
 'DDR0_SB_CA6': CDS_PINID='DDR0_SB_CA6';
NODE_NAME     J17 82
 '@S9S_MB_2U_LIB.S9S_MB_2U(SCH_1):PAGE98_I12@PURE_QUANTA.SCONN288_ADR50017P130CC(CHIPS)':
 'CA6_B': CDS_PINID='CA6_B';
NODE_NAME     J18 82
 '@S9S_MB_2U_LIB.S9S_MB_2U(SCH_1):PAGE99_I24@PURE_QUANTA.SCONN288_ADR50017P087CC(CHIPS)':
 'CA6_B': CDS_PINID='CA6_B';
NET_NAME
'M_A_CPU1_SB_CB<0>'
 '@S9S_MB_2U_LIB.S9S_MB_2U(SCH_1):M_A_CPU1_SB_CB'<0>:
 C_SIGNAL='@s9s_mb_2u_lib.s9s_mb_2u(sch_1):m_a_cpu1_sb_cb(0)';
NODE_NAME     U1 B32
 '@S9S_MB_2U_LIB.S9S_MB_2U(SCH_1):PAGE51_I2@PURE_QUANTA.SOCKET4677_AZIF0045P001C01CS(CHIPS)':
 'DDR0_SB_ECC0': CDS_PINID='DDR0_SB_ECC0';
NODE_NAME     J17 96
 '@S9S_MB_2U_LIB.S9S_MB_2U(SCH_1):PAGE98_I12@PURE_QUANTA.SCONN288_ADR50017P130CC(CHIPS)':
 'CB0_B': CDS_PINID='CB0_B';
NODE_NAME     J18 96
 '@S9S_MB_2U_LIB.S9S_MB_2U(SCH_1):PAGE99_I24@PURE_QUANTA.SCONN288_ADR50017P087CC(CHIPS)':
 'CB0_B': CDS_PINID='CB0_B';
NET_NAME
'M_A_CPU1_SB_CB<1>'
 '@S9S_MB_2U_LIB.S9S_MB_2U(SCH_1):M_A_CPU1_SB_CB'<1>:
 C_SIGNAL='@s9s_mb_2u_lib.s9s_mb_2u(sch_1):m_a_cpu1_sb_cb(1)';
NODE_NAME     U1 C31
 '@S9S_MB_2U_LIB.S9S_MB_2U(SCH_1):PAGE51_I2@PURE_QUANTA.SOCKET4677_AZIF0045P001C01CS(CHIPS)':
 'DDR0_SB_ECC1': CDS_PINID='DDR0_SB_ECC1';
NODE_NAME     J17 98
 '@S9S_MB_2U_LIB.S9S_MB_2U(SCH_1):PAGE98_I12@PURE_QUANTA.SCONN288_ADR50017P130CC(CHIPS)':
 'CB1_B': CDS_PINID='CB1_B';
NODE_NAME     J18 98
 '@S9S_MB_2U_LIB.S9S_MB_2U(SCH_1):PAGE99_I24@PURE_QUANTA.SCONN288_ADR50017P087CC(CHIPS)':
 'CB1_B': CDS_PINID='CB1_B';
NET_NAME
'M_A_CPU1_SB_CB<2>'
 '@S9S_MB_2U_LIB.S9S_MB_2U(SCH_1):M_A_CPU1_SB_CB'<2>:
 C_SIGNAL='@s9s_mb_2u_lib.s9s_mb_2u(sch_1):m_a_cpu1_sb_cb(2)';
NODE_NAME     U1 F32
 '@S9S_MB_2U_LIB.S9S_MB_2U(SCH_1):PAGE51_I2@PURE_QUANTA.SOCKET4677_AZIF0045P001C01CS(CHIPS)':
 'DDR0_SB_ECC2': CDS_PINID='DDR0_SB_ECC2';
NODE_NAME     J17 241
 '@S9S_MB_2U_LIB.S9S_MB_2U(SCH_1):PAGE98_I12@PURE_QUANTA.SCONN288_ADR50017P130CC(CHIPS)':
 'CB2_B': CDS_PINID='CB2_B';
NODE_NAME     J18 241
 '@S9S_MB_2U_LIB.S9S_MB_2U(SCH_1):PAGE99_I24@PURE_QUANTA.SCONN288_ADR50017P087CC(CHIPS)':
 'CB2_B': CDS_PINID='CB2_B';
NET_NAME
'M_A_CPU1_SB_CB<3>'
 '@S9S_MB_2U_LIB.S9S_MB_2U(SCH_1):M_A_CPU1_SB_CB'<3>:
 C_SIGNAL='@s9s_mb_2u_lib.s9s_mb_2u(sch_1):m_a_cpu1_sb_cb(3)';
NODE_NAME     U1 E31
 '@S9S_MB_2U_LIB.S9S_MB_2U(SCH_1):PAGE51_I2@PURE_QUANTA.SOCKET4677_AZIF0045P001C01CS(CHIPS)':
 'DDR0_SB_ECC3': CDS_PINID='DDR0_SB_ECC3';
NODE_NAME     J17 243
 '@S9S_MB_2U_LIB.S9S_MB_2U(SCH_1):PAGE98_I12@PURE_QUANTA.SCONN288_ADR50017P130CC(CHIPS)':
 'CB3_B': CDS_PINID='CB3_B';
NODE_NAME     J18 243
 '@S9S_MB_2U_LIB.S9S_MB_2U(SCH_1):PAGE99_I24@PURE_QUANTA.SCONN288_ADR50017P087CC(CHIPS)':
 'CB3_B': CDS_PINID='CB3_B';
NET_NAME
'M_A_CPU1_SB_CB<4>'
 '@S9S_MB_2U_LIB.S9S_MB_2U(SCH_1):M_A_CPU1_SB_CB'<4>:
 C_SIGNAL='@s9s_mb_2u_lib.s9s_mb_2u(sch_1):m_a_cpu1_sb_cb(4)';
NODE_NAME     U1 C35
 '@S9S_MB_2U_LIB.S9S_MB_2U(SCH_1):PAGE51_I2@PURE_QUANTA.SOCKET4677_AZIF0045P001C01CS(CHIPS)':
 'DDR0_SB_ECC4': CDS_PINID='DDR0_SB_ECC4';
NODE_NAME     J17 89
 '@S9S_MB_2U_LIB.S9S_MB_2U(SCH_1):PAGE98_I12@PURE_QUANTA.SCONN288_ADR50017P130CC(CHIPS)':
 'CB4_B': CDS_PINID='CB4_B';
NODE_NAME     J18 89
 '@S9S_MB_2U_LIB.S9S_MB_2U(SCH_1):PAGE99_I24@PURE_QUANTA.SCONN288_ADR50017P087CC(CHIPS)':
 'CB4_B': CDS_PINID='CB4_B';
NET_NAME
'M_A_CPU1_SB_CB<5>'
 '@S9S_MB_2U_LIB.S9S_MB_2U(SCH_1):M_A_CPU1_SB_CB'<5>:
 C_SIGNAL='@s9s_mb_2u_lib.s9s_mb_2u(sch_1):m_a_cpu1_sb_cb(5)';
NODE_NAME     U1 B34
 '@S9S_MB_2U_LIB.S9S_MB_2U(SCH_1):PAGE51_I2@PURE_QUANTA.SOCKET4677_AZIF0045P001C01CS(CHIPS)':
 'DDR0_SB_ECC5': CDS_PINID='DDR0_SB_ECC5';
NODE_NAME     J17 91
 '@S9S_MB_2U_LIB.S9S_MB_2U(SCH_1):PAGE98_I12@PURE_QUANTA.SCONN288_ADR50017P130CC(CHIPS)':
 'CB5_B': CDS_PINID='CB5_B';
NODE_NAME     J18 91
 '@S9S_MB_2U_LIB.S9S_MB_2U(SCH_1):PAGE99_I24@PURE_QUANTA.SCONN288_ADR50017P087CC(CHIPS)':
 'CB5_B': CDS_PINID='CB5_B';
NET_NAME
'M_A_CPU1_SB_CB<6>'
 '@S9S_MB_2U_LIB.S9S_MB_2U(SCH_1):M_A_CPU1_SB_CB'<6>:
 C_SIGNAL='@s9s_mb_2u_lib.s9s_mb_2u(sch_1):m_a_cpu1_sb_cb(6)';
NODE_NAME     U1 E35
 '@S9S_MB_2U_LIB.S9S_MB_2U(SCH_1):PAGE51_I2@PURE_QUANTA.SOCKET4677_AZIF0045P001C01CS(CHIPS)':
 'DDR0_SB_ECC6': CDS_PINID='DDR0_SB_ECC6';
NODE_NAME     J17 234
 '@S9S_MB_2U_LIB.S9S_MB_2U(SCH_1):PAGE98_I12@PURE_QUANTA.SCONN288_ADR50017P130CC(CHIPS)':
 'CB6_B': CDS_PINID='CB6_B';
NODE_NAME     J18 234
 '@S9S_MB_2U_LIB.S9S_MB_2U(SCH_1):PAGE99_I24@PURE_QUANTA.SCONN288_ADR50017P087CC(CHIPS)':
 'CB6_B': CDS_PINID='CB6_B';
NET_NAME
'M_A_CPU1_SB_CB<7>'
 '@S9S_MB_2U_LIB.S9S_MB_2U(SCH_1):M_A_CPU1_SB_CB'<7>:
 C_SIGNAL='@s9s_mb_2u_lib.s9s_mb_2u(sch_1):m_a_cpu1_sb_cb(7)';
NODE_NAME     U1 F34
 '@S9S_MB_2U_LIB.S9S_MB_2U(SCH_1):PAGE51_I2@PURE_QUANTA.SOCKET4677_AZIF0045P001C01CS(CHIPS)':
 'DDR0_SB_ECC7': CDS_PINID='DDR0_SB_ECC7';
NODE_NAME     J17 236
 '@S9S_MB_2U_LIB.S9S_MB_2U(SCH_1):PAGE98_I12@PURE_QUANTA.SCONN288_ADR50017P130CC(CHIPS)':
 'CB7_B': CDS_PINID='CB7_B';
NODE_NAME     J18 236
 '@S9S_MB_2U_LIB.S9S_MB_2U(SCH_1):PAGE99_I24@PURE_QUANTA.SCONN288_ADR50017P087CC(CHIPS)':
 'CB7_B': CDS_PINID='CB7_B';
NET_NAME
'M_A_CPU1_SB_CS_N<0>'
 '@S9S_MB_2U_LIB.S9S_MB_2U(SCH_1):M_A_CPU1_SB_CS_N'<0>:
 C_SIGNAL='@s9s_mb_2u_lib.s9s_mb_2u(sch_1):m_a_cpu1_sb_cs_n(0)';
NODE_NAME     U1 B38
 '@S9S_MB_2U_LIB.S9S_MB_2U(SCH_1):PAGE51_I2@PURE_QUANTA.SOCKET4677_AZIF0045P001C01CS(CHIPS)':
 'DDR0_SB_CS_N0': CDS_PINID='DDR0_SB_CS_N0';
NODE_NAME     J17 84
 '@S9S_MB_2U_LIB.S9S_MB_2U(SCH_1):PAGE98_I12@PURE_QUANTA.SCONN288_ADR50017P130CC(CHIPS)':
 'CS0_B_N': CDS_PINID='CS0_B_N';
NET_NAME
'M_A_CPU1_SB_CS_N<1>'
 '@S9S_MB_2U_LIB.S9S_MB_2U(SCH_1):M_A_CPU1_SB_CS_N'<1>:
 C_SIGNAL='@s9s_mb_2u_lib.s9s_mb_2u(sch_1):m_a_cpu1_sb_cs_n(1)';
NODE_NAME     U1 C37
 '@S9S_MB_2U_LIB.S9S_MB_2U(SCH_1):PAGE51_I2@PURE_QUANTA.SOCKET4677_AZIF0045P001C01CS(CHIPS)':
 'DDR0_SB_CS_N1': CDS_PINID='DDR0_SB_CS_N1';
NODE_NAME     J17 229
 '@S9S_MB_2U_LIB.S9S_MB_2U(SCH_1):PAGE98_I12@PURE_QUANTA.SCONN288_ADR50017P130CC(CHIPS)':
 'CS1_B_N': CDS_PINID='CS1_B_N';
NET_NAME
'M_A_CPU1_SB_CS_N<2>'
 '@S9S_MB_2U_LIB.S9S_MB_2U(SCH_1):M_A_CPU1_SB_CS_N'<2>:
 C_SIGNAL='@s9s_mb_2u_lib.s9s_mb_2u(sch_1):m_a_cpu1_sb_cs_n(2)';
NODE_NAME     U1 F38
 '@S9S_MB_2U_LIB.S9S_MB_2U(SCH_1):PAGE51_I2@PURE_QUANTA.SOCKET4677_AZIF0045P001C01CS(CHIPS)':
 'DDR0_SB_CS_N2': CDS_PINID='DDR0_SB_CS_N2';
NODE_NAME     J18 84
 '@S9S_MB_2U_LIB.S9S_MB_2U(SCH_1):PAGE99_I24@PURE_QUANTA.SCONN288_ADR50017P087CC(CHIPS)':
 'CS0_B_N': CDS_PINID='CS0_B_N';
NET_NAME
'M_A_CPU1_SB_CS_N<3>'
 '@S9S_MB_2U_LIB.S9S_MB_2U(SCH_1):M_A_CPU1_SB_CS_N'<3>:
 C_SIGNAL='@s9s_mb_2u_lib.s9s_mb_2u(sch_1):m_a_cpu1_sb_cs_n(3)';
NODE_NAME     U1 E37
 '@S9S_MB_2U_LIB.S9S_MB_2U(SCH_1):PAGE51_I2@PURE_QUANTA.SOCKET4677_AZIF0045P001C01CS(CHIPS)':
 'DDR0_SB_CS_N3': CDS_PINID='DDR0_SB_CS_N3';
NODE_NAME     J18 229
 '@S9S_MB_2U_LIB.S9S_MB_2U(SCH_1):PAGE99_I24@PURE_QUANTA.SCONN288_ADR50017P087CC(CHIPS)':
 'CS1_B_N': CDS_PINID='CS1_B_N';
NET_NAME
'M_A_CPU1_SB_DQ<0>'
 '@S9S_MB_2U_LIB.S9S_MB_2U(SCH_1):M_A_CPU1_SB_DQ'<0>:
 C_SIGNAL='@s9s_mb_2u_lib.s9s_mb_2u(sch_1):m_a_cpu1_sb_dq(0)';
NODE_NAME     U1 K32
 '@S9S_MB_2U_LIB.S9S_MB_2U(SCH_1):PAGE51_I2@PURE_QUANTA.SOCKET4677_AZIF0045P001C01CS(CHIPS)':
 'DDR0_SB_DQ0': CDS_PINID='DDR0_SB_DQ0';
NODE_NAME     J17 100
 '@S9S_MB_2U_LIB.S9S_MB_2U(SCH_1):PAGE98_I12@PURE_QUANTA.SCONN288_ADR50017P130CC(CHIPS)':
 'DQ0_B': CDS_PINID='DQ0_B';
NODE_NAME     J18 100
 '@S9S_MB_2U_LIB.S9S_MB_2U(SCH_1):PAGE99_I24@PURE_QUANTA.SCONN288_ADR50017P087CC(CHIPS)':
 'DQ0_B': CDS_PINID='DQ0_B';
NET_NAME
'M_A_CPU1_SB_DQ<10>'
 '@S9S_MB_2U_LIB.S9S_MB_2U(SCH_1):M_A_CPU1_SB_DQ'<10>:
 C_SIGNAL='@s9s_mb_2u_lib.s9s_mb_2u(sch_1):m_a_cpu1_sb_dq(10)';
NODE_NAME     U1 E29
 '@S9S_MB_2U_LIB.S9S_MB_2U(SCH_1):PAGE51_I2@PURE_QUANTA.SOCKET4677_AZIF0045P001C01CS(CHIPS)':
 'DDR0_SB_DQ10': CDS_PINID='DDR0_SB_DQ10';
NODE_NAME     J17 256
 '@S9S_MB_2U_LIB.S9S_MB_2U(SCH_1):PAGE98_I12@PURE_QUANTA.SCONN288_ADR50017P130CC(CHIPS)':
 'DQ10_B': CDS_PINID='DQ10_B';
NODE_NAME     J18 256
 '@S9S_MB_2U_LIB.S9S_MB_2U(SCH_1):PAGE99_I24@PURE_QUANTA.SCONN288_ADR50017P087CC(CHIPS)':
 'DQ10_B': CDS_PINID='DQ10_B';
NET_NAME
'M_A_CPU1_SB_DQ<11>'
 '@S9S_MB_2U_LIB.S9S_MB_2U(SCH_1):M_A_CPU1_SB_DQ'<11>:
 C_SIGNAL='@s9s_mb_2u_lib.s9s_mb_2u(sch_1):m_a_cpu1_sb_dq(11)';
NODE_NAME     U1 F28
 '@S9S_MB_2U_LIB.S9S_MB_2U(SCH_1):PAGE51_I2@PURE_QUANTA.SOCKET4677_AZIF0045P001C01CS(CHIPS)':
 'DDR0_SB_DQ11': CDS_PINID='DDR0_SB_DQ11';
NODE_NAME     J17 258
 '@S9S_MB_2U_LIB.S9S_MB_2U(SCH_1):PAGE98_I12@PURE_QUANTA.SCONN288_ADR50017P130CC(CHIPS)':
 'DQ11_B': CDS_PINID='DQ11_B';
NODE_NAME     J18 258
 '@S9S_MB_2U_LIB.S9S_MB_2U(SCH_1):PAGE99_I24@PURE_QUANTA.SCONN288_ADR50017P087CC(CHIPS)':
 'DQ11_B': CDS_PINID='DQ11_B';
NET_NAME
'M_A_CPU1_SB_DQ<12>'
 '@S9S_MB_2U_LIB.S9S_MB_2U(SCH_1):M_A_CPU1_SB_DQ'<12>:
 C_SIGNAL='@s9s_mb_2u_lib.s9s_mb_2u(sch_1):m_a_cpu1_sb_dq(12)';
NODE_NAME     U1 B26
 '@S9S_MB_2U_LIB.S9S_MB_2U(SCH_1):PAGE51_I2@PURE_QUANTA.SOCKET4677_AZIF0045P001C01CS(CHIPS)':
 'DDR0_SB_DQ12': CDS_PINID='DDR0_SB_DQ12';
NODE_NAME     J17 118
 '@S9S_MB_2U_LIB.S9S_MB_2U(SCH_1):PAGE98_I12@PURE_QUANTA.SCONN288_ADR50017P130CC(CHIPS)':
 'DQ12_B': CDS_PINID='DQ12_B';
NODE_NAME     J18 118
 '@S9S_MB_2U_LIB.S9S_MB_2U(SCH_1):PAGE99_I24@PURE_QUANTA.SCONN288_ADR50017P087CC(CHIPS)':
 'DQ12_B': CDS_PINID='DQ12_B';
NET_NAME
'M_A_CPU1_SB_DQ<13>'
 '@S9S_MB_2U_LIB.S9S_MB_2U(SCH_1):M_A_CPU1_SB_DQ'<13>:
 C_SIGNAL='@s9s_mb_2u_lib.s9s_mb_2u(sch_1):m_a_cpu1_sb_dq(13)';
NODE_NAME     U1 C25
 '@S9S_MB_2U_LIB.S9S_MB_2U(SCH_1):PAGE51_I2@PURE_QUANTA.SOCKET4677_AZIF0045P001C01CS(CHIPS)':
 'DDR0_SB_DQ13': CDS_PINID='DDR0_SB_DQ13';
NODE_NAME     J17 120
 '@S9S_MB_2U_LIB.S9S_MB_2U(SCH_1):PAGE98_I12@PURE_QUANTA.SCONN288_ADR50017P130CC(CHIPS)':
 'DQ13_B': CDS_PINID='DQ13_B';
NODE_NAME     J18 120
 '@S9S_MB_2U_LIB.S9S_MB_2U(SCH_1):PAGE99_I24@PURE_QUANTA.SCONN288_ADR50017P087CC(CHIPS)':
 'DQ13_B': CDS_PINID='DQ13_B';
NET_NAME
'M_A_CPU1_SB_DQ<14>'
 '@S9S_MB_2U_LIB.S9S_MB_2U(SCH_1):M_A_CPU1_SB_DQ'<14>:
 C_SIGNAL='@s9s_mb_2u_lib.s9s_mb_2u(sch_1):m_a_cpu1_sb_dq(14)';
NODE_NAME     U1 F26
 '@S9S_MB_2U_LIB.S9S_MB_2U(SCH_1):PAGE51_I2@PURE_QUANTA.SOCKET4677_AZIF0045P001C01CS(CHIPS)':
 'DDR0_SB_DQ14': CDS_PINID='DDR0_SB_DQ14';
NODE_NAME     J17 263
 '@S9S_MB_2U_LIB.S9S_MB_2U(SCH_1):PAGE98_I12@PURE_QUANTA.SCONN288_ADR50017P130CC(CHIPS)':
 'DQ14_B': CDS_PINID='DQ14_B';
NODE_NAME     J18 263
 '@S9S_MB_2U_LIB.S9S_MB_2U(SCH_1):PAGE99_I24@PURE_QUANTA.SCONN288_ADR50017P087CC(CHIPS)':
 'DQ14_B': CDS_PINID='DQ14_B';
NET_NAME
'M_A_CPU1_SB_DQ<15>'
 '@S9S_MB_2U_LIB.S9S_MB_2U(SCH_1):M_A_CPU1_SB_DQ'<15>:
 C_SIGNAL='@s9s_mb_2u_lib.s9s_mb_2u(sch_1):m_a_cpu1_sb_dq(15)';
NODE_NAME     U1 E25
 '@S9S_MB_2U_LIB.S9S_MB_2U(SCH_1):PAGE51_I2@PURE_QUANTA.SOCKET4677_AZIF0045P001C01CS(CHIPS)':
 'DDR0_SB_DQ15': CDS_PINID='DDR0_SB_DQ15';
NODE_NAME     J17 265
 '@S9S_MB_2U_LIB.S9S_MB_2U(SCH_1):PAGE98_I12@PURE_QUANTA.SCONN288_ADR50017P130CC(CHIPS)':
 'DQ15_B': CDS_PINID='DQ15_B';
NODE_NAME     J18 265
 '@S9S_MB_2U_LIB.S9S_MB_2U(SCH_1):PAGE99_I24@PURE_QUANTA.SCONN288_ADR50017P087CC(CHIPS)':
 'DQ15_B': CDS_PINID='DQ15_B';
NET_NAME
'M_A_CPU1_SB_DQ<16>'
 '@S9S_MB_2U_LIB.S9S_MB_2U(SCH_1):M_A_CPU1_SB_DQ'<16>:
 C_SIGNAL='@s9s_mb_2u_lib.s9s_mb_2u(sch_1):m_a_cpu1_sb_dq(16)';
NODE_NAME     U1 C23
 '@S9S_MB_2U_LIB.S9S_MB_2U(SCH_1):PAGE51_I2@PURE_QUANTA.SOCKET4677_AZIF0045P001C01CS(CHIPS)':
 'DDR0_SB_DQ16': CDS_PINID='DDR0_SB_DQ16';
NODE_NAME     J17 122
 '@S9S_MB_2U_LIB.S9S_MB_2U(SCH_1):PAGE98_I12@PURE_QUANTA.SCONN288_ADR50017P130CC(CHIPS)':
 'DQ16_B': CDS_PINID='DQ16_B';
NODE_NAME     J18 122
 '@S9S_MB_2U_LIB.S9S_MB_2U(SCH_1):PAGE99_I24@PURE_QUANTA.SCONN288_ADR50017P087CC(CHIPS)':
 'DQ16_B': CDS_PINID='DQ16_B';
NET_NAME
'M_A_CPU1_SB_DQ<17>'
 '@S9S_MB_2U_LIB.S9S_MB_2U(SCH_1):M_A_CPU1_SB_DQ'<17>:
 C_SIGNAL='@s9s_mb_2u_lib.s9s_mb_2u(sch_1):m_a_cpu1_sb_dq(17)';
NODE_NAME     U1 B22
 '@S9S_MB_2U_LIB.S9S_MB_2U(SCH_1):PAGE51_I2@PURE_QUANTA.SOCKET4677_AZIF0045P001C01CS(CHIPS)':
 'DDR0_SB_DQ17': CDS_PINID='DDR0_SB_DQ17';
NODE_NAME     J17 124
 '@S9S_MB_2U_LIB.S9S_MB_2U(SCH_1):PAGE98_I12@PURE_QUANTA.SCONN288_ADR50017P130CC(CHIPS)':
 'DQ17_B': CDS_PINID='DQ17_B';
NODE_NAME     J18 124
 '@S9S_MB_2U_LIB.S9S_MB_2U(SCH_1):PAGE99_I24@PURE_QUANTA.SCONN288_ADR50017P087CC(CHIPS)':
 'DQ17_B': CDS_PINID='DQ17_B';
NET_NAME
'M_A_CPU1_SB_DQ<18>'
 '@S9S_MB_2U_LIB.S9S_MB_2U(SCH_1):M_A_CPU1_SB_DQ'<18>:
 C_SIGNAL='@s9s_mb_2u_lib.s9s_mb_2u(sch_1):m_a_cpu1_sb_dq(18)';
NODE_NAME     U1 E23
 '@S9S_MB_2U_LIB.S9S_MB_2U(SCH_1):PAGE51_I2@PURE_QUANTA.SOCKET4677_AZIF0045P001C01CS(CHIPS)':
 'DDR0_SB_DQ18': CDS_PINID='DDR0_SB_DQ18';
NODE_NAME     J17 267
 '@S9S_MB_2U_LIB.S9S_MB_2U(SCH_1):PAGE98_I12@PURE_QUANTA.SCONN288_ADR50017P130CC(CHIPS)':
 'DQ18_B': CDS_PINID='DQ18_B';
NODE_NAME     J18 267
 '@S9S_MB_2U_LIB.S9S_MB_2U(SCH_1):PAGE99_I24@PURE_QUANTA.SCONN288_ADR50017P087CC(CHIPS)':
 'DQ18_B': CDS_PINID='DQ18_B';
NET_NAME
'M_A_CPU1_SB_DQ<19>'
 '@S9S_MB_2U_LIB.S9S_MB_2U(SCH_1):M_A_CPU1_SB_DQ'<19>:
 C_SIGNAL='@s9s_mb_2u_lib.s9s_mb_2u(sch_1):m_a_cpu1_sb_dq(19)';
NODE_NAME     U1 F22
 '@S9S_MB_2U_LIB.S9S_MB_2U(SCH_1):PAGE51_I2@PURE_QUANTA.SOCKET4677_AZIF0045P001C01CS(CHIPS)':
 'DDR0_SB_DQ19': CDS_PINID='DDR0_SB_DQ19';
NODE_NAME     J17 269
 '@S9S_MB_2U_LIB.S9S_MB_2U(SCH_1):PAGE98_I12@PURE_QUANTA.SCONN288_ADR50017P130CC(CHIPS)':
 'DQ19_B': CDS_PINID='DQ19_B';
NODE_NAME     J18 269
 '@S9S_MB_2U_LIB.S9S_MB_2U(SCH_1):PAGE99_I24@PURE_QUANTA.SCONN288_ADR50017P087CC(CHIPS)':
 'DQ19_B': CDS_PINID='DQ19_B';
NET_NAME
'M_A_CPU1_SB_DQ<1>'
 '@S9S_MB_2U_LIB.S9S_MB_2U(SCH_1):M_A_CPU1_SB_DQ'<1>:
 C_SIGNAL='@s9s_mb_2u_lib.s9s_mb_2u(sch_1):m_a_cpu1_sb_dq(1)';
NODE_NAME     U1 J31
 '@S9S_MB_2U_LIB.S9S_MB_2U(SCH_1):PAGE51_I2@PURE_QUANTA.SOCKET4677_AZIF0045P001C01CS(CHIPS)':
 'DDR0_SB_DQ1': CDS_PINID='DDR0_SB_DQ1';
NODE_NAME     J17 102
 '@S9S_MB_2U_LIB.S9S_MB_2U(SCH_1):PAGE98_I12@PURE_QUANTA.SCONN288_ADR50017P130CC(CHIPS)':
 'DQ1_B': CDS_PINID='DQ1_B';
NODE_NAME     J18 102
 '@S9S_MB_2U_LIB.S9S_MB_2U(SCH_1):PAGE99_I24@PURE_QUANTA.SCONN288_ADR50017P087CC(CHIPS)':
 'DQ1_B': CDS_PINID='DQ1_B';
NET_NAME
'M_A_CPU1_SB_DQ<20>'
 '@S9S_MB_2U_LIB.S9S_MB_2U(SCH_1):M_A_CPU1_SB_DQ'<20>:
 C_SIGNAL='@s9s_mb_2u_lib.s9s_mb_2u(sch_1):m_a_cpu1_sb_dq(20)';
NODE_NAME     U1 B20
 '@S9S_MB_2U_LIB.S9S_MB_2U(SCH_1):PAGE51_I2@PURE_QUANTA.SOCKET4677_AZIF0045P001C01CS(CHIPS)':
 'DDR0_SB_DQ20': CDS_PINID='DDR0_SB_DQ20';
NODE_NAME     J17 129
 '@S9S_MB_2U_LIB.S9S_MB_2U(SCH_1):PAGE98_I12@PURE_QUANTA.SCONN288_ADR50017P130CC(CHIPS)':
 'DQ20_B': CDS_PINID='DQ20_B';
NODE_NAME     J18 129
 '@S9S_MB_2U_LIB.S9S_MB_2U(SCH_1):PAGE99_I24@PURE_QUANTA.SCONN288_ADR50017P087CC(CHIPS)':
 'DQ20_B': CDS_PINID='DQ20_B';
NET_NAME
'M_A_CPU1_SB_DQ<21>'
 '@S9S_MB_2U_LIB.S9S_MB_2U(SCH_1):M_A_CPU1_SB_DQ'<21>:
 C_SIGNAL='@s9s_mb_2u_lib.s9s_mb_2u(sch_1):m_a_cpu1_sb_dq(21)';
NODE_NAME     U1 C19
 '@S9S_MB_2U_LIB.S9S_MB_2U(SCH_1):PAGE51_I2@PURE_QUANTA.SOCKET4677_AZIF0045P001C01CS(CHIPS)':
 'DDR0_SB_DQ21': CDS_PINID='DDR0_SB_DQ21';
NODE_NAME     J17 131
 '@S9S_MB_2U_LIB.S9S_MB_2U(SCH_1):PAGE98_I12@PURE_QUANTA.SCONN288_ADR50017P130CC(CHIPS)':
 'DQ21_B': CDS_PINID='DQ21_B';
NODE_NAME     J18 131
 '@S9S_MB_2U_LIB.S9S_MB_2U(SCH_1):PAGE99_I24@PURE_QUANTA.SCONN288_ADR50017P087CC(CHIPS)':
 'DQ21_B': CDS_PINID='DQ21_B';
NET_NAME
'M_A_CPU1_SB_DQ<22>'
 '@S9S_MB_2U_LIB.S9S_MB_2U(SCH_1):M_A_CPU1_SB_DQ'<22>:
 C_SIGNAL='@s9s_mb_2u_lib.s9s_mb_2u(sch_1):m_a_cpu1_sb_dq(22)';
NODE_NAME     U1 F20
 '@S9S_MB_2U_LIB.S9S_MB_2U(SCH_1):PAGE51_I2@PURE_QUANTA.SOCKET4677_AZIF0045P001C01CS(CHIPS)':
 'DDR0_SB_DQ22': CDS_PINID='DDR0_SB_DQ22';
NODE_NAME     J17 274
 '@S9S_MB_2U_LIB.S9S_MB_2U(SCH_1):PAGE98_I12@PURE_QUANTA.SCONN288_ADR50017P130CC(CHIPS)':
 'DQ22_B': CDS_PINID='DQ22_B';
NODE_NAME     J18 274
 '@S9S_MB_2U_LIB.S9S_MB_2U(SCH_1):PAGE99_I24@PURE_QUANTA.SCONN288_ADR50017P087CC(CHIPS)':
 'DQ22_B': CDS_PINID='DQ22_B';
NET_NAME
'M_A_CPU1_SB_DQ<23>'
 '@S9S_MB_2U_LIB.S9S_MB_2U(SCH_1):M_A_CPU1_SB_DQ'<23>:
 C_SIGNAL='@s9s_mb_2u_lib.s9s_mb_2u(sch_1):m_a_cpu1_sb_dq(23)';
NODE_NAME     U1 E19
 '@S9S_MB_2U_LIB.S9S_MB_2U(SCH_1):PAGE51_I2@PURE_QUANTA.SOCKET4677_AZIF0045P001C01CS(CHIPS)':
 'DDR0_SB_DQ23': CDS_PINID='DDR0_SB_DQ23';
NODE_NAME     J17 276
 '@S9S_MB_2U_LIB.S9S_MB_2U(SCH_1):PAGE98_I12@PURE_QUANTA.SCONN288_ADR50017P130CC(CHIPS)':
 'DQ23_B': CDS_PINID='DQ23_B';
NODE_NAME     J18 276
 '@S9S_MB_2U_LIB.S9S_MB_2U(SCH_1):PAGE99_I24@PURE_QUANTA.SCONN288_ADR50017P087CC(CHIPS)':
 'DQ23_B': CDS_PINID='DQ23_B';
NET_NAME
'M_A_CPU1_SB_DQ<24>'
 '@S9S_MB_2U_LIB.S9S_MB_2U(SCH_1):M_A_CPU1_SB_DQ'<24>:
 C_SIGNAL='@s9s_mb_2u_lib.s9s_mb_2u(sch_1):m_a_cpu1_sb_dq(24)';
NODE_NAME     U1 C11
 '@S9S_MB_2U_LIB.S9S_MB_2U(SCH_1):PAGE51_I2@PURE_QUANTA.SOCKET4677_AZIF0045P001C01CS(CHIPS)':
 'DDR0_SB_DQ24': CDS_PINID='DDR0_SB_DQ24';
NODE_NAME     J17 133
 '@S9S_MB_2U_LIB.S9S_MB_2U(SCH_1):PAGE98_I12@PURE_QUANTA.SCONN288_ADR50017P130CC(CHIPS)':
 'DQ24_B': CDS_PINID='DQ24_B';
NODE_NAME     J18 133
 '@S9S_MB_2U_LIB.S9S_MB_2U(SCH_1):PAGE99_I24@PURE_QUANTA.SCONN288_ADR50017P087CC(CHIPS)':
 'DQ24_B': CDS_PINID='DQ24_B';
NET_NAME
'M_A_CPU1_SB_DQ<25>'
 '@S9S_MB_2U_LIB.S9S_MB_2U(SCH_1):M_A_CPU1_SB_DQ'<25>:
 C_SIGNAL='@s9s_mb_2u_lib.s9s_mb_2u(sch_1):m_a_cpu1_sb_dq(25)';
NODE_NAME     U1 B10
 '@S9S_MB_2U_LIB.S9S_MB_2U(SCH_1):PAGE51_I2@PURE_QUANTA.SOCKET4677_AZIF0045P001C01CS(CHIPS)':
 'DDR0_SB_DQ25': CDS_PINID='DDR0_SB_DQ25';
NODE_NAME     J17 135
 '@S9S_MB_2U_LIB.S9S_MB_2U(SCH_1):PAGE98_I12@PURE_QUANTA.SCONN288_ADR50017P130CC(CHIPS)':
 'DQ25_B': CDS_PINID='DQ25_B';
NODE_NAME     J18 135
 '@S9S_MB_2U_LIB.S9S_MB_2U(SCH_1):PAGE99_I24@PURE_QUANTA.SCONN288_ADR50017P087CC(CHIPS)':
 'DQ25_B': CDS_PINID='DQ25_B';
NET_NAME
'M_A_CPU1_SB_DQ<26>'
 '@S9S_MB_2U_LIB.S9S_MB_2U(SCH_1):M_A_CPU1_SB_DQ'<26>:
 C_SIGNAL='@s9s_mb_2u_lib.s9s_mb_2u(sch_1):m_a_cpu1_sb_dq(26)';
NODE_NAME     U1 E11
 '@S9S_MB_2U_LIB.S9S_MB_2U(SCH_1):PAGE51_I2@PURE_QUANTA.SOCKET4677_AZIF0045P001C01CS(CHIPS)':
 'DDR0_SB_DQ26': CDS_PINID='DDR0_SB_DQ26';
NODE_NAME     J17 278
 '@S9S_MB_2U_LIB.S9S_MB_2U(SCH_1):PAGE98_I12@PURE_QUANTA.SCONN288_ADR50017P130CC(CHIPS)':
 'DQ26_B': CDS_PINID='DQ26_B';
NODE_NAME     J18 278
 '@S9S_MB_2U_LIB.S9S_MB_2U(SCH_1):PAGE99_I24@PURE_QUANTA.SCONN288_ADR50017P087CC(CHIPS)':
 'DQ26_B': CDS_PINID='DQ26_B';
NET_NAME
'M_A_CPU1_SB_DQ<27>'
 '@S9S_MB_2U_LIB.S9S_MB_2U(SCH_1):M_A_CPU1_SB_DQ'<27>:
 C_SIGNAL='@s9s_mb_2u_lib.s9s_mb_2u(sch_1):m_a_cpu1_sb_dq(27)';
NODE_NAME     U1 F10
 '@S9S_MB_2U_LIB.S9S_MB_2U(SCH_1):PAGE51_I2@PURE_QUANTA.SOCKET4677_AZIF0045P001C01CS(CHIPS)':
 'DDR0_SB_DQ27': CDS_PINID='DDR0_SB_DQ27';
NODE_NAME     J17 280
 '@S9S_MB_2U_LIB.S9S_MB_2U(SCH_1):PAGE98_I12@PURE_QUANTA.SCONN288_ADR50017P130CC(CHIPS)':
 'DQ27_B': CDS_PINID='DQ27_B';
NODE_NAME     J18 280
 '@S9S_MB_2U_LIB.S9S_MB_2U(SCH_1):PAGE99_I24@PURE_QUANTA.SCONN288_ADR50017P087CC(CHIPS)':
 'DQ27_B': CDS_PINID='DQ27_B';
NET_NAME
'M_A_CPU1_SB_DQ<28>'
 '@S9S_MB_2U_LIB.S9S_MB_2U(SCH_1):M_A_CPU1_SB_DQ'<28>:
 C_SIGNAL='@s9s_mb_2u_lib.s9s_mb_2u(sch_1):m_a_cpu1_sb_dq(28)';
NODE_NAME     U1 B8
 '@S9S_MB_2U_LIB.S9S_MB_2U(SCH_1):PAGE51_I2@PURE_QUANTA.SOCKET4677_AZIF0045P001C01CS(CHIPS)':
 'DDR0_SB_DQ28': CDS_PINID='DDR0_SB_DQ28';
NODE_NAME     J17 140
 '@S9S_MB_2U_LIB.S9S_MB_2U(SCH_1):PAGE98_I12@PURE_QUANTA.SCONN288_ADR50017P130CC(CHIPS)':
 'DQ28_B': CDS_PINID='DQ28_B';
NODE_NAME     J18 140
 '@S9S_MB_2U_LIB.S9S_MB_2U(SCH_1):PAGE99_I24@PURE_QUANTA.SCONN288_ADR50017P087CC(CHIPS)':
 'DQ28_B': CDS_PINID='DQ28_B';
NET_NAME
'M_A_CPU1_SB_DQ<29>'
 '@S9S_MB_2U_LIB.S9S_MB_2U(SCH_1):M_A_CPU1_SB_DQ'<29>:
 C_SIGNAL='@s9s_mb_2u_lib.s9s_mb_2u(sch_1):m_a_cpu1_sb_dq(29)';
NODE_NAME     U1 C7
 '@S9S_MB_2U_LIB.S9S_MB_2U(SCH_1):PAGE51_I2@PURE_QUANTA.SOCKET4677_AZIF0045P001C01CS(CHIPS)':
 'DDR0_SB_DQ29': CDS_PINID='DDR0_SB_DQ29';
NODE_NAME     J17 142
 '@S9S_MB_2U_LIB.S9S_MB_2U(SCH_1):PAGE98_I12@PURE_QUANTA.SCONN288_ADR50017P130CC(CHIPS)':
 'DQ29_B': CDS_PINID='DQ29_B';
NODE_NAME     J18 142
 '@S9S_MB_2U_LIB.S9S_MB_2U(SCH_1):PAGE99_I24@PURE_QUANTA.SCONN288_ADR50017P087CC(CHIPS)':
 'DQ29_B': CDS_PINID='DQ29_B';
NET_NAME
'M_A_CPU1_SB_DQ<2>'
 '@S9S_MB_2U_LIB.S9S_MB_2U(SCH_1):M_A_CPU1_SB_DQ'<2>:
 C_SIGNAL='@s9s_mb_2u_lib.s9s_mb_2u(sch_1):m_a_cpu1_sb_dq(2)';
NODE_NAME     U1 M32
 '@S9S_MB_2U_LIB.S9S_MB_2U(SCH_1):PAGE51_I2@PURE_QUANTA.SOCKET4677_AZIF0045P001C01CS(CHIPS)':
 'DDR0_SB_DQ2': CDS_PINID='DDR0_SB_DQ2';
NODE_NAME     J17 245
 '@S9S_MB_2U_LIB.S9S_MB_2U(SCH_1):PAGE98_I12@PURE_QUANTA.SCONN288_ADR50017P130CC(CHIPS)':
 'DQ2_B': CDS_PINID='DQ2_B';
NODE_NAME     J18 245
 '@S9S_MB_2U_LIB.S9S_MB_2U(SCH_1):PAGE99_I24@PURE_QUANTA.SCONN288_ADR50017P087CC(CHIPS)':
 'DQ2_B': CDS_PINID='DQ2_B';
NET_NAME
'M_A_CPU1_SB_DQ<30>'
 '@S9S_MB_2U_LIB.S9S_MB_2U(SCH_1):M_A_CPU1_SB_DQ'<30>:
 C_SIGNAL='@s9s_mb_2u_lib.s9s_mb_2u(sch_1):m_a_cpu1_sb_dq(30)';
NODE_NAME     U1 F8
 '@S9S_MB_2U_LIB.S9S_MB_2U(SCH_1):PAGE51_I2@PURE_QUANTA.SOCKET4677_AZIF0045P001C01CS(CHIPS)':
 'DDR0_SB_DQ30': CDS_PINID='DDR0_SB_DQ30';
NODE_NAME     J17 285
 '@S9S_MB_2U_LIB.S9S_MB_2U(SCH_1):PAGE98_I12@PURE_QUANTA.SCONN288_ADR50017P130CC(CHIPS)':
 'DQ30_B': CDS_PINID='DQ30_B';
NODE_NAME     J18 285
 '@S9S_MB_2U_LIB.S9S_MB_2U(SCH_1):PAGE99_I24@PURE_QUANTA.SCONN288_ADR50017P087CC(CHIPS)':
 'DQ30_B': CDS_PINID='DQ30_B';
NET_NAME
'M_A_CPU1_SB_DQ<31>'
 '@S9S_MB_2U_LIB.S9S_MB_2U(SCH_1):M_A_CPU1_SB_DQ'<31>:
 C_SIGNAL='@s9s_mb_2u_lib.s9s_mb_2u(sch_1):m_a_cpu1_sb_dq(31)';
NODE_NAME     U1 E7
 '@S9S_MB_2U_LIB.S9S_MB_2U(SCH_1):PAGE51_I2@PURE_QUANTA.SOCKET4677_AZIF0045P001C01CS(CHIPS)':
 'DDR0_SB_DQ31': CDS_PINID='DDR0_SB_DQ31';
NODE_NAME     J17 287
 '@S9S_MB_2U_LIB.S9S_MB_2U(SCH_1):PAGE98_I12@PURE_QUANTA.SCONN288_ADR50017P130CC(CHIPS)':
 'DQ31_B': CDS_PINID='DQ31_B';
NODE_NAME     J18 287
 '@S9S_MB_2U_LIB.S9S_MB_2U(SCH_1):PAGE99_I24@PURE_QUANTA.SCONN288_ADR50017P087CC(CHIPS)':
 'DQ31_B': CDS_PINID='DQ31_B';
NET_NAME
'M_A_CPU1_SB_DQ<3>'
 '@S9S_MB_2U_LIB.S9S_MB_2U(SCH_1):M_A_CPU1_SB_DQ'<3>:
 C_SIGNAL='@s9s_mb_2u_lib.s9s_mb_2u(sch_1):m_a_cpu1_sb_dq(3)';
NODE_NAME     U1 N31
 '@S9S_MB_2U_LIB.S9S_MB_2U(SCH_1):PAGE51_I2@PURE_QUANTA.SOCKET4677_AZIF0045P001C01CS(CHIPS)':
 'DDR0_SB_DQ3': CDS_PINID='DDR0_SB_DQ3';
NODE_NAME     J17 247
 '@S9S_MB_2U_LIB.S9S_MB_2U(SCH_1):PAGE98_I12@PURE_QUANTA.SCONN288_ADR50017P130CC(CHIPS)':
 'DQ3_B': CDS_PINID='DQ3_B';
NODE_NAME     J18 247
 '@S9S_MB_2U_LIB.S9S_MB_2U(SCH_1):PAGE99_I24@PURE_QUANTA.SCONN288_ADR50017P087CC(CHIPS)':
 'DQ3_B': CDS_PINID='DQ3_B';
NET_NAME
'M_A_CPU1_SB_DQ<4>'
 '@S9S_MB_2U_LIB.S9S_MB_2U(SCH_1):M_A_CPU1_SB_DQ'<4>:
 C_SIGNAL='@s9s_mb_2u_lib.s9s_mb_2u(sch_1):m_a_cpu1_sb_dq(4)';
NODE_NAME     U1 J29
 '@S9S_MB_2U_LIB.S9S_MB_2U(SCH_1):PAGE51_I2@PURE_QUANTA.SOCKET4677_AZIF0045P001C01CS(CHIPS)':
 'DDR0_SB_DQ4': CDS_PINID='DDR0_SB_DQ4';
NODE_NAME     J17 107
 '@S9S_MB_2U_LIB.S9S_MB_2U(SCH_1):PAGE98_I12@PURE_QUANTA.SCONN288_ADR50017P130CC(CHIPS)':
 'DQ4_B': CDS_PINID='DQ4_B';
NODE_NAME     J18 107
 '@S9S_MB_2U_LIB.S9S_MB_2U(SCH_1):PAGE99_I24@PURE_QUANTA.SCONN288_ADR50017P087CC(CHIPS)':
 'DQ4_B': CDS_PINID='DQ4_B';
NET_NAME
'M_A_CPU1_SB_DQ<5>'
 '@S9S_MB_2U_LIB.S9S_MB_2U(SCH_1):M_A_CPU1_SB_DQ'<5>:
 C_SIGNAL='@s9s_mb_2u_lib.s9s_mb_2u(sch_1):m_a_cpu1_sb_dq(5)';
NODE_NAME     U1 K28
 '@S9S_MB_2U_LIB.S9S_MB_2U(SCH_1):PAGE51_I2@PURE_QUANTA.SOCKET4677_AZIF0045P001C01CS(CHIPS)':
 'DDR0_SB_DQ5': CDS_PINID='DDR0_SB_DQ5';
NODE_NAME     J17 109
 '@S9S_MB_2U_LIB.S9S_MB_2U(SCH_1):PAGE98_I12@PURE_QUANTA.SCONN288_ADR50017P130CC(CHIPS)':
 'DQ5_B': CDS_PINID='DQ5_B';
NODE_NAME     J18 109
 '@S9S_MB_2U_LIB.S9S_MB_2U(SCH_1):PAGE99_I24@PURE_QUANTA.SCONN288_ADR50017P087CC(CHIPS)':
 'DQ5_B': CDS_PINID='DQ5_B';
NET_NAME
'M_A_CPU1_SB_DQ<6>'
 '@S9S_MB_2U_LIB.S9S_MB_2U(SCH_1):M_A_CPU1_SB_DQ'<6>:
 C_SIGNAL='@s9s_mb_2u_lib.s9s_mb_2u(sch_1):m_a_cpu1_sb_dq(6)';
NODE_NAME     U1 N29
 '@S9S_MB_2U_LIB.S9S_MB_2U(SCH_1):PAGE51_I2@PURE_QUANTA.SOCKET4677_AZIF0045P001C01CS(CHIPS)':
 'DDR0_SB_DQ6': CDS_PINID='DDR0_SB_DQ6';
NODE_NAME     J17 252
 '@S9S_MB_2U_LIB.S9S_MB_2U(SCH_1):PAGE98_I12@PURE_QUANTA.SCONN288_ADR50017P130CC(CHIPS)':
 'DQ6_B': CDS_PINID='DQ6_B';
NODE_NAME     J18 252
 '@S9S_MB_2U_LIB.S9S_MB_2U(SCH_1):PAGE99_I24@PURE_QUANTA.SCONN288_ADR50017P087CC(CHIPS)':
 'DQ6_B': CDS_PINID='DQ6_B';
NET_NAME
'M_A_CPU1_SB_DQ<7>'
 '@S9S_MB_2U_LIB.S9S_MB_2U(SCH_1):M_A_CPU1_SB_DQ'<7>:
 C_SIGNAL='@s9s_mb_2u_lib.s9s_mb_2u(sch_1):m_a_cpu1_sb_dq(7)';
NODE_NAME     U1 M28
 '@S9S_MB_2U_LIB.S9S_MB_2U(SCH_1):PAGE51_I2@PURE_QUANTA.SOCKET4677_AZIF0045P001C01CS(CHIPS)':
 'DDR0_SB_DQ7': CDS_PINID='DDR0_SB_DQ7';
NODE_NAME     J17 254
 '@S9S_MB_2U_LIB.S9S_MB_2U(SCH_1):PAGE98_I12@PURE_QUANTA.SCONN288_ADR50017P130CC(CHIPS)':
 'DQ7_B': CDS_PINID='DQ7_B';
NODE_NAME     J18 254
 '@S9S_MB_2U_LIB.S9S_MB_2U(SCH_1):PAGE99_I24@PURE_QUANTA.SCONN288_ADR50017P087CC(CHIPS)':
 'DQ7_B': CDS_PINID='DQ7_B';
NET_NAME
'M_A_CPU1_SB_DQ<8>'
 '@S9S_MB_2U_LIB.S9S_MB_2U(SCH_1):M_A_CPU1_SB_DQ'<8>:
 C_SIGNAL='@s9s_mb_2u_lib.s9s_mb_2u(sch_1):m_a_cpu1_sb_dq(8)';
NODE_NAME     U1 C29
 '@S9S_MB_2U_LIB.S9S_MB_2U(SCH_1):PAGE51_I2@PURE_QUANTA.SOCKET4677_AZIF0045P001C01CS(CHIPS)':
 'DDR0_SB_DQ8': CDS_PINID='DDR0_SB_DQ8';
NODE_NAME     J17 111
 '@S9S_MB_2U_LIB.S9S_MB_2U(SCH_1):PAGE98_I12@PURE_QUANTA.SCONN288_ADR50017P130CC(CHIPS)':
 'DQ8_B': CDS_PINID='DQ8_B';
NODE_NAME     J18 111
 '@S9S_MB_2U_LIB.S9S_MB_2U(SCH_1):PAGE99_I24@PURE_QUANTA.SCONN288_ADR50017P087CC(CHIPS)':
 'DQ8_B': CDS_PINID='DQ8_B';
NET_NAME
'M_A_CPU1_SB_DQ<9>'
 '@S9S_MB_2U_LIB.S9S_MB_2U(SCH_1):M_A_CPU1_SB_DQ'<9>:
 C_SIGNAL='@s9s_mb_2u_lib.s9s_mb_2u(sch_1):m_a_cpu1_sb_dq(9)';
NODE_NAME     U1 B28
 '@S9S_MB_2U_LIB.S9S_MB_2U(SCH_1):PAGE51_I2@PURE_QUANTA.SOCKET4677_AZIF0045P001C01CS(CHIPS)':
 'DDR0_SB_DQ9': CDS_PINID='DDR0_SB_DQ9';
NODE_NAME     J17 113
 '@S9S_MB_2U_LIB.S9S_MB_2U(SCH_1):PAGE98_I12@PURE_QUANTA.SCONN288_ADR50017P130CC(CHIPS)':
 'DQ9_B': CDS_PINID='DQ9_B';
NODE_NAME     J18 113
 '@S9S_MB_2U_LIB.S9S_MB_2U(SCH_1):PAGE99_I24@PURE_QUANTA.SCONN288_ADR50017P087CC(CHIPS)':
 'DQ9_B': CDS_PINID='DQ9_B';
NET_NAME
'M_A_CPU1_SB_DQS_DN<0>'
 '@S9S_MB_2U_LIB.S9S_MB_2U(SCH_1):M_A_CPU1_SB_DQS_DN'<0>:
 C_SIGNAL='@s9s_mb_2u_lib.s9s_mb_2u(sch_1):m_a_cpu1_sb_dqs_dn(0)';
NODE_NAME     U1 H30
 '@S9S_MB_2U_LIB.S9S_MB_2U(SCH_1):PAGE51_I2@PURE_QUANTA.SOCKET4677_AZIF0045P001C01CS(CHIPS)':
 'DDR0_SB_DQS_DN0': CDS_PINID='DDR0_SB_DQS_DN0';
NODE_NAME     J17 105
 '@S9S_MB_2U_LIB.S9S_MB_2U(SCH_1):PAGE98_I178@PURE_QUANTA.SCONN288_ADR50017P130CC(CHIPS)':
 'DQS0_B_C': CDS_PINID='DQS0_B_C';
NODE_NAME     J18 105
 '@S9S_MB_2U_LIB.S9S_MB_2U(SCH_1):PAGE99_I178@PURE_QUANTA.SCONN288_ADR50017P087CC(CHIPS)':
 'DQS0_B_C': CDS_PINID='DQS0_B_C';
NET_NAME
'M_A_CPU1_SB_DQS_DN<1>'
 '@S9S_MB_2U_LIB.S9S_MB_2U(SCH_1):M_A_CPU1_SB_DQS_DN'<1>:
 C_SIGNAL='@s9s_mb_2u_lib.s9s_mb_2u(sch_1):m_a_cpu1_sb_dqs_dn(1)';
NODE_NAME     U1 A27
 '@S9S_MB_2U_LIB.S9S_MB_2U(SCH_1):PAGE51_I2@PURE_QUANTA.SOCKET4677_AZIF0045P001C01CS(CHIPS)':
 'DDR0_SB_DQS_DN1': CDS_PINID='DDR0_SB_DQS_DN1';
NODE_NAME     J17 116
 '@S9S_MB_2U_LIB.S9S_MB_2U(SCH_1):PAGE98_I178@PURE_QUANTA.SCONN288_ADR50017P130CC(CHIPS)':
 'DQS1_B_C': CDS_PINID='DQS1_B_C';
NODE_NAME     J18 116
 '@S9S_MB_2U_LIB.S9S_MB_2U(SCH_1):PAGE99_I178@PURE_QUANTA.SCONN288_ADR50017P087CC(CHIPS)':
 'DQS1_B_C': CDS_PINID='DQS1_B_C';
NET_NAME
'M_A_CPU1_SB_DQS_DN<2>'
 '@S9S_MB_2U_LIB.S9S_MB_2U(SCH_1):M_A_CPU1_SB_DQS_DN'<2>:
 C_SIGNAL='@s9s_mb_2u_lib.s9s_mb_2u(sch_1):m_a_cpu1_sb_dqs_dn(2)';
NODE_NAME     U1 A21
 '@S9S_MB_2U_LIB.S9S_MB_2U(SCH_1):PAGE51_I2@PURE_QUANTA.SOCKET4677_AZIF0045P001C01CS(CHIPS)':
 'DDR0_SB_DQS_DN2': CDS_PINID='DDR0_SB_DQS_DN2';
NODE_NAME     J17 127
 '@S9S_MB_2U_LIB.S9S_MB_2U(SCH_1):PAGE98_I178@PURE_QUANTA.SCONN288_ADR50017P130CC(CHIPS)':
 'DQS2_B_C': CDS_PINID='DQS2_B_C';
NODE_NAME     J18 127
 '@S9S_MB_2U_LIB.S9S_MB_2U(SCH_1):PAGE99_I178@PURE_QUANTA.SCONN288_ADR50017P087CC(CHIPS)':
 'DQS2_B_C': CDS_PINID='DQS2_B_C';
NET_NAME
'M_A_CPU1_SB_DQS_DN<3>'
 '@S9S_MB_2U_LIB.S9S_MB_2U(SCH_1):M_A_CPU1_SB_DQS_DN'<3>:
 C_SIGNAL='@s9s_mb_2u_lib.s9s_mb_2u(sch_1):m_a_cpu1_sb_dqs_dn(3)';
NODE_NAME     U1 A9
 '@S9S_MB_2U_LIB.S9S_MB_2U(SCH_1):PAGE51_I2@PURE_QUANTA.SOCKET4677_AZIF0045P001C01CS(CHIPS)':
 'DDR0_SB_DQS_DN3': CDS_PINID='DDR0_SB_DQS_DN3';
NODE_NAME     J17 138
 '@S9S_MB_2U_LIB.S9S_MB_2U(SCH_1):PAGE98_I178@PURE_QUANTA.SCONN288_ADR50017P130CC(CHIPS)':
 'DQS3_B_C': CDS_PINID='DQS3_B_C';
NODE_NAME     J18 138
 '@S9S_MB_2U_LIB.S9S_MB_2U(SCH_1):PAGE99_I178@PURE_QUANTA.SCONN288_ADR50017P087CC(CHIPS)':
 'DQS3_B_C': CDS_PINID='DQS3_B_C';
NET_NAME
'M_A_CPU1_SB_DQS_DN<4>'
 '@S9S_MB_2U_LIB.S9S_MB_2U(SCH_1):M_A_CPU1_SB_DQS_DN'<4>:
 C_SIGNAL='@s9s_mb_2u_lib.s9s_mb_2u(sch_1):m_a_cpu1_sb_dqs_dn(4)';
NODE_NAME     U1 G33
 '@S9S_MB_2U_LIB.S9S_MB_2U(SCH_1):PAGE51_I2@PURE_QUANTA.SOCKET4677_AZIF0045P001C01CS(CHIPS)':
 'DDR0_SB_DQS_DN4': CDS_PINID='DDR0_SB_DQS_DN4';
NODE_NAME     J17 238
 '@S9S_MB_2U_LIB.S9S_MB_2U(SCH_1):PAGE98_I178@PURE_QUANTA.SCONN288_ADR50017P130CC(CHIPS)':
 'DQS4_B_C': CDS_PINID='DQS4_B_C';
NODE_NAME     J18 238
 '@S9S_MB_2U_LIB.S9S_MB_2U(SCH_1):PAGE99_I178@PURE_QUANTA.SCONN288_ADR50017P087CC(CHIPS)':
 'DQS4_B_C': CDS_PINID='DQS4_B_C';
NET_NAME
'M_A_CPU1_SB_DQS_DN<5>'
 '@S9S_MB_2U_LIB.S9S_MB_2U(SCH_1):M_A_CPU1_SB_DQS_DN'<5>:
 C_SIGNAL='@s9s_mb_2u_lib.s9s_mb_2u(sch_1):m_a_cpu1_sb_dqs_dn(5)';
NODE_NAME     U1 M30
 '@S9S_MB_2U_LIB.S9S_MB_2U(SCH_1):PAGE51_I2@PURE_QUANTA.SOCKET4677_AZIF0045P001C01CS(CHIPS)':
 'DDR0_SB_DQS_DN5': CDS_PINID='DDR0_SB_DQS_DN5';
NODE_NAME     J17 249
 '@S9S_MB_2U_LIB.S9S_MB_2U(SCH_1):PAGE98_I178@PURE_QUANTA.SCONN288_ADR50017P130CC(CHIPS)':
 'DQS5_B_C||TDQS5_B_C': CDS_PINID='\dqs5_b_c||tdqs5_b_c\';
NODE_NAME     J18 249
 '@S9S_MB_2U_LIB.S9S_MB_2U(SCH_1):PAGE99_I178@PURE_QUANTA.SCONN288_ADR50017P087CC(CHIPS)':
 'DQS5_B_C||TDQS5_B_C': CDS_PINID='\dqs5_b_c||tdqs5_b_c\';
NET_NAME
'M_A_CPU1_SB_DQS_DN<6>'
 '@S9S_MB_2U_LIB.S9S_MB_2U(SCH_1):M_A_CPU1_SB_DQS_DN'<6>:
 C_SIGNAL='@s9s_mb_2u_lib.s9s_mb_2u(sch_1):m_a_cpu1_sb_dqs_dn(6)';
NODE_NAME     U1 G27
 '@S9S_MB_2U_LIB.S9S_MB_2U(SCH_1):PAGE51_I2@PURE_QUANTA.SOCKET4677_AZIF0045P001C01CS(CHIPS)':
 'DDR0_SB_DQS_DN6': CDS_PINID='DDR0_SB_DQS_DN6';
NODE_NAME     J17 260
 '@S9S_MB_2U_LIB.S9S_MB_2U(SCH_1):PAGE98_I178@PURE_QUANTA.SCONN288_ADR50017P130CC(CHIPS)':
 'DQS6_B_C||TDQS6_B_C': CDS_PINID='\dqs6_b_c||tdqs6_b_c\';
NODE_NAME     J18 260
 '@S9S_MB_2U_LIB.S9S_MB_2U(SCH_1):PAGE99_I178@PURE_QUANTA.SCONN288_ADR50017P087CC(CHIPS)':
 'DQS6_B_C||TDQS6_B_C': CDS_PINID='\dqs6_b_c||tdqs6_b_c\';
NET_NAME
'M_A_CPU1_SB_DQS_DN<7>'
 '@S9S_MB_2U_LIB.S9S_MB_2U(SCH_1):M_A_CPU1_SB_DQS_DN'<7>:
 C_SIGNAL='@s9s_mb_2u_lib.s9s_mb_2u(sch_1):m_a_cpu1_sb_dqs_dn(7)';
NODE_NAME     U1 G21
 '@S9S_MB_2U_LIB.S9S_MB_2U(SCH_1):PAGE51_I2@PURE_QUANTA.SOCKET4677_AZIF0045P001C01CS(CHIPS)':
 'DDR0_SB_DQS_DN7': CDS_PINID='DDR0_SB_DQS_DN7';
NODE_NAME     J17 271
 '@S9S_MB_2U_LIB.S9S_MB_2U(SCH_1):PAGE98_I178@PURE_QUANTA.SCONN288_ADR50017P130CC(CHIPS)':
 'DQS7_B_C||TDQS7_B_C': CDS_PINID='\dqs7_b_c||tdqs7_b_c\';
NODE_NAME     J18 271
 '@S9S_MB_2U_LIB.S9S_MB_2U(SCH_1):PAGE99_I178@PURE_QUANTA.SCONN288_ADR50017P087CC(CHIPS)':
 'DQS7_B_C||TDQS7_B_C': CDS_PINID='\dqs7_b_c||tdqs7_b_c\';
NET_NAME
'M_A_CPU1_SB_DQS_DN<8>'
 '@S9S_MB_2U_LIB.S9S_MB_2U(SCH_1):M_A_CPU1_SB_DQS_DN'<8>:
 C_SIGNAL='@s9s_mb_2u_lib.s9s_mb_2u(sch_1):m_a_cpu1_sb_dqs_dn(8)';
NODE_NAME     U1 G9
 '@S9S_MB_2U_LIB.S9S_MB_2U(SCH_1):PAGE51_I2@PURE_QUANTA.SOCKET4677_AZIF0045P001C01CS(CHIPS)':
 'DDR0_SB_DQS_DN8': CDS_PINID='DDR0_SB_DQS_DN8';
NODE_NAME     J17 282
 '@S9S_MB_2U_LIB.S9S_MB_2U(SCH_1):PAGE98_I178@PURE_QUANTA.SCONN288_ADR50017P130CC(CHIPS)':
 'DQS8_B_C||TDQS8_B_C': CDS_PINID='\dqs8_b_c||tdqs8_b_c\';
NODE_NAME     J18 282
 '@S9S_MB_2U_LIB.S9S_MB_2U(SCH_1):PAGE99_I178@PURE_QUANTA.SCONN288_ADR50017P087CC(CHIPS)':
 'DQS8_B_C||TDQS8_B_C': CDS_PINID='\dqs8_b_c||tdqs8_b_c\';
NET_NAME
'M_A_CPU1_SB_DQS_DN<9>'
 '@S9S_MB_2U_LIB.S9S_MB_2U(SCH_1):M_A_CPU1_SB_DQS_DN'<9>:
 C_SIGNAL='@s9s_mb_2u_lib.s9s_mb_2u(sch_1):m_a_cpu1_sb_dqs_dn(9)';
NODE_NAME     U1 A33
 '@S9S_MB_2U_LIB.S9S_MB_2U(SCH_1):PAGE51_I2@PURE_QUANTA.SOCKET4677_AZIF0045P001C01CS(CHIPS)':
 'DDR0_SB_DQS_DN9': CDS_PINID='DDR0_SB_DQS_DN9';
NODE_NAME     J17 94
 '@S9S_MB_2U_LIB.S9S_MB_2U(SCH_1):PAGE98_I178@PURE_QUANTA.SCONN288_ADR50017P130CC(CHIPS)':
 'DQS9_B_C||TDQS9_B_C': CDS_PINID='\dqs9_b_c||tdqs9_b_c\';
NODE_NAME     J18 94
 '@S9S_MB_2U_LIB.S9S_MB_2U(SCH_1):PAGE99_I178@PURE_QUANTA.SCONN288_ADR50017P087CC(CHIPS)':
 'DQS9_B_C||TDQS9_B_C': CDS_PINID='\dqs9_b_c||tdqs9_b_c\';
NET_NAME
'M_A_CPU1_SB_DQS_DP<0>'
 '@S9S_MB_2U_LIB.S9S_MB_2U(SCH_1):M_A_CPU1_SB_DQS_DP'<0>:
 C_SIGNAL='@s9s_mb_2u_lib.s9s_mb_2u(sch_1):m_a_cpu1_sb_dqs_dp(0)';
NODE_NAME     U1 K30
 '@S9S_MB_2U_LIB.S9S_MB_2U(SCH_1):PAGE51_I2@PURE_QUANTA.SOCKET4677_AZIF0045P001C01CS(CHIPS)':
 'DDR0_SB_DQS_DP0': CDS_PINID='DDR0_SB_DQS_DP0';
NODE_NAME     J17 104
 '@S9S_MB_2U_LIB.S9S_MB_2U(SCH_1):PAGE98_I178@PURE_QUANTA.SCONN288_ADR50017P130CC(CHIPS)':
 'DQS0_B_T': CDS_PINID='DQS0_B_T';
NODE_NAME     J18 104
 '@S9S_MB_2U_LIB.S9S_MB_2U(SCH_1):PAGE99_I178@PURE_QUANTA.SCONN288_ADR50017P087CC(CHIPS)':
 'DQS0_B_T': CDS_PINID='DQS0_B_T';
NET_NAME
'M_A_CPU1_SB_DQS_DP<1>'
 '@S9S_MB_2U_LIB.S9S_MB_2U(SCH_1):M_A_CPU1_SB_DQS_DP'<1>:
 C_SIGNAL='@s9s_mb_2u_lib.s9s_mb_2u(sch_1):m_a_cpu1_sb_dqs_dp(1)';
NODE_NAME     U1 C27
 '@S9S_MB_2U_LIB.S9S_MB_2U(SCH_1):PAGE51_I2@PURE_QUANTA.SOCKET4677_AZIF0045P001C01CS(CHIPS)':
 'DDR0_SB_DQS_DP1': CDS_PINID='DDR0_SB_DQS_DP1';
NODE_NAME     J17 115
 '@S9S_MB_2U_LIB.S9S_MB_2U(SCH_1):PAGE98_I178@PURE_QUANTA.SCONN288_ADR50017P130CC(CHIPS)':
 'DQS1_B_T': CDS_PINID='DQS1_B_T';
NODE_NAME     J18 115
 '@S9S_MB_2U_LIB.S9S_MB_2U(SCH_1):PAGE99_I178@PURE_QUANTA.SCONN288_ADR50017P087CC(CHIPS)':
 'DQS1_B_T': CDS_PINID='DQS1_B_T';
NET_NAME
'M_A_CPU1_SB_DQS_DP<2>'
 '@S9S_MB_2U_LIB.S9S_MB_2U(SCH_1):M_A_CPU1_SB_DQS_DP'<2>:
 C_SIGNAL='@s9s_mb_2u_lib.s9s_mb_2u(sch_1):m_a_cpu1_sb_dqs_dp(2)';
NODE_NAME     U1 C21
 '@S9S_MB_2U_LIB.S9S_MB_2U(SCH_1):PAGE51_I2@PURE_QUANTA.SOCKET4677_AZIF0045P001C01CS(CHIPS)':
 'DDR0_SB_DQS_DP2': CDS_PINID='DDR0_SB_DQS_DP2';
NODE_NAME     J17 126
 '@S9S_MB_2U_LIB.S9S_MB_2U(SCH_1):PAGE98_I178@PURE_QUANTA.SCONN288_ADR50017P130CC(CHIPS)':
 'DQS2_B_T': CDS_PINID='DQS2_B_T';
NODE_NAME     J18 126
 '@S9S_MB_2U_LIB.S9S_MB_2U(SCH_1):PAGE99_I178@PURE_QUANTA.SCONN288_ADR50017P087CC(CHIPS)':
 'DQS2_B_T': CDS_PINID='DQS2_B_T';
NET_NAME
'M_A_CPU1_SB_DQS_DP<3>'
 '@S9S_MB_2U_LIB.S9S_MB_2U(SCH_1):M_A_CPU1_SB_DQS_DP'<3>:
 C_SIGNAL='@s9s_mb_2u_lib.s9s_mb_2u(sch_1):m_a_cpu1_sb_dqs_dp(3)';
NODE_NAME     U1 C9
 '@S9S_MB_2U_LIB.S9S_MB_2U(SCH_1):PAGE51_I2@PURE_QUANTA.SOCKET4677_AZIF0045P001C01CS(CHIPS)':
 'DDR0_SB_DQS_DP3': CDS_PINID='DDR0_SB_DQS_DP3';
NODE_NAME     J17 137
 '@S9S_MB_2U_LIB.S9S_MB_2U(SCH_1):PAGE98_I178@PURE_QUANTA.SCONN288_ADR50017P130CC(CHIPS)':
 'DQS3_B_T': CDS_PINID='DQS3_B_T';
NODE_NAME     J18 137
 '@S9S_MB_2U_LIB.S9S_MB_2U(SCH_1):PAGE99_I178@PURE_QUANTA.SCONN288_ADR50017P087CC(CHIPS)':
 'DQS3_B_T': CDS_PINID='DQS3_B_T';
NET_NAME
'M_A_CPU1_SB_DQS_DP<4>'
 '@S9S_MB_2U_LIB.S9S_MB_2U(SCH_1):M_A_CPU1_SB_DQS_DP'<4>:
 C_SIGNAL='@s9s_mb_2u_lib.s9s_mb_2u(sch_1):m_a_cpu1_sb_dqs_dp(4)';
NODE_NAME     U1 E33
 '@S9S_MB_2U_LIB.S9S_MB_2U(SCH_1):PAGE51_I2@PURE_QUANTA.SOCKET4677_AZIF0045P001C01CS(CHIPS)':
 'DDR0_SB_DQS_DP4': CDS_PINID='DDR0_SB_DQS_DP4';
NODE_NAME     J17 239
 '@S9S_MB_2U_LIB.S9S_MB_2U(SCH_1):PAGE98_I178@PURE_QUANTA.SCONN288_ADR50017P130CC(CHIPS)':
 'DQS4_B_T': CDS_PINID='DQS4_B_T';
NODE_NAME     J18 239
 '@S9S_MB_2U_LIB.S9S_MB_2U(SCH_1):PAGE99_I178@PURE_QUANTA.SCONN288_ADR50017P087CC(CHIPS)':
 'DQS4_B_T': CDS_PINID='DQS4_B_T';
NET_NAME
'M_A_CPU1_SB_DQS_DP<5>'
 '@S9S_MB_2U_LIB.S9S_MB_2U(SCH_1):M_A_CPU1_SB_DQS_DP'<5>:
 C_SIGNAL='@s9s_mb_2u_lib.s9s_mb_2u(sch_1):m_a_cpu1_sb_dqs_dp(5)';
NODE_NAME     U1 P30
 '@S9S_MB_2U_LIB.S9S_MB_2U(SCH_1):PAGE51_I2@PURE_QUANTA.SOCKET4677_AZIF0045P001C01CS(CHIPS)':
 'DDR0_SB_DQS_DP5': CDS_PINID='DDR0_SB_DQS_DP5';
NODE_NAME     J17 250
 '@S9S_MB_2U_LIB.S9S_MB_2U(SCH_1):PAGE98_I178@PURE_QUANTA.SCONN288_ADR50017P130CC(CHIPS)':
 'DQS5_B_T||TDQS5_B_T': CDS_PINID='\dqs5_b_t||tdqs5_b_t\';
NODE_NAME     J18 250
 '@S9S_MB_2U_LIB.S9S_MB_2U(SCH_1):PAGE99_I178@PURE_QUANTA.SCONN288_ADR50017P087CC(CHIPS)':
 'DQS5_B_T||TDQS5_B_T': CDS_PINID='\dqs5_b_t||tdqs5_b_t\';
NET_NAME
'M_A_CPU1_SB_DQS_DP<6>'
 '@S9S_MB_2U_LIB.S9S_MB_2U(SCH_1):M_A_CPU1_SB_DQS_DP'<6>:
 C_SIGNAL='@s9s_mb_2u_lib.s9s_mb_2u(sch_1):m_a_cpu1_sb_dqs_dp(6)';
NODE_NAME     U1 E27
 '@S9S_MB_2U_LIB.S9S_MB_2U(SCH_1):PAGE51_I2@PURE_QUANTA.SOCKET4677_AZIF0045P001C01CS(CHIPS)':
 'DDR0_SB_DQS_DP6': CDS_PINID='DDR0_SB_DQS_DP6';
NODE_NAME     J17 261
 '@S9S_MB_2U_LIB.S9S_MB_2U(SCH_1):PAGE98_I178@PURE_QUANTA.SCONN288_ADR50017P130CC(CHIPS)':
 'DQS6_B_T||TDQS6_B_T': CDS_PINID='\dqs6_b_t||tdqs6_b_t\';
NODE_NAME     J18 261
 '@S9S_MB_2U_LIB.S9S_MB_2U(SCH_1):PAGE99_I178@PURE_QUANTA.SCONN288_ADR50017P087CC(CHIPS)':
 'DQS6_B_T||TDQS6_B_T': CDS_PINID='\dqs6_b_t||tdqs6_b_t\';
NET_NAME
'M_A_CPU1_SB_DQS_DP<7>'
 '@S9S_MB_2U_LIB.S9S_MB_2U(SCH_1):M_A_CPU1_SB_DQS_DP'<7>:
 C_SIGNAL='@s9s_mb_2u_lib.s9s_mb_2u(sch_1):m_a_cpu1_sb_dqs_dp(7)';
NODE_NAME     U1 E21
 '@S9S_MB_2U_LIB.S9S_MB_2U(SCH_1):PAGE51_I2@PURE_QUANTA.SOCKET4677_AZIF0045P001C01CS(CHIPS)':
 'DDR0_SB_DQS_DP7': CDS_PINID='DDR0_SB_DQS_DP7';
NODE_NAME     J17 272
 '@S9S_MB_2U_LIB.S9S_MB_2U(SCH_1):PAGE98_I178@PURE_QUANTA.SCONN288_ADR50017P130CC(CHIPS)':
 'DQS7_B_T||TDQS7_B_T': CDS_PINID='\dqs7_b_t||tdqs7_b_t\';
NODE_NAME     J18 272
 '@S9S_MB_2U_LIB.S9S_MB_2U(SCH_1):PAGE99_I178@PURE_QUANTA.SCONN288_ADR50017P087CC(CHIPS)':
 'DQS7_B_T||TDQS7_B_T': CDS_PINID='\dqs7_b_t||tdqs7_b_t\';
NET_NAME
'M_A_CPU1_SB_DQS_DP<8>'
 '@S9S_MB_2U_LIB.S9S_MB_2U(SCH_1):M_A_CPU1_SB_DQS_DP'<8>:
 C_SIGNAL='@s9s_mb_2u_lib.s9s_mb_2u(sch_1):m_a_cpu1_sb_dqs_dp(8)';
NODE_NAME     U1 E9
 '@S9S_MB_2U_LIB.S9S_MB_2U(SCH_1):PAGE51_I2@PURE_QUANTA.SOCKET4677_AZIF0045P001C01CS(CHIPS)':
 'DDR0_SB_DQS_DP8': CDS_PINID='DDR0_SB_DQS_DP8';
NODE_NAME     J17 283
 '@S9S_MB_2U_LIB.S9S_MB_2U(SCH_1):PAGE98_I178@PURE_QUANTA.SCONN288_ADR50017P130CC(CHIPS)':
 'DQS8_B_T||TDQS8_B_T': CDS_PINID='\dqs8_b_t||tdqs8_b_t\';
NODE_NAME     J18 283
 '@S9S_MB_2U_LIB.S9S_MB_2U(SCH_1):PAGE99_I178@PURE_QUANTA.SCONN288_ADR50017P087CC(CHIPS)':
 'DQS8_B_T||TDQS8_B_T': CDS_PINID='\dqs8_b_t||tdqs8_b_t\';
NET_NAME
'M_A_CPU1_SB_DQS_DP<9>'
 '@S9S_MB_2U_LIB.S9S_MB_2U(SCH_1):M_A_CPU1_SB_DQS_DP'<9>:
 C_SIGNAL='@s9s_mb_2u_lib.s9s_mb_2u(sch_1):m_a_cpu1_sb_dqs_dp(9)';
NODE_NAME     U1 C33
 '@S9S_MB_2U_LIB.S9S_MB_2U(SCH_1):PAGE51_I2@PURE_QUANTA.SOCKET4677_AZIF0045P001C01CS(CHIPS)':
 'DDR0_SB_DQS_DP9': CDS_PINID='DDR0_SB_DQS_DP9';
NODE_NAME     J17 93
 '@S9S_MB_2U_LIB.S9S_MB_2U(SCH_1):PAGE98_I178@PURE_QUANTA.SCONN288_ADR50017P130CC(CHIPS)':
 'DQS9_B_T||TDQS9_B_T||DBI4_B_N': CDS_PINID='\dqs9_b_t||tdqs9_b_t||dbi4_b_n\';
NODE_NAME     J18 93
 '@S9S_MB_2U_LIB.S9S_MB_2U(SCH_1):PAGE99_I178@PURE_QUANTA.SCONN288_ADR50017P087CC(CHIPS)':
 'DQS9_B_T||TDQS9_B_T||DBI4_B_N': CDS_PINID='\dqs9_b_t||tdqs9_b_t||dbi4_b_n\';
NET_NAME
'M_A_CPU1_SB_PAR'
 '@S9S_MB_2U_LIB.S9S_MB_2U(SCH_1):M_A_CPU1_SB_PAR':
 C_SIGNAL='@s9s_mb_2u_lib.s9s_mb_2u(sch_1):m_a_cpu1_sb_par';
NODE_NAME     U1 G39
 '@S9S_MB_2U_LIB.S9S_MB_2U(SCH_1):PAGE51_I2@PURE_QUANTA.SOCKET4677_AZIF0045P001C01CS(CHIPS)':
 'DDR0_SB_PAR': CDS_PINID='DDR0_SB_PAR';
NODE_NAME     J17 227
 '@S9S_MB_2U_LIB.S9S_MB_2U(SCH_1):PAGE98_I12@PURE_QUANTA.SCONN288_ADR50017P130CC(CHIPS)':
 'PAR_B': CDS_PINID='PAR_B';
NODE_NAME     J18 227
 '@S9S_MB_2U_LIB.S9S_MB_2U(SCH_1):PAGE99_I24@PURE_QUANTA.SCONN288_ADR50017P087CC(CHIPS)':
 'PAR_B': CDS_PINID='PAR_B';
NET_NAME
'M_A_CPU1_SB_RSP<0>'
 '@S9S_MB_2U_LIB.S9S_MB_2U(SCH_1):M_A_CPU1_SB_RSP'<0>:
 C_SIGNAL='@s9s_mb_2u_lib.s9s_mb_2u(sch_1):m_a_cpu1_sb_rsp(0)';
NODE_NAME     U1 AV44
 '@S9S_MB_2U_LIB.S9S_MB_2U(SCH_1):PAGE51_I2@PURE_QUANTA.SOCKET4677_AZIF0045P001C01CS(CHIPS)':
 'DDR0_B_RSP0': CDS_PINID='DDR0_B_RSP0';
NODE_NAME     J17 87
 '@S9S_MB_2U_LIB.S9S_MB_2U(SCH_1):PAGE98_I12@PURE_QUANTA.SCONN288_ADR50017P130CC(CHIPS)':
 'LBS||RSP_B_N': CDS_PINID='\lbs||rsp_b_n\';
NET_NAME
'M_A_CPU1_SB_RSP<1>'
 '@S9S_MB_2U_LIB.S9S_MB_2U(SCH_1):M_A_CPU1_SB_RSP'<1>:
 C_SIGNAL='@s9s_mb_2u_lib.s9s_mb_2u(sch_1):m_a_cpu1_sb_rsp(1)';
NODE_NAME     U1 AV42
 '@S9S_MB_2U_LIB.S9S_MB_2U(SCH_1):PAGE51_I2@PURE_QUANTA.SOCKET4677_AZIF0045P001C01CS(CHIPS)':
 'DDR0_B_RSP1': CDS_PINID='DDR0_B_RSP1';
NODE_NAME     J18 87
 '@S9S_MB_2U_LIB.S9S_MB_2U(SCH_1):PAGE99_I24@PURE_QUANTA.SCONN288_ADR50017P087CC(CHIPS)':
 'LBS||RSP_B_N': CDS_PINID='\lbs||rsp_b_n\';
NET_NAME
'M_B_CPU0_ALERT_N'
 '@S9S_MB_2U_LIB.S9S_MB_2U(SCH_1):M_B_CPU0_ALERT_N':
 C_SIGNAL='@s9s_mb_2u_lib.s9s_mb_2u(sch_1):m_b_cpu0_alert_n';
NODE_NAME     U2 AV49
 '@S9S_MB_2U_LIB.S9S_MB_2U(SCH_1):PAGE21_I169@PURE_QUANTA.SOCKET4677_AZIF0045P001C01CS(CHIPS)':
 'DDR1_ALERT_N': CDS_PINID='DDR1_ALERT_N';
NODE_NAME     J4 62
 '@S9S_MB_2U_LIB.S9S_MB_2U(SCH_1):PAGE85_I23@PURE_QUANTA.SCONN288_ADR50017P087CC(CHIPS)':
 'ALERT_N': CDS_PINID='ALERT_N';
NODE_NAME     J3 62
 '@S9S_MB_2U_LIB.S9S_MB_2U(SCH_1):PAGE84_I180@PURE_QUANTA.SCONN288_ADR50017P130CC(CHIPS)':
 'ALERT_N': CDS_PINID='ALERT_N';
NET_NAME
'M_B_CPU0_CLK_DN<0>'
 '@S9S_MB_2U_LIB.S9S_MB_2U(SCH_1):M_B_CPU0_CLK_DN'<0>:
 C_SIGNAL='@s9s_mb_2u_lib.s9s_mb_2u(sch_1):m_b_cpu0_clk_dn(0)';
NODE_NAME     U2 R45
 '@S9S_MB_2U_LIB.S9S_MB_2U(SCH_1):PAGE21_I169@PURE_QUANTA.SOCKET4677_AZIF0045P001C01CS(CHIPS)':
 'DDR1_CLK_DN0': CDS_PINID='DDR1_CLK_DN0';
NODE_NAME     J3 218
 '@S9S_MB_2U_LIB.S9S_MB_2U(SCH_1):PAGE84_I180@PURE_QUANTA.SCONN288_ADR50017P130CC(CHIPS)':
 'CK_C': CDS_PINID='CK_C';
NET_NAME
'M_B_CPU0_CLK_DN<1>'
 '@S9S_MB_2U_LIB.S9S_MB_2U(SCH_1):M_B_CPU0_CLK_DN'<1>:
 C_SIGNAL='@s9s_mb_2u_lib.s9s_mb_2u(sch_1):m_b_cpu0_clk_dn(1)';
NODE_NAME     U2 W45
 '@S9S_MB_2U_LIB.S9S_MB_2U(SCH_1):PAGE21_I169@PURE_QUANTA.SOCKET4677_AZIF0045P001C01CS(CHIPS)':
 'DDR1_CLK_DN1': CDS_PINID='DDR1_CLK_DN1';
NODE_NAME     J4 218
 '@S9S_MB_2U_LIB.S9S_MB_2U(SCH_1):PAGE85_I23@PURE_QUANTA.SCONN288_ADR50017P087CC(CHIPS)':
 'CK_C': CDS_PINID='CK_C';
NET_NAME
'M_B_CPU0_CLK_DP<0>'
 '@S9S_MB_2U_LIB.S9S_MB_2U(SCH_1):M_B_CPU0_CLK_DP'<0>:
 C_SIGNAL='@s9s_mb_2u_lib.s9s_mb_2u(sch_1):m_b_cpu0_clk_dp(0)';
NODE_NAME     U2 U45
 '@S9S_MB_2U_LIB.S9S_MB_2U(SCH_1):PAGE21_I169@PURE_QUANTA.SOCKET4677_AZIF0045P001C01CS(CHIPS)':
 'DDR1_CLK_DP0': CDS_PINID='DDR1_CLK_DP0';
NODE_NAME     J3 217
 '@S9S_MB_2U_LIB.S9S_MB_2U(SCH_1):PAGE84_I180@PURE_QUANTA.SCONN288_ADR50017P130CC(CHIPS)':
 'CK_T': CDS_PINID='CK_T';
NET_NAME
'M_B_CPU0_CLK_DP<1>'
 '@S9S_MB_2U_LIB.S9S_MB_2U(SCH_1):M_B_CPU0_CLK_DP'<1>:
 C_SIGNAL='@s9s_mb_2u_lib.s9s_mb_2u(sch_1):m_b_cpu0_clk_dp(1)';
NODE_NAME     U2 AA45
 '@S9S_MB_2U_LIB.S9S_MB_2U(SCH_1):PAGE21_I169@PURE_QUANTA.SOCKET4677_AZIF0045P001C01CS(CHIPS)':
 'DDR1_CLK_DP1': CDS_PINID='DDR1_CLK_DP1';
NODE_NAME     J4 217
 '@S9S_MB_2U_LIB.S9S_MB_2U(SCH_1):PAGE85_I23@PURE_QUANTA.SCONN288_ADR50017P087CC(CHIPS)':
 'CK_T': CDS_PINID='CK_T';
NET_NAME
'M_B_CPU0_SA_CA<0>'
 '@S9S_MB_2U_LIB.S9S_MB_2U(SCH_1):M_B_CPU0_SA_CA'<0>:
 C_SIGNAL='@s9s_mb_2u_lib.s9s_mb_2u(sch_1):m_b_cpu0_sa_ca(0)';
NODE_NAME     U2 H49
 '@S9S_MB_2U_LIB.S9S_MB_2U(SCH_1):PAGE21_I169@PURE_QUANTA.SOCKET4677_AZIF0045P001C01CS(CHIPS)':
 'DDR1_SA_CA0': CDS_PINID='DDR1_SA_CA0';
NODE_NAME     J4 66
 '@S9S_MB_2U_LIB.S9S_MB_2U(SCH_1):PAGE85_I23@PURE_QUANTA.SCONN288_ADR50017P087CC(CHIPS)':
 'CA0_A': CDS_PINID='CA0_A';
NODE_NAME     J3 66
 '@S9S_MB_2U_LIB.S9S_MB_2U(SCH_1):PAGE84_I180@PURE_QUANTA.SCONN288_ADR50017P130CC(CHIPS)':
 'CA0_A': CDS_PINID='CA0_A';
NET_NAME
'M_B_CPU0_SA_CA<1>'
 '@S9S_MB_2U_LIB.S9S_MB_2U(SCH_1):M_B_CPU0_SA_CA'<1>:
 C_SIGNAL='@s9s_mb_2u_lib.s9s_mb_2u(sch_1):m_b_cpu0_sa_ca(1)';
NODE_NAME     U2 P49
 '@S9S_MB_2U_LIB.S9S_MB_2U(SCH_1):PAGE21_I169@PURE_QUANTA.SOCKET4677_AZIF0045P001C01CS(CHIPS)':
 'DDR1_SA_CA1': CDS_PINID='DDR1_SA_CA1';
NODE_NAME     J4 211
 '@S9S_MB_2U_LIB.S9S_MB_2U(SCH_1):PAGE85_I23@PURE_QUANTA.SCONN288_ADR50017P087CC(CHIPS)':
 'CA1_A': CDS_PINID='CA1_A';
NODE_NAME     J3 211
 '@S9S_MB_2U_LIB.S9S_MB_2U(SCH_1):PAGE84_I180@PURE_QUANTA.SCONN288_ADR50017P130CC(CHIPS)':
 'CA1_A': CDS_PINID='CA1_A';
NET_NAME
'M_B_CPU0_SA_CA<2>'
 '@S9S_MB_2U_LIB.S9S_MB_2U(SCH_1):M_B_CPU0_SA_CA'<2>:
 C_SIGNAL='@s9s_mb_2u_lib.s9s_mb_2u(sch_1):m_b_cpu0_sa_ca(2)';
NODE_NAME     U2 J48
 '@S9S_MB_2U_LIB.S9S_MB_2U(SCH_1):PAGE21_I169@PURE_QUANTA.SOCKET4677_AZIF0045P001C01CS(CHIPS)':
 'DDR1_SA_CA2': CDS_PINID='DDR1_SA_CA2';
NODE_NAME     J4 68
 '@S9S_MB_2U_LIB.S9S_MB_2U(SCH_1):PAGE85_I23@PURE_QUANTA.SCONN288_ADR50017P087CC(CHIPS)':
 'CA2_A': CDS_PINID='CA2_A';
NODE_NAME     J3 68
 '@S9S_MB_2U_LIB.S9S_MB_2U(SCH_1):PAGE84_I180@PURE_QUANTA.SCONN288_ADR50017P130CC(CHIPS)':
 'CA2_A': CDS_PINID='CA2_A';
NET_NAME
'M_B_CPU0_SA_CA<3>'
 '@S9S_MB_2U_LIB.S9S_MB_2U(SCH_1):M_B_CPU0_SA_CA'<3>:
 C_SIGNAL='@s9s_mb_2u_lib.s9s_mb_2u(sch_1):m_b_cpu0_sa_ca(3)';
NODE_NAME     U2 N48
 '@S9S_MB_2U_LIB.S9S_MB_2U(SCH_1):PAGE21_I169@PURE_QUANTA.SOCKET4677_AZIF0045P001C01CS(CHIPS)':
 'DDR1_SA_CA3': CDS_PINID='DDR1_SA_CA3';
NODE_NAME     J4 213
 '@S9S_MB_2U_LIB.S9S_MB_2U(SCH_1):PAGE85_I23@PURE_QUANTA.SCONN288_ADR50017P087CC(CHIPS)':
 'CA3_A': CDS_PINID='CA3_A';
NODE_NAME     J3 213
 '@S9S_MB_2U_LIB.S9S_MB_2U(SCH_1):PAGE84_I180@PURE_QUANTA.SCONN288_ADR50017P130CC(CHIPS)':
 'CA3_A': CDS_PINID='CA3_A';
NET_NAME
'M_B_CPU0_SA_CA<4>'
 '@S9S_MB_2U_LIB.S9S_MB_2U(SCH_1):M_B_CPU0_SA_CA'<4>:
 C_SIGNAL='@s9s_mb_2u_lib.s9s_mb_2u(sch_1):m_b_cpu0_sa_ca(4)';
NODE_NAME     U2 K47
 '@S9S_MB_2U_LIB.S9S_MB_2U(SCH_1):PAGE21_I169@PURE_QUANTA.SOCKET4677_AZIF0045P001C01CS(CHIPS)':
 'DDR1_SA_CA4': CDS_PINID='DDR1_SA_CA4';
NODE_NAME     J4 70
 '@S9S_MB_2U_LIB.S9S_MB_2U(SCH_1):PAGE85_I23@PURE_QUANTA.SCONN288_ADR50017P087CC(CHIPS)':
 'CA4_A': CDS_PINID='CA4_A';
NODE_NAME     J3 70
 '@S9S_MB_2U_LIB.S9S_MB_2U(SCH_1):PAGE84_I180@PURE_QUANTA.SCONN288_ADR50017P130CC(CHIPS)':
 'CA4_A': CDS_PINID='CA4_A';
NET_NAME
'M_B_CPU0_SA_CA<5>'
 '@S9S_MB_2U_LIB.S9S_MB_2U(SCH_1):M_B_CPU0_SA_CA'<5>:
 C_SIGNAL='@s9s_mb_2u_lib.s9s_mb_2u(sch_1):m_b_cpu0_sa_ca(5)';
NODE_NAME     U2 M47
 '@S9S_MB_2U_LIB.S9S_MB_2U(SCH_1):PAGE21_I169@PURE_QUANTA.SOCKET4677_AZIF0045P001C01CS(CHIPS)':
 'DDR1_SA_CA5': CDS_PINID='DDR1_SA_CA5';
NODE_NAME     J4 215
 '@S9S_MB_2U_LIB.S9S_MB_2U(SCH_1):PAGE85_I23@PURE_QUANTA.SCONN288_ADR50017P087CC(CHIPS)':
 'CA5_A': CDS_PINID='CA5_A';
NODE_NAME     J3 215
 '@S9S_MB_2U_LIB.S9S_MB_2U(SCH_1):PAGE84_I180@PURE_QUANTA.SCONN288_ADR50017P130CC(CHIPS)':
 'CA5_A': CDS_PINID='CA5_A';
NET_NAME
'M_B_CPU0_SA_CA<6>'
 '@S9S_MB_2U_LIB.S9S_MB_2U(SCH_1):M_B_CPU0_SA_CA'<6>:
 C_SIGNAL='@s9s_mb_2u_lib.s9s_mb_2u(sch_1):m_b_cpu0_sa_ca(6)';
NODE_NAME     U2 Y44
 '@S9S_MB_2U_LIB.S9S_MB_2U(SCH_1):PAGE21_I169@PURE_QUANTA.SOCKET4677_AZIF0045P001C01CS(CHIPS)':
 'DDR1_SA_CA6': CDS_PINID='DDR1_SA_CA6';
NODE_NAME     J4 72
 '@S9S_MB_2U_LIB.S9S_MB_2U(SCH_1):PAGE85_I23@PURE_QUANTA.SCONN288_ADR50017P087CC(CHIPS)':
 'CA6_A': CDS_PINID='CA6_A';
NODE_NAME     J3 72
 '@S9S_MB_2U_LIB.S9S_MB_2U(SCH_1):PAGE84_I180@PURE_QUANTA.SCONN288_ADR50017P130CC(CHIPS)':
 'CA6_A': CDS_PINID='CA6_A';
NET_NAME
'M_B_CPU0_SA_CB<0>'
 '@S9S_MB_2U_LIB.S9S_MB_2U(SCH_1):M_B_CPU0_SA_CB'<0>:
 C_SIGNAL='@s9s_mb_2u_lib.s9s_mb_2u(sch_1):m_b_cpu0_sa_cb(0)';
NODE_NAME     U2 K57
 '@S9S_MB_2U_LIB.S9S_MB_2U(SCH_1):PAGE21_I169@PURE_QUANTA.SOCKET4677_AZIF0045P001C01CS(CHIPS)':
 'DDR1_SA_ECC0': CDS_PINID='DDR1_SA_ECC0';
NODE_NAME     J4 51
 '@S9S_MB_2U_LIB.S9S_MB_2U(SCH_1):PAGE85_I23@PURE_QUANTA.SCONN288_ADR50017P087CC(CHIPS)':
 'CB0_A': CDS_PINID='CB0_A';
NODE_NAME     J3 51
 '@S9S_MB_2U_LIB.S9S_MB_2U(SCH_1):PAGE84_I180@PURE_QUANTA.SCONN288_ADR50017P130CC(CHIPS)':
 'CB0_A': CDS_PINID='CB0_A';
NET_NAME
'M_B_CPU0_SA_CB<1>'
 '@S9S_MB_2U_LIB.S9S_MB_2U(SCH_1):M_B_CPU0_SA_CB'<1>:
 C_SIGNAL='@s9s_mb_2u_lib.s9s_mb_2u(sch_1):m_b_cpu0_sa_cb(1)';
NODE_NAME     U2 J56
 '@S9S_MB_2U_LIB.S9S_MB_2U(SCH_1):PAGE21_I169@PURE_QUANTA.SOCKET4677_AZIF0045P001C01CS(CHIPS)':
 'DDR1_SA_ECC1': CDS_PINID='DDR1_SA_ECC1';
NODE_NAME     J4 53
 '@S9S_MB_2U_LIB.S9S_MB_2U(SCH_1):PAGE85_I23@PURE_QUANTA.SCONN288_ADR50017P087CC(CHIPS)':
 'CB1_A': CDS_PINID='CB1_A';
NODE_NAME     J3 53
 '@S9S_MB_2U_LIB.S9S_MB_2U(SCH_1):PAGE84_I180@PURE_QUANTA.SCONN288_ADR50017P130CC(CHIPS)':
 'CB1_A': CDS_PINID='CB1_A';
NET_NAME
'M_B_CPU0_SA_CB<2>'
 '@S9S_MB_2U_LIB.S9S_MB_2U(SCH_1):M_B_CPU0_SA_CB'<2>:
 C_SIGNAL='@s9s_mb_2u_lib.s9s_mb_2u(sch_1):m_b_cpu0_sa_cb(2)';
NODE_NAME     U2 M57
 '@S9S_MB_2U_LIB.S9S_MB_2U(SCH_1):PAGE21_I169@PURE_QUANTA.SOCKET4677_AZIF0045P001C01CS(CHIPS)':
 'DDR1_SA_ECC2': CDS_PINID='DDR1_SA_ECC2';
NODE_NAME     J4 196
 '@S9S_MB_2U_LIB.S9S_MB_2U(SCH_1):PAGE85_I23@PURE_QUANTA.SCONN288_ADR50017P087CC(CHIPS)':
 'CB2_A': CDS_PINID='CB2_A';
NODE_NAME     J3 196
 '@S9S_MB_2U_LIB.S9S_MB_2U(SCH_1):PAGE84_I180@PURE_QUANTA.SCONN288_ADR50017P130CC(CHIPS)':
 'CB2_A': CDS_PINID='CB2_A';
NET_NAME
'M_B_CPU0_SA_CB<3>'
 '@S9S_MB_2U_LIB.S9S_MB_2U(SCH_1):M_B_CPU0_SA_CB'<3>:
 C_SIGNAL='@s9s_mb_2u_lib.s9s_mb_2u(sch_1):m_b_cpu0_sa_cb(3)';
NODE_NAME     U2 N56
 '@S9S_MB_2U_LIB.S9S_MB_2U(SCH_1):PAGE21_I169@PURE_QUANTA.SOCKET4677_AZIF0045P001C01CS(CHIPS)':
 'DDR1_SA_ECC3': CDS_PINID='DDR1_SA_ECC3';
NODE_NAME     J4 198
 '@S9S_MB_2U_LIB.S9S_MB_2U(SCH_1):PAGE85_I23@PURE_QUANTA.SCONN288_ADR50017P087CC(CHIPS)':
 'CB3_A': CDS_PINID='CB3_A';
NODE_NAME     J3 198
 '@S9S_MB_2U_LIB.S9S_MB_2U(SCH_1):PAGE84_I180@PURE_QUANTA.SCONN288_ADR50017P130CC(CHIPS)':
 'CB3_A': CDS_PINID='CB3_A';
NET_NAME
'M_B_CPU0_SA_CB<4>'
 '@S9S_MB_2U_LIB.S9S_MB_2U(SCH_1):M_B_CPU0_SA_CB'<4>:
 C_SIGNAL='@s9s_mb_2u_lib.s9s_mb_2u(sch_1):m_b_cpu0_sa_cb(4)';
NODE_NAME     U2 J54
 '@S9S_MB_2U_LIB.S9S_MB_2U(SCH_1):PAGE21_I169@PURE_QUANTA.SOCKET4677_AZIF0045P001C01CS(CHIPS)':
 'DDR1_SA_ECC4': CDS_PINID='DDR1_SA_ECC4';
NODE_NAME     J4 58
 '@S9S_MB_2U_LIB.S9S_MB_2U(SCH_1):PAGE85_I23@PURE_QUANTA.SCONN288_ADR50017P087CC(CHIPS)':
 'CB4_A': CDS_PINID='CB4_A';
NODE_NAME     J3 58
 '@S9S_MB_2U_LIB.S9S_MB_2U(SCH_1):PAGE84_I180@PURE_QUANTA.SCONN288_ADR50017P130CC(CHIPS)':
 'CB4_A': CDS_PINID='CB4_A';
NET_NAME
'M_B_CPU0_SA_CB<5>'
 '@S9S_MB_2U_LIB.S9S_MB_2U(SCH_1):M_B_CPU0_SA_CB'<5>:
 C_SIGNAL='@s9s_mb_2u_lib.s9s_mb_2u(sch_1):m_b_cpu0_sa_cb(5)';
NODE_NAME     U2 K53
 '@S9S_MB_2U_LIB.S9S_MB_2U(SCH_1):PAGE21_I169@PURE_QUANTA.SOCKET4677_AZIF0045P001C01CS(CHIPS)':
 'DDR1_SA_ECC5': CDS_PINID='DDR1_SA_ECC5';
NODE_NAME     J4 60
 '@S9S_MB_2U_LIB.S9S_MB_2U(SCH_1):PAGE85_I23@PURE_QUANTA.SCONN288_ADR50017P087CC(CHIPS)':
 'CB5_A': CDS_PINID='CB5_A';
NODE_NAME     J3 60
 '@S9S_MB_2U_LIB.S9S_MB_2U(SCH_1):PAGE84_I180@PURE_QUANTA.SCONN288_ADR50017P130CC(CHIPS)':
 'CB5_A': CDS_PINID='CB5_A';
NET_NAME
'M_B_CPU0_SA_CB<6>'
 '@S9S_MB_2U_LIB.S9S_MB_2U(SCH_1):M_B_CPU0_SA_CB'<6>:
 C_SIGNAL='@s9s_mb_2u_lib.s9s_mb_2u(sch_1):m_b_cpu0_sa_cb(6)';
NODE_NAME     U2 N54
 '@S9S_MB_2U_LIB.S9S_MB_2U(SCH_1):PAGE21_I169@PURE_QUANTA.SOCKET4677_AZIF0045P001C01CS(CHIPS)':
 'DDR1_SA_ECC6': CDS_PINID='DDR1_SA_ECC6';
NODE_NAME     J4 203
 '@S9S_MB_2U_LIB.S9S_MB_2U(SCH_1):PAGE85_I23@PURE_QUANTA.SCONN288_ADR50017P087CC(CHIPS)':
 'CB6_A': CDS_PINID='CB6_A';
NODE_NAME     J3 203
 '@S9S_MB_2U_LIB.S9S_MB_2U(SCH_1):PAGE84_I180@PURE_QUANTA.SCONN288_ADR50017P130CC(CHIPS)':
 'CB6_A': CDS_PINID='CB6_A';
NET_NAME
'M_B_CPU0_SA_CB<7>'
 '@S9S_MB_2U_LIB.S9S_MB_2U(SCH_1):M_B_CPU0_SA_CB'<7>:
 C_SIGNAL='@s9s_mb_2u_lib.s9s_mb_2u(sch_1):m_b_cpu0_sa_cb(7)';
NODE_NAME     U2 M53
 '@S9S_MB_2U_LIB.S9S_MB_2U(SCH_1):PAGE21_I169@PURE_QUANTA.SOCKET4677_AZIF0045P001C01CS(CHIPS)':
 'DDR1_SA_ECC7': CDS_PINID='DDR1_SA_ECC7';
NODE_NAME     J4 205
 '@S9S_MB_2U_LIB.S9S_MB_2U(SCH_1):PAGE85_I23@PURE_QUANTA.SCONN288_ADR50017P087CC(CHIPS)':
 'CB7_A': CDS_PINID='CB7_A';
NODE_NAME     J3 205
 '@S9S_MB_2U_LIB.S9S_MB_2U(SCH_1):PAGE84_I180@PURE_QUANTA.SCONN288_ADR50017P130CC(CHIPS)':
 'CB7_A': CDS_PINID='CB7_A';
NET_NAME
'M_B_CPU0_SA_CS_N<0>'
 '@S9S_MB_2U_LIB.S9S_MB_2U(SCH_1):M_B_CPU0_SA_CS_N'<0>:
 C_SIGNAL='@s9s_mb_2u_lib.s9s_mb_2u(sch_1):m_b_cpu0_sa_cs_n(0)';
NODE_NAME     U2 K51
 '@S9S_MB_2U_LIB.S9S_MB_2U(SCH_1):PAGE21_I169@PURE_QUANTA.SOCKET4677_AZIF0045P001C01CS(CHIPS)':
 'DDR1_SA_CS_N0': CDS_PINID='DDR1_SA_CS_N0';
NODE_NAME     J3 64
 '@S9S_MB_2U_LIB.S9S_MB_2U(SCH_1):PAGE84_I180@PURE_QUANTA.SCONN288_ADR50017P130CC(CHIPS)':
 'CS0_A_N': CDS_PINID='CS0_A_N';
NET_NAME
'M_B_CPU0_SA_CS_N<1>'
 '@S9S_MB_2U_LIB.S9S_MB_2U(SCH_1):M_B_CPU0_SA_CS_N'<1>:
 C_SIGNAL='@s9s_mb_2u_lib.s9s_mb_2u(sch_1):m_b_cpu0_sa_cs_n(1)';
NODE_NAME     U2 J50
 '@S9S_MB_2U_LIB.S9S_MB_2U(SCH_1):PAGE21_I169@PURE_QUANTA.SOCKET4677_AZIF0045P001C01CS(CHIPS)':
 'DDR1_SA_CS_N1': CDS_PINID='DDR1_SA_CS_N1';
NODE_NAME     J3 209
 '@S9S_MB_2U_LIB.S9S_MB_2U(SCH_1):PAGE84_I180@PURE_QUANTA.SCONN288_ADR50017P130CC(CHIPS)':
 'CS1_A_N': CDS_PINID='CS1_A_N';
NET_NAME
'M_B_CPU0_SA_CS_N<2>'
 '@S9S_MB_2U_LIB.S9S_MB_2U(SCH_1):M_B_CPU0_SA_CS_N'<2>:
 C_SIGNAL='@s9s_mb_2u_lib.s9s_mb_2u(sch_1):m_b_cpu0_sa_cs_n(2)';
NODE_NAME     U2 M51
 '@S9S_MB_2U_LIB.S9S_MB_2U(SCH_1):PAGE21_I169@PURE_QUANTA.SOCKET4677_AZIF0045P001C01CS(CHIPS)':
 'DDR1_SA_CS_N2': CDS_PINID='DDR1_SA_CS_N2';
NODE_NAME     J4 64
 '@S9S_MB_2U_LIB.S9S_MB_2U(SCH_1):PAGE85_I23@PURE_QUANTA.SCONN288_ADR50017P087CC(CHIPS)':
 'CS0_A_N': CDS_PINID='CS0_A_N';
NET_NAME
'M_B_CPU0_SA_CS_N<3>'
 '@S9S_MB_2U_LIB.S9S_MB_2U(SCH_1):M_B_CPU0_SA_CS_N'<3>:
 C_SIGNAL='@s9s_mb_2u_lib.s9s_mb_2u(sch_1):m_b_cpu0_sa_cs_n(3)';
NODE_NAME     U2 N50
 '@S9S_MB_2U_LIB.S9S_MB_2U(SCH_1):PAGE21_I169@PURE_QUANTA.SOCKET4677_AZIF0045P001C01CS(CHIPS)':
 'DDR1_SA_CS_N3': CDS_PINID='DDR1_SA_CS_N3';
NODE_NAME     J4 209
 '@S9S_MB_2U_LIB.S9S_MB_2U(SCH_1):PAGE85_I23@PURE_QUANTA.SCONN288_ADR50017P087CC(CHIPS)':
 'CS1_A_N': CDS_PINID='CS1_A_N';
NET_NAME
'M_B_CPU0_SA_DQ<0>'
 '@S9S_MB_2U_LIB.S9S_MB_2U(SCH_1):M_B_CPU0_SA_DQ'<0>:
 C_SIGNAL='@s9s_mb_2u_lib.s9s_mb_2u(sch_1):m_b_cpu0_sa_dq(0)';
NODE_NAME     U2 K75
 '@S9S_MB_2U_LIB.S9S_MB_2U(SCH_1):PAGE21_I169@PURE_QUANTA.SOCKET4677_AZIF0045P001C01CS(CHIPS)':
 'DDR1_SA_DQ0': CDS_PINID='DDR1_SA_DQ0';
NODE_NAME     J4 7
 '@S9S_MB_2U_LIB.S9S_MB_2U(SCH_1):PAGE85_I23@PURE_QUANTA.SCONN288_ADR50017P087CC(CHIPS)':
 'DQ0_A': CDS_PINID='DQ0_A';
NODE_NAME     J3 7
 '@S9S_MB_2U_LIB.S9S_MB_2U(SCH_1):PAGE84_I180@PURE_QUANTA.SCONN288_ADR50017P130CC(CHIPS)':
 'DQ0_A': CDS_PINID='DQ0_A';
NET_NAME
'M_B_CPU0_SA_DQ<10>'
 '@S9S_MB_2U_LIB.S9S_MB_2U(SCH_1):M_B_CPU0_SA_DQ'<10>:
 C_SIGNAL='@s9s_mb_2u_lib.s9s_mb_2u(sch_1):m_b_cpu0_sa_dq(10)';
NODE_NAME     U2 W72
 '@S9S_MB_2U_LIB.S9S_MB_2U(SCH_1):PAGE21_I169@PURE_QUANTA.SOCKET4677_AZIF0045P001C01CS(CHIPS)':
 'DDR1_SA_DQ10': CDS_PINID='DDR1_SA_DQ10';
NODE_NAME     J4 163
 '@S9S_MB_2U_LIB.S9S_MB_2U(SCH_1):PAGE85_I23@PURE_QUANTA.SCONN288_ADR50017P087CC(CHIPS)':
 'DQ10_A': CDS_PINID='DQ10_A';
NODE_NAME     J3 163
 '@S9S_MB_2U_LIB.S9S_MB_2U(SCH_1):PAGE84_I180@PURE_QUANTA.SCONN288_ADR50017P130CC(CHIPS)':
 'DQ10_A': CDS_PINID='DQ10_A';
NET_NAME
'M_B_CPU0_SA_DQ<11>'
 '@S9S_MB_2U_LIB.S9S_MB_2U(SCH_1):M_B_CPU0_SA_DQ'<11>:
 C_SIGNAL='@s9s_mb_2u_lib.s9s_mb_2u(sch_1):m_b_cpu0_sa_dq(11)';
NODE_NAME     U2 Y71
 '@S9S_MB_2U_LIB.S9S_MB_2U(SCH_1):PAGE21_I169@PURE_QUANTA.SOCKET4677_AZIF0045P001C01CS(CHIPS)':
 'DDR1_SA_DQ11': CDS_PINID='DDR1_SA_DQ11';
NODE_NAME     J4 165
 '@S9S_MB_2U_LIB.S9S_MB_2U(SCH_1):PAGE85_I23@PURE_QUANTA.SCONN288_ADR50017P087CC(CHIPS)':
 'DQ11_A': CDS_PINID='DQ11_A';
NODE_NAME     J3 165
 '@S9S_MB_2U_LIB.S9S_MB_2U(SCH_1):PAGE84_I180@PURE_QUANTA.SCONN288_ADR50017P130CC(CHIPS)':
 'DQ11_A': CDS_PINID='DQ11_A';
NET_NAME
'M_B_CPU0_SA_DQ<12>'
 '@S9S_MB_2U_LIB.S9S_MB_2U(SCH_1):M_B_CPU0_SA_DQ'<12>:
 C_SIGNAL='@s9s_mb_2u_lib.s9s_mb_2u(sch_1):m_b_cpu0_sa_dq(12)';
NODE_NAME     U2 T69
 '@S9S_MB_2U_LIB.S9S_MB_2U(SCH_1):PAGE21_I169@PURE_QUANTA.SOCKET4677_AZIF0045P001C01CS(CHIPS)':
 'DDR1_SA_DQ12': CDS_PINID='DDR1_SA_DQ12';
NODE_NAME     J4 25
 '@S9S_MB_2U_LIB.S9S_MB_2U(SCH_1):PAGE85_I23@PURE_QUANTA.SCONN288_ADR50017P087CC(CHIPS)':
 'DQ12_A': CDS_PINID='DQ12_A';
NODE_NAME     J3 25
 '@S9S_MB_2U_LIB.S9S_MB_2U(SCH_1):PAGE84_I180@PURE_QUANTA.SCONN288_ADR50017P130CC(CHIPS)':
 'DQ12_A': CDS_PINID='DQ12_A';
NET_NAME
'M_B_CPU0_SA_DQ<13>'
 '@S9S_MB_2U_LIB.S9S_MB_2U(SCH_1):M_B_CPU0_SA_DQ'<13>:
 C_SIGNAL='@s9s_mb_2u_lib.s9s_mb_2u(sch_1):m_b_cpu0_sa_dq(13)';
NODE_NAME     U2 U68
 '@S9S_MB_2U_LIB.S9S_MB_2U(SCH_1):PAGE21_I169@PURE_QUANTA.SOCKET4677_AZIF0045P001C01CS(CHIPS)':
 'DDR1_SA_DQ13': CDS_PINID='DDR1_SA_DQ13';
NODE_NAME     J4 27
 '@S9S_MB_2U_LIB.S9S_MB_2U(SCH_1):PAGE85_I23@PURE_QUANTA.SCONN288_ADR50017P087CC(CHIPS)':
 'DQ13_A': CDS_PINID='DQ13_A';
NODE_NAME     J3 27
 '@S9S_MB_2U_LIB.S9S_MB_2U(SCH_1):PAGE84_I180@PURE_QUANTA.SCONN288_ADR50017P130CC(CHIPS)':
 'DQ13_A': CDS_PINID='DQ13_A';
NET_NAME
'M_B_CPU0_SA_DQ<14>'
 '@S9S_MB_2U_LIB.S9S_MB_2U(SCH_1):M_B_CPU0_SA_DQ'<14>:
 C_SIGNAL='@s9s_mb_2u_lib.s9s_mb_2u(sch_1):m_b_cpu0_sa_dq(14)';
NODE_NAME     U2 Y69
 '@S9S_MB_2U_LIB.S9S_MB_2U(SCH_1):PAGE21_I169@PURE_QUANTA.SOCKET4677_AZIF0045P001C01CS(CHIPS)':
 'DDR1_SA_DQ14': CDS_PINID='DDR1_SA_DQ14';
NODE_NAME     J4 170
 '@S9S_MB_2U_LIB.S9S_MB_2U(SCH_1):PAGE85_I23@PURE_QUANTA.SCONN288_ADR50017P087CC(CHIPS)':
 'DQ14_A': CDS_PINID='DQ14_A';
NODE_NAME     J3 170
 '@S9S_MB_2U_LIB.S9S_MB_2U(SCH_1):PAGE84_I180@PURE_QUANTA.SCONN288_ADR50017P130CC(CHIPS)':
 'DQ14_A': CDS_PINID='DQ14_A';
NET_NAME
'M_B_CPU0_SA_DQ<15>'
 '@S9S_MB_2U_LIB.S9S_MB_2U(SCH_1):M_B_CPU0_SA_DQ'<15>:
 C_SIGNAL='@s9s_mb_2u_lib.s9s_mb_2u(sch_1):m_b_cpu0_sa_dq(15)';
NODE_NAME     U2 W68
 '@S9S_MB_2U_LIB.S9S_MB_2U(SCH_1):PAGE21_I169@PURE_QUANTA.SOCKET4677_AZIF0045P001C01CS(CHIPS)':
 'DDR1_SA_DQ15': CDS_PINID='DDR1_SA_DQ15';
NODE_NAME     J4 172
 '@S9S_MB_2U_LIB.S9S_MB_2U(SCH_1):PAGE85_I23@PURE_QUANTA.SCONN288_ADR50017P087CC(CHIPS)':
 'DQ15_A': CDS_PINID='DQ15_A';
NODE_NAME     J3 172
 '@S9S_MB_2U_LIB.S9S_MB_2U(SCH_1):PAGE84_I180@PURE_QUANTA.SCONN288_ADR50017P130CC(CHIPS)':
 'DQ15_A': CDS_PINID='DQ15_A';
NET_NAME
'M_B_CPU0_SA_DQ<16>'
 '@S9S_MB_2U_LIB.S9S_MB_2U(SCH_1):M_B_CPU0_SA_DQ'<16>:
 C_SIGNAL='@s9s_mb_2u_lib.s9s_mb_2u(sch_1):m_b_cpu0_sa_dq(16)';
NODE_NAME     U2 K63
 '@S9S_MB_2U_LIB.S9S_MB_2U(SCH_1):PAGE21_I169@PURE_QUANTA.SOCKET4677_AZIF0045P001C01CS(CHIPS)':
 'DDR1_SA_DQ16': CDS_PINID='DDR1_SA_DQ16';
NODE_NAME     J4 29
 '@S9S_MB_2U_LIB.S9S_MB_2U(SCH_1):PAGE85_I23@PURE_QUANTA.SCONN288_ADR50017P087CC(CHIPS)':
 'DQ16_A': CDS_PINID='DQ16_A';
NODE_NAME     J3 29
 '@S9S_MB_2U_LIB.S9S_MB_2U(SCH_1):PAGE84_I180@PURE_QUANTA.SCONN288_ADR50017P130CC(CHIPS)':
 'DQ16_A': CDS_PINID='DQ16_A';
NET_NAME
'M_B_CPU0_SA_DQ<17>'
 '@S9S_MB_2U_LIB.S9S_MB_2U(SCH_1):M_B_CPU0_SA_DQ'<17>:
 C_SIGNAL='@s9s_mb_2u_lib.s9s_mb_2u(sch_1):m_b_cpu0_sa_dq(17)';
NODE_NAME     U2 J62
 '@S9S_MB_2U_LIB.S9S_MB_2U(SCH_1):PAGE21_I169@PURE_QUANTA.SOCKET4677_AZIF0045P001C01CS(CHIPS)':
 'DDR1_SA_DQ17': CDS_PINID='DDR1_SA_DQ17';
NODE_NAME     J4 31
 '@S9S_MB_2U_LIB.S9S_MB_2U(SCH_1):PAGE85_I23@PURE_QUANTA.SCONN288_ADR50017P087CC(CHIPS)':
 'DQ17_A': CDS_PINID='DQ17_A';
NODE_NAME     J3 31
 '@S9S_MB_2U_LIB.S9S_MB_2U(SCH_1):PAGE84_I180@PURE_QUANTA.SCONN288_ADR50017P130CC(CHIPS)':
 'DQ17_A': CDS_PINID='DQ17_A';
NET_NAME
'M_B_CPU0_SA_DQ<18>'
 '@S9S_MB_2U_LIB.S9S_MB_2U(SCH_1):M_B_CPU0_SA_DQ'<18>:
 C_SIGNAL='@s9s_mb_2u_lib.s9s_mb_2u(sch_1):m_b_cpu0_sa_dq(18)';
NODE_NAME     U2 M63
 '@S9S_MB_2U_LIB.S9S_MB_2U(SCH_1):PAGE21_I169@PURE_QUANTA.SOCKET4677_AZIF0045P001C01CS(CHIPS)':
 'DDR1_SA_DQ18': CDS_PINID='DDR1_SA_DQ18';
NODE_NAME     J4 174
 '@S9S_MB_2U_LIB.S9S_MB_2U(SCH_1):PAGE85_I23@PURE_QUANTA.SCONN288_ADR50017P087CC(CHIPS)':
 'DQ18_A': CDS_PINID='DQ18_A';
NODE_NAME     J3 174
 '@S9S_MB_2U_LIB.S9S_MB_2U(SCH_1):PAGE84_I180@PURE_QUANTA.SCONN288_ADR50017P130CC(CHIPS)':
 'DQ18_A': CDS_PINID='DQ18_A';
NET_NAME
'M_B_CPU0_SA_DQ<19>'
 '@S9S_MB_2U_LIB.S9S_MB_2U(SCH_1):M_B_CPU0_SA_DQ'<19>:
 C_SIGNAL='@s9s_mb_2u_lib.s9s_mb_2u(sch_1):m_b_cpu0_sa_dq(19)';
NODE_NAME     U2 N62
 '@S9S_MB_2U_LIB.S9S_MB_2U(SCH_1):PAGE21_I169@PURE_QUANTA.SOCKET4677_AZIF0045P001C01CS(CHIPS)':
 'DDR1_SA_DQ19': CDS_PINID='DDR1_SA_DQ19';
NODE_NAME     J4 176
 '@S9S_MB_2U_LIB.S9S_MB_2U(SCH_1):PAGE85_I23@PURE_QUANTA.SCONN288_ADR50017P087CC(CHIPS)':
 'DQ19_A': CDS_PINID='DQ19_A';
NODE_NAME     J3 176
 '@S9S_MB_2U_LIB.S9S_MB_2U(SCH_1):PAGE84_I180@PURE_QUANTA.SCONN288_ADR50017P130CC(CHIPS)':
 'DQ19_A': CDS_PINID='DQ19_A';
NET_NAME
'M_B_CPU0_SA_DQ<1>'
 '@S9S_MB_2U_LIB.S9S_MB_2U(SCH_1):M_B_CPU0_SA_DQ'<1>:
 C_SIGNAL='@s9s_mb_2u_lib.s9s_mb_2u(sch_1):m_b_cpu0_sa_dq(1)';
NODE_NAME     U2 J74
 '@S9S_MB_2U_LIB.S9S_MB_2U(SCH_1):PAGE21_I169@PURE_QUANTA.SOCKET4677_AZIF0045P001C01CS(CHIPS)':
 'DDR1_SA_DQ1': CDS_PINID='DDR1_SA_DQ1';
NODE_NAME     J4 9
 '@S9S_MB_2U_LIB.S9S_MB_2U(SCH_1):PAGE85_I23@PURE_QUANTA.SCONN288_ADR50017P087CC(CHIPS)':
 'DQ1_A': CDS_PINID='DQ1_A';
NODE_NAME     J3 9
 '@S9S_MB_2U_LIB.S9S_MB_2U(SCH_1):PAGE84_I180@PURE_QUANTA.SCONN288_ADR50017P130CC(CHIPS)':
 'DQ1_A': CDS_PINID='DQ1_A';
NET_NAME
'M_B_CPU0_SA_DQ<20>'
 '@S9S_MB_2U_LIB.S9S_MB_2U(SCH_1):M_B_CPU0_SA_DQ'<20>:
 C_SIGNAL='@s9s_mb_2u_lib.s9s_mb_2u(sch_1):m_b_cpu0_sa_dq(20)';
NODE_NAME     U2 J60
 '@S9S_MB_2U_LIB.S9S_MB_2U(SCH_1):PAGE21_I169@PURE_QUANTA.SOCKET4677_AZIF0045P001C01CS(CHIPS)':
 'DDR1_SA_DQ20': CDS_PINID='DDR1_SA_DQ20';
NODE_NAME     J4 36
 '@S9S_MB_2U_LIB.S9S_MB_2U(SCH_1):PAGE85_I23@PURE_QUANTA.SCONN288_ADR50017P087CC(CHIPS)':
 'DQ20_A': CDS_PINID='DQ20_A';
NODE_NAME     J3 36
 '@S9S_MB_2U_LIB.S9S_MB_2U(SCH_1):PAGE84_I180@PURE_QUANTA.SCONN288_ADR50017P130CC(CHIPS)':
 'DQ20_A': CDS_PINID='DQ20_A';
NET_NAME
'M_B_CPU0_SA_DQ<21>'
 '@S9S_MB_2U_LIB.S9S_MB_2U(SCH_1):M_B_CPU0_SA_DQ'<21>:
 C_SIGNAL='@s9s_mb_2u_lib.s9s_mb_2u(sch_1):m_b_cpu0_sa_dq(21)';
NODE_NAME     U2 K59
 '@S9S_MB_2U_LIB.S9S_MB_2U(SCH_1):PAGE21_I169@PURE_QUANTA.SOCKET4677_AZIF0045P001C01CS(CHIPS)':
 'DDR1_SA_DQ21': CDS_PINID='DDR1_SA_DQ21';
NODE_NAME     J4 38
 '@S9S_MB_2U_LIB.S9S_MB_2U(SCH_1):PAGE85_I23@PURE_QUANTA.SCONN288_ADR50017P087CC(CHIPS)':
 'DQ21_A': CDS_PINID='DQ21_A';
NODE_NAME     J3 38
 '@S9S_MB_2U_LIB.S9S_MB_2U(SCH_1):PAGE84_I180@PURE_QUANTA.SCONN288_ADR50017P130CC(CHIPS)':
 'DQ21_A': CDS_PINID='DQ21_A';
NET_NAME
'M_B_CPU0_SA_DQ<22>'
 '@S9S_MB_2U_LIB.S9S_MB_2U(SCH_1):M_B_CPU0_SA_DQ'<22>:
 C_SIGNAL='@s9s_mb_2u_lib.s9s_mb_2u(sch_1):m_b_cpu0_sa_dq(22)';
NODE_NAME     U2 N60
 '@S9S_MB_2U_LIB.S9S_MB_2U(SCH_1):PAGE21_I169@PURE_QUANTA.SOCKET4677_AZIF0045P001C01CS(CHIPS)':
 'DDR1_SA_DQ22': CDS_PINID='DDR1_SA_DQ22';
NODE_NAME     J4 181
 '@S9S_MB_2U_LIB.S9S_MB_2U(SCH_1):PAGE85_I23@PURE_QUANTA.SCONN288_ADR50017P087CC(CHIPS)':
 'DQ22_A': CDS_PINID='DQ22_A';
NODE_NAME     J3 181
 '@S9S_MB_2U_LIB.S9S_MB_2U(SCH_1):PAGE84_I180@PURE_QUANTA.SCONN288_ADR50017P130CC(CHIPS)':
 'DQ22_A': CDS_PINID='DQ22_A';
NET_NAME
'M_B_CPU0_SA_DQ<23>'
 '@S9S_MB_2U_LIB.S9S_MB_2U(SCH_1):M_B_CPU0_SA_DQ'<23>:
 C_SIGNAL='@s9s_mb_2u_lib.s9s_mb_2u(sch_1):m_b_cpu0_sa_dq(23)';
NODE_NAME     U2 M59
 '@S9S_MB_2U_LIB.S9S_MB_2U(SCH_1):PAGE21_I169@PURE_QUANTA.SOCKET4677_AZIF0045P001C01CS(CHIPS)':
 'DDR1_SA_DQ23': CDS_PINID='DDR1_SA_DQ23';
NODE_NAME     J4 183
 '@S9S_MB_2U_LIB.S9S_MB_2U(SCH_1):PAGE85_I23@PURE_QUANTA.SCONN288_ADR50017P087CC(CHIPS)':
 'DQ23_A': CDS_PINID='DQ23_A';
NODE_NAME     J3 183
 '@S9S_MB_2U_LIB.S9S_MB_2U(SCH_1):PAGE84_I180@PURE_QUANTA.SCONN288_ADR50017P130CC(CHIPS)':
 'DQ23_A': CDS_PINID='DQ23_A';
NET_NAME
'M_B_CPU0_SA_DQ<24>'
 '@S9S_MB_2U_LIB.S9S_MB_2U(SCH_1):M_B_CPU0_SA_DQ'<24>:
 C_SIGNAL='@s9s_mb_2u_lib.s9s_mb_2u(sch_1):m_b_cpu0_sa_dq(24)';
NODE_NAME     U2 U60
 '@S9S_MB_2U_LIB.S9S_MB_2U(SCH_1):PAGE21_I169@PURE_QUANTA.SOCKET4677_AZIF0045P001C01CS(CHIPS)':
 'DDR1_SA_DQ24': CDS_PINID='DDR1_SA_DQ24';
NODE_NAME     J4 40
 '@S9S_MB_2U_LIB.S9S_MB_2U(SCH_1):PAGE85_I23@PURE_QUANTA.SCONN288_ADR50017P087CC(CHIPS)':
 'DQ24_A': CDS_PINID='DQ24_A';
NODE_NAME     J3 40
 '@S9S_MB_2U_LIB.S9S_MB_2U(SCH_1):PAGE84_I180@PURE_QUANTA.SCONN288_ADR50017P130CC(CHIPS)':
 'DQ24_A': CDS_PINID='DQ24_A';
NET_NAME
'M_B_CPU0_SA_DQ<25>'
 '@S9S_MB_2U_LIB.S9S_MB_2U(SCH_1):M_B_CPU0_SA_DQ'<25>:
 C_SIGNAL='@s9s_mb_2u_lib.s9s_mb_2u(sch_1):m_b_cpu0_sa_dq(25)';
NODE_NAME     U2 T59
 '@S9S_MB_2U_LIB.S9S_MB_2U(SCH_1):PAGE21_I169@PURE_QUANTA.SOCKET4677_AZIF0045P001C01CS(CHIPS)':
 'DDR1_SA_DQ25': CDS_PINID='DDR1_SA_DQ25';
NODE_NAME     J4 42
 '@S9S_MB_2U_LIB.S9S_MB_2U(SCH_1):PAGE85_I23@PURE_QUANTA.SCONN288_ADR50017P087CC(CHIPS)':
 'DQ25_A': CDS_PINID='DQ25_A';
NODE_NAME     J3 42
 '@S9S_MB_2U_LIB.S9S_MB_2U(SCH_1):PAGE84_I180@PURE_QUANTA.SCONN288_ADR50017P130CC(CHIPS)':
 'DQ25_A': CDS_PINID='DQ25_A';
NET_NAME
'M_B_CPU0_SA_DQ<26>'
 '@S9S_MB_2U_LIB.S9S_MB_2U(SCH_1):M_B_CPU0_SA_DQ'<26>:
 C_SIGNAL='@s9s_mb_2u_lib.s9s_mb_2u(sch_1):m_b_cpu0_sa_dq(26)';
NODE_NAME     U2 W60
 '@S9S_MB_2U_LIB.S9S_MB_2U(SCH_1):PAGE21_I169@PURE_QUANTA.SOCKET4677_AZIF0045P001C01CS(CHIPS)':
 'DDR1_SA_DQ26': CDS_PINID='DDR1_SA_DQ26';
NODE_NAME     J4 185
 '@S9S_MB_2U_LIB.S9S_MB_2U(SCH_1):PAGE85_I23@PURE_QUANTA.SCONN288_ADR50017P087CC(CHIPS)':
 'DQ26_A': CDS_PINID='DQ26_A';
NODE_NAME     J3 185
 '@S9S_MB_2U_LIB.S9S_MB_2U(SCH_1):PAGE84_I180@PURE_QUANTA.SCONN288_ADR50017P130CC(CHIPS)':
 'DQ26_A': CDS_PINID='DQ26_A';
NET_NAME
'M_B_CPU0_SA_DQ<27>'
 '@S9S_MB_2U_LIB.S9S_MB_2U(SCH_1):M_B_CPU0_SA_DQ'<27>:
 C_SIGNAL='@s9s_mb_2u_lib.s9s_mb_2u(sch_1):m_b_cpu0_sa_dq(27)';
NODE_NAME     U2 Y59
 '@S9S_MB_2U_LIB.S9S_MB_2U(SCH_1):PAGE21_I169@PURE_QUANTA.SOCKET4677_AZIF0045P001C01CS(CHIPS)':
 'DDR1_SA_DQ27': CDS_PINID='DDR1_SA_DQ27';
NODE_NAME     J4 187
 '@S9S_MB_2U_LIB.S9S_MB_2U(SCH_1):PAGE85_I23@PURE_QUANTA.SCONN288_ADR50017P087CC(CHIPS)':
 'DQ27_A': CDS_PINID='DQ27_A';
NODE_NAME     J3 187
 '@S9S_MB_2U_LIB.S9S_MB_2U(SCH_1):PAGE84_I180@PURE_QUANTA.SCONN288_ADR50017P130CC(CHIPS)':
 'DQ27_A': CDS_PINID='DQ27_A';
NET_NAME
'M_B_CPU0_SA_DQ<28>'
 '@S9S_MB_2U_LIB.S9S_MB_2U(SCH_1):M_B_CPU0_SA_DQ'<28>:
 C_SIGNAL='@s9s_mb_2u_lib.s9s_mb_2u(sch_1):m_b_cpu0_sa_dq(28)';
NODE_NAME     U2 T57
 '@S9S_MB_2U_LIB.S9S_MB_2U(SCH_1):PAGE21_I169@PURE_QUANTA.SOCKET4677_AZIF0045P001C01CS(CHIPS)':
 'DDR1_SA_DQ28': CDS_PINID='DDR1_SA_DQ28';
NODE_NAME     J4 47
 '@S9S_MB_2U_LIB.S9S_MB_2U(SCH_1):PAGE85_I23@PURE_QUANTA.SCONN288_ADR50017P087CC(CHIPS)':
 'DQ28_A': CDS_PINID='DQ28_A';
NODE_NAME     J3 47
 '@S9S_MB_2U_LIB.S9S_MB_2U(SCH_1):PAGE84_I180@PURE_QUANTA.SCONN288_ADR50017P130CC(CHIPS)':
 'DQ28_A': CDS_PINID='DQ28_A';
NET_NAME
'M_B_CPU0_SA_DQ<29>'
 '@S9S_MB_2U_LIB.S9S_MB_2U(SCH_1):M_B_CPU0_SA_DQ'<29>:
 C_SIGNAL='@s9s_mb_2u_lib.s9s_mb_2u(sch_1):m_b_cpu0_sa_dq(29)';
NODE_NAME     U2 U56
 '@S9S_MB_2U_LIB.S9S_MB_2U(SCH_1):PAGE21_I169@PURE_QUANTA.SOCKET4677_AZIF0045P001C01CS(CHIPS)':
 'DDR1_SA_DQ29': CDS_PINID='DDR1_SA_DQ29';
NODE_NAME     J4 49
 '@S9S_MB_2U_LIB.S9S_MB_2U(SCH_1):PAGE85_I23@PURE_QUANTA.SCONN288_ADR50017P087CC(CHIPS)':
 'DQ29_A': CDS_PINID='DQ29_A';
NODE_NAME     J3 49
 '@S9S_MB_2U_LIB.S9S_MB_2U(SCH_1):PAGE84_I180@PURE_QUANTA.SCONN288_ADR50017P130CC(CHIPS)':
 'DQ29_A': CDS_PINID='DQ29_A';
NET_NAME
'M_B_CPU0_SA_DQ<2>'
 '@S9S_MB_2U_LIB.S9S_MB_2U(SCH_1):M_B_CPU0_SA_DQ'<2>:
 C_SIGNAL='@s9s_mb_2u_lib.s9s_mb_2u(sch_1):m_b_cpu0_sa_dq(2)';
NODE_NAME     U2 M75
 '@S9S_MB_2U_LIB.S9S_MB_2U(SCH_1):PAGE21_I169@PURE_QUANTA.SOCKET4677_AZIF0045P001C01CS(CHIPS)':
 'DDR1_SA_DQ2': CDS_PINID='DDR1_SA_DQ2';
NODE_NAME     J4 152
 '@S9S_MB_2U_LIB.S9S_MB_2U(SCH_1):PAGE85_I23@PURE_QUANTA.SCONN288_ADR50017P087CC(CHIPS)':
 'DQ2_A': CDS_PINID='DQ2_A';
NODE_NAME     J3 152
 '@S9S_MB_2U_LIB.S9S_MB_2U(SCH_1):PAGE84_I180@PURE_QUANTA.SCONN288_ADR50017P130CC(CHIPS)':
 'DQ2_A': CDS_PINID='DQ2_A';
NET_NAME
'M_B_CPU0_SA_DQ<30>'
 '@S9S_MB_2U_LIB.S9S_MB_2U(SCH_1):M_B_CPU0_SA_DQ'<30>:
 C_SIGNAL='@s9s_mb_2u_lib.s9s_mb_2u(sch_1):m_b_cpu0_sa_dq(30)';
NODE_NAME     U2 Y57
 '@S9S_MB_2U_LIB.S9S_MB_2U(SCH_1):PAGE21_I169@PURE_QUANTA.SOCKET4677_AZIF0045P001C01CS(CHIPS)':
 'DDR1_SA_DQ30': CDS_PINID='DDR1_SA_DQ30';
NODE_NAME     J4 192
 '@S9S_MB_2U_LIB.S9S_MB_2U(SCH_1):PAGE85_I23@PURE_QUANTA.SCONN288_ADR50017P087CC(CHIPS)':
 'DQ30_A': CDS_PINID='DQ30_A';
NODE_NAME     J3 192
 '@S9S_MB_2U_LIB.S9S_MB_2U(SCH_1):PAGE84_I180@PURE_QUANTA.SCONN288_ADR50017P130CC(CHIPS)':
 'DQ30_A': CDS_PINID='DQ30_A';
NET_NAME
'M_B_CPU0_SA_DQ<31>'
 '@S9S_MB_2U_LIB.S9S_MB_2U(SCH_1):M_B_CPU0_SA_DQ'<31>:
 C_SIGNAL='@s9s_mb_2u_lib.s9s_mb_2u(sch_1):m_b_cpu0_sa_dq(31)';
NODE_NAME     U2 W56
 '@S9S_MB_2U_LIB.S9S_MB_2U(SCH_1):PAGE21_I169@PURE_QUANTA.SOCKET4677_AZIF0045P001C01CS(CHIPS)':
 'DDR1_SA_DQ31': CDS_PINID='DDR1_SA_DQ31';
NODE_NAME     J4 194
 '@S9S_MB_2U_LIB.S9S_MB_2U(SCH_1):PAGE85_I23@PURE_QUANTA.SCONN288_ADR50017P087CC(CHIPS)':
 'DQ31_A': CDS_PINID='DQ31_A';
NODE_NAME     J3 194
 '@S9S_MB_2U_LIB.S9S_MB_2U(SCH_1):PAGE84_I180@PURE_QUANTA.SCONN288_ADR50017P130CC(CHIPS)':
 'DQ31_A': CDS_PINID='DQ31_A';
NET_NAME
'M_B_CPU0_SA_DQ<3>'
 '@S9S_MB_2U_LIB.S9S_MB_2U(SCH_1):M_B_CPU0_SA_DQ'<3>:
 C_SIGNAL='@s9s_mb_2u_lib.s9s_mb_2u(sch_1):m_b_cpu0_sa_dq(3)';
NODE_NAME     U2 N74
 '@S9S_MB_2U_LIB.S9S_MB_2U(SCH_1):PAGE21_I169@PURE_QUANTA.SOCKET4677_AZIF0045P001C01CS(CHIPS)':
 'DDR1_SA_DQ3': CDS_PINID='DDR1_SA_DQ3';
NODE_NAME     J4 154
 '@S9S_MB_2U_LIB.S9S_MB_2U(SCH_1):PAGE85_I23@PURE_QUANTA.SCONN288_ADR50017P087CC(CHIPS)':
 'DQ3_A': CDS_PINID='DQ3_A';
NODE_NAME     J3 154
 '@S9S_MB_2U_LIB.S9S_MB_2U(SCH_1):PAGE84_I180@PURE_QUANTA.SCONN288_ADR50017P130CC(CHIPS)':
 'DQ3_A': CDS_PINID='DQ3_A';
NET_NAME
'M_B_CPU0_SA_DQ<4>'
 '@S9S_MB_2U_LIB.S9S_MB_2U(SCH_1):M_B_CPU0_SA_DQ'<4>:
 C_SIGNAL='@s9s_mb_2u_lib.s9s_mb_2u(sch_1):m_b_cpu0_sa_dq(4)';
NODE_NAME     U2 J72
 '@S9S_MB_2U_LIB.S9S_MB_2U(SCH_1):PAGE21_I169@PURE_QUANTA.SOCKET4677_AZIF0045P001C01CS(CHIPS)':
 'DDR1_SA_DQ4': CDS_PINID='DDR1_SA_DQ4';
NODE_NAME     J4 14
 '@S9S_MB_2U_LIB.S9S_MB_2U(SCH_1):PAGE85_I23@PURE_QUANTA.SCONN288_ADR50017P087CC(CHIPS)':
 'DQ4_A': CDS_PINID='DQ4_A';
NODE_NAME     J3 14
 '@S9S_MB_2U_LIB.S9S_MB_2U(SCH_1):PAGE84_I180@PURE_QUANTA.SCONN288_ADR50017P130CC(CHIPS)':
 'DQ4_A': CDS_PINID='DQ4_A';
NET_NAME
'M_B_CPU0_SA_DQ<5>'
 '@S9S_MB_2U_LIB.S9S_MB_2U(SCH_1):M_B_CPU0_SA_DQ'<5>:
 C_SIGNAL='@s9s_mb_2u_lib.s9s_mb_2u(sch_1):m_b_cpu0_sa_dq(5)';
NODE_NAME     U2 K71
 '@S9S_MB_2U_LIB.S9S_MB_2U(SCH_1):PAGE21_I169@PURE_QUANTA.SOCKET4677_AZIF0045P001C01CS(CHIPS)':
 'DDR1_SA_DQ5': CDS_PINID='DDR1_SA_DQ5';
NODE_NAME     J4 16
 '@S9S_MB_2U_LIB.S9S_MB_2U(SCH_1):PAGE85_I23@PURE_QUANTA.SCONN288_ADR50017P087CC(CHIPS)':
 'DQ5_A': CDS_PINID='DQ5_A';
NODE_NAME     J3 16
 '@S9S_MB_2U_LIB.S9S_MB_2U(SCH_1):PAGE84_I180@PURE_QUANTA.SCONN288_ADR50017P130CC(CHIPS)':
 'DQ5_A': CDS_PINID='DQ5_A';
NET_NAME
'M_B_CPU0_SA_DQ<6>'
 '@S9S_MB_2U_LIB.S9S_MB_2U(SCH_1):M_B_CPU0_SA_DQ'<6>:
 C_SIGNAL='@s9s_mb_2u_lib.s9s_mb_2u(sch_1):m_b_cpu0_sa_dq(6)';
NODE_NAME     U2 N72
 '@S9S_MB_2U_LIB.S9S_MB_2U(SCH_1):PAGE21_I169@PURE_QUANTA.SOCKET4677_AZIF0045P001C01CS(CHIPS)':
 'DDR1_SA_DQ6': CDS_PINID='DDR1_SA_DQ6';
NODE_NAME     J4 159
 '@S9S_MB_2U_LIB.S9S_MB_2U(SCH_1):PAGE85_I23@PURE_QUANTA.SCONN288_ADR50017P087CC(CHIPS)':
 'DQ6_A': CDS_PINID='DQ6_A';
NODE_NAME     J3 159
 '@S9S_MB_2U_LIB.S9S_MB_2U(SCH_1):PAGE84_I180@PURE_QUANTA.SCONN288_ADR50017P130CC(CHIPS)':
 'DQ6_A': CDS_PINID='DQ6_A';
NET_NAME
'M_B_CPU0_SA_DQ<7>'
 '@S9S_MB_2U_LIB.S9S_MB_2U(SCH_1):M_B_CPU0_SA_DQ'<7>:
 C_SIGNAL='@s9s_mb_2u_lib.s9s_mb_2u(sch_1):m_b_cpu0_sa_dq(7)';
NODE_NAME     U2 M71
 '@S9S_MB_2U_LIB.S9S_MB_2U(SCH_1):PAGE21_I169@PURE_QUANTA.SOCKET4677_AZIF0045P001C01CS(CHIPS)':
 'DDR1_SA_DQ7': CDS_PINID='DDR1_SA_DQ7';
NODE_NAME     J4 161
 '@S9S_MB_2U_LIB.S9S_MB_2U(SCH_1):PAGE85_I23@PURE_QUANTA.SCONN288_ADR50017P087CC(CHIPS)':
 'DQ7_A': CDS_PINID='DQ7_A';
NODE_NAME     J3 161
 '@S9S_MB_2U_LIB.S9S_MB_2U(SCH_1):PAGE84_I180@PURE_QUANTA.SCONN288_ADR50017P130CC(CHIPS)':
 'DQ7_A': CDS_PINID='DQ7_A';
NET_NAME
'M_B_CPU0_SA_DQ<8>'
 '@S9S_MB_2U_LIB.S9S_MB_2U(SCH_1):M_B_CPU0_SA_DQ'<8>:
 C_SIGNAL='@s9s_mb_2u_lib.s9s_mb_2u(sch_1):m_b_cpu0_sa_dq(8)';
NODE_NAME     U2 U72
 '@S9S_MB_2U_LIB.S9S_MB_2U(SCH_1):PAGE21_I169@PURE_QUANTA.SOCKET4677_AZIF0045P001C01CS(CHIPS)':
 'DDR1_SA_DQ8': CDS_PINID='DDR1_SA_DQ8';
NODE_NAME     J4 18
 '@S9S_MB_2U_LIB.S9S_MB_2U(SCH_1):PAGE85_I23@PURE_QUANTA.SCONN288_ADR50017P087CC(CHIPS)':
 'DQ8_A': CDS_PINID='DQ8_A';
NODE_NAME     J3 18
 '@S9S_MB_2U_LIB.S9S_MB_2U(SCH_1):PAGE84_I180@PURE_QUANTA.SCONN288_ADR50017P130CC(CHIPS)':
 'DQ8_A': CDS_PINID='DQ8_A';
NET_NAME
'M_B_CPU0_SA_DQ<9>'
 '@S9S_MB_2U_LIB.S9S_MB_2U(SCH_1):M_B_CPU0_SA_DQ'<9>:
 C_SIGNAL='@s9s_mb_2u_lib.s9s_mb_2u(sch_1):m_b_cpu0_sa_dq(9)';
NODE_NAME     U2 T71
 '@S9S_MB_2U_LIB.S9S_MB_2U(SCH_1):PAGE21_I169@PURE_QUANTA.SOCKET4677_AZIF0045P001C01CS(CHIPS)':
 'DDR1_SA_DQ9': CDS_PINID='DDR1_SA_DQ9';
NODE_NAME     J4 20
 '@S9S_MB_2U_LIB.S9S_MB_2U(SCH_1):PAGE85_I23@PURE_QUANTA.SCONN288_ADR50017P087CC(CHIPS)':
 'DQ9_A': CDS_PINID='DQ9_A';
NODE_NAME     J3 20
 '@S9S_MB_2U_LIB.S9S_MB_2U(SCH_1):PAGE84_I180@PURE_QUANTA.SCONN288_ADR50017P130CC(CHIPS)':
 'DQ9_A': CDS_PINID='DQ9_A';
NET_NAME
'M_B_CPU0_SA_DQS_DN<0>'
 '@S9S_MB_2U_LIB.S9S_MB_2U(SCH_1):M_B_CPU0_SA_DQS_DN'<0>:
 C_SIGNAL='@s9s_mb_2u_lib.s9s_mb_2u(sch_1):m_b_cpu0_sa_dqs_dn(0)';
NODE_NAME     U2 H73
 '@S9S_MB_2U_LIB.S9S_MB_2U(SCH_1):PAGE21_I169@PURE_QUANTA.SOCKET4677_AZIF0045P001C01CS(CHIPS)':
 'DDR1_SA_DQS_DN0': CDS_PINID='DDR1_SA_DQS_DN0';
NODE_NAME     J4 12
 '@S9S_MB_2U_LIB.S9S_MB_2U(SCH_1):PAGE85_I178@PURE_QUANTA.SCONN288_ADR50017P087CC(CHIPS)':
 'DQS0_A_C': CDS_PINID='DQS0_A_C';
NODE_NAME     J3 12
 '@S9S_MB_2U_LIB.S9S_MB_2U(SCH_1):PAGE84_I179@PURE_QUANTA.SCONN288_ADR50017P130CC(CHIPS)':
 'DQS0_A_C': CDS_PINID='DQS0_A_C';
NET_NAME
'M_B_CPU0_SA_DQS_DN<1>'
 '@S9S_MB_2U_LIB.S9S_MB_2U(SCH_1):M_B_CPU0_SA_DQS_DN'<1>:
 C_SIGNAL='@s9s_mb_2u_lib.s9s_mb_2u(sch_1):m_b_cpu0_sa_dqs_dn(1)';
NODE_NAME     U2 R70
 '@S9S_MB_2U_LIB.S9S_MB_2U(SCH_1):PAGE21_I169@PURE_QUANTA.SOCKET4677_AZIF0045P001C01CS(CHIPS)':
 'DDR1_SA_DQS_DN1': CDS_PINID='DDR1_SA_DQS_DN1';
NODE_NAME     J4 23
 '@S9S_MB_2U_LIB.S9S_MB_2U(SCH_1):PAGE85_I178@PURE_QUANTA.SCONN288_ADR50017P087CC(CHIPS)':
 'DQS1_A_C': CDS_PINID='DQS1_A_C';
NODE_NAME     J3 23
 '@S9S_MB_2U_LIB.S9S_MB_2U(SCH_1):PAGE84_I179@PURE_QUANTA.SCONN288_ADR50017P130CC(CHIPS)':
 'DQS1_A_C': CDS_PINID='DQS1_A_C';
NET_NAME
'M_B_CPU0_SA_DQS_DN<2>'
 '@S9S_MB_2U_LIB.S9S_MB_2U(SCH_1):M_B_CPU0_SA_DQS_DN'<2>:
 C_SIGNAL='@s9s_mb_2u_lib.s9s_mb_2u(sch_1):m_b_cpu0_sa_dqs_dn(2)';
NODE_NAME     U2 H61
 '@S9S_MB_2U_LIB.S9S_MB_2U(SCH_1):PAGE21_I169@PURE_QUANTA.SOCKET4677_AZIF0045P001C01CS(CHIPS)':
 'DDR1_SA_DQS_DN2': CDS_PINID='DDR1_SA_DQS_DN2';
NODE_NAME     J4 34
 '@S9S_MB_2U_LIB.S9S_MB_2U(SCH_1):PAGE85_I178@PURE_QUANTA.SCONN288_ADR50017P087CC(CHIPS)':
 'DQS2_A_C': CDS_PINID='DQS2_A_C';
NODE_NAME     J3 34
 '@S9S_MB_2U_LIB.S9S_MB_2U(SCH_1):PAGE84_I179@PURE_QUANTA.SCONN288_ADR50017P130CC(CHIPS)':
 'DQS2_A_C': CDS_PINID='DQS2_A_C';
NET_NAME
'M_B_CPU0_SA_DQS_DN<3>'
 '@S9S_MB_2U_LIB.S9S_MB_2U(SCH_1):M_B_CPU0_SA_DQS_DN'<3>:
 C_SIGNAL='@s9s_mb_2u_lib.s9s_mb_2u(sch_1):m_b_cpu0_sa_dqs_dn(3)';
NODE_NAME     U2 R58
 '@S9S_MB_2U_LIB.S9S_MB_2U(SCH_1):PAGE21_I169@PURE_QUANTA.SOCKET4677_AZIF0045P001C01CS(CHIPS)':
 'DDR1_SA_DQS_DN3': CDS_PINID='DDR1_SA_DQS_DN3';
NODE_NAME     J4 45
 '@S9S_MB_2U_LIB.S9S_MB_2U(SCH_1):PAGE85_I178@PURE_QUANTA.SCONN288_ADR50017P087CC(CHIPS)':
 'DQS3_A_C': CDS_PINID='DQS3_A_C';
NODE_NAME     J3 45
 '@S9S_MB_2U_LIB.S9S_MB_2U(SCH_1):PAGE84_I179@PURE_QUANTA.SCONN288_ADR50017P130CC(CHIPS)':
 'DQS3_A_C': CDS_PINID='DQS3_A_C';
NET_NAME
'M_B_CPU0_SA_DQS_DN<4>'
 '@S9S_MB_2U_LIB.S9S_MB_2U(SCH_1):M_B_CPU0_SA_DQS_DN'<4>:
 C_SIGNAL='@s9s_mb_2u_lib.s9s_mb_2u(sch_1):m_b_cpu0_sa_dqs_dn(4)';
NODE_NAME     U2 H55
 '@S9S_MB_2U_LIB.S9S_MB_2U(SCH_1):PAGE21_I169@PURE_QUANTA.SOCKET4677_AZIF0045P001C01CS(CHIPS)':
 'DDR1_SA_DQS_DN4': CDS_PINID='DDR1_SA_DQS_DN4';
NODE_NAME     J4 56
 '@S9S_MB_2U_LIB.S9S_MB_2U(SCH_1):PAGE85_I178@PURE_QUANTA.SCONN288_ADR50017P087CC(CHIPS)':
 'DQS4_A_C': CDS_PINID='DQS4_A_C';
NODE_NAME     J3 56
 '@S9S_MB_2U_LIB.S9S_MB_2U(SCH_1):PAGE84_I179@PURE_QUANTA.SCONN288_ADR50017P130CC(CHIPS)':
 'DQS4_A_C': CDS_PINID='DQS4_A_C';
NET_NAME
'M_B_CPU0_SA_DQS_DN<5>'
 '@S9S_MB_2U_LIB.S9S_MB_2U(SCH_1):M_B_CPU0_SA_DQS_DN'<5>:
 C_SIGNAL='@s9s_mb_2u_lib.s9s_mb_2u(sch_1):m_b_cpu0_sa_dqs_dn(5)';
NODE_NAME     U2 M73
 '@S9S_MB_2U_LIB.S9S_MB_2U(SCH_1):PAGE21_I169@PURE_QUANTA.SOCKET4677_AZIF0045P001C01CS(CHIPS)':
 'DDR1_SA_DQS_DN5': CDS_PINID='DDR1_SA_DQS_DN5';
NODE_NAME     J4 156
 '@S9S_MB_2U_LIB.S9S_MB_2U(SCH_1):PAGE85_I178@PURE_QUANTA.SCONN288_ADR50017P087CC(CHIPS)':
 'DQS5_A_C||TDQS5_A_C||DQS5_A_T||TDQS5_A_T': CDS_PINID='\dqs5_a_c||tdqs5_a_c||dqs5_a_t||tdqs5_a_t\';
NODE_NAME     J3 156
 '@S9S_MB_2U_LIB.S9S_MB_2U(SCH_1):PAGE84_I179@PURE_QUANTA.SCONN288_ADR50017P130CC(CHIPS)':
 'DQS5_A_C||TDQS5_A_C||DQS5_A_T||TDQS5_A_T': CDS_PINID='\dqs5_a_c||tdqs5_a_c||dqs5_a_t||tdqs5_a_t\';
NET_NAME
'M_B_CPU0_SA_DQS_DN<6>'
 '@S9S_MB_2U_LIB.S9S_MB_2U(SCH_1):M_B_CPU0_SA_DQS_DN'<6>:
 C_SIGNAL='@s9s_mb_2u_lib.s9s_mb_2u(sch_1):m_b_cpu0_sa_dqs_dn(6)';
NODE_NAME     U2 AA70
 '@S9S_MB_2U_LIB.S9S_MB_2U(SCH_1):PAGE21_I169@PURE_QUANTA.SOCKET4677_AZIF0045P001C01CS(CHIPS)':
 'DDR1_SA_DQS_DN6': CDS_PINID='DDR1_SA_DQS_DN6';
NODE_NAME     J4 167
 '@S9S_MB_2U_LIB.S9S_MB_2U(SCH_1):PAGE85_I178@PURE_QUANTA.SCONN288_ADR50017P087CC(CHIPS)':
 'DQS6_A_C||TDQS6_A_C||DQS6_A_T||TDQS6_A_T': CDS_PINID='\dqs6_a_c||tdqs6_a_c||dqs6_a_t||tdqs6_a_t\';
NODE_NAME     J3 167
 '@S9S_MB_2U_LIB.S9S_MB_2U(SCH_1):PAGE84_I179@PURE_QUANTA.SCONN288_ADR50017P130CC(CHIPS)':
 'DQS6_A_C||TDQS6_A_C||DQS6_A_T||TDQS6_A_T': CDS_PINID='\dqs6_a_c||tdqs6_a_c||dqs6_a_t||tdqs6_a_t\';
NET_NAME
'M_B_CPU0_SA_DQS_DN<7>'
 '@S9S_MB_2U_LIB.S9S_MB_2U(SCH_1):M_B_CPU0_SA_DQS_DN'<7>:
 C_SIGNAL='@s9s_mb_2u_lib.s9s_mb_2u(sch_1):m_b_cpu0_sa_dqs_dn(7)';
NODE_NAME     U2 M61
 '@S9S_MB_2U_LIB.S9S_MB_2U(SCH_1):PAGE21_I169@PURE_QUANTA.SOCKET4677_AZIF0045P001C01CS(CHIPS)':
 'DDR1_SA_DQS_DN7': CDS_PINID='DDR1_SA_DQS_DN7';
NODE_NAME     J4 178
 '@S9S_MB_2U_LIB.S9S_MB_2U(SCH_1):PAGE85_I178@PURE_QUANTA.SCONN288_ADR50017P087CC(CHIPS)':
 'DQS7_A_C||TDQS7_A_C': CDS_PINID='\dqs7_a_c||tdqs7_a_c\';
NODE_NAME     J3 178
 '@S9S_MB_2U_LIB.S9S_MB_2U(SCH_1):PAGE84_I179@PURE_QUANTA.SCONN288_ADR50017P130CC(CHIPS)':
 'DQS7_A_C||TDQS7_A_C': CDS_PINID='\dqs7_a_c||tdqs7_a_c\';
NET_NAME
'M_B_CPU0_SA_DQS_DN<8>'
 '@S9S_MB_2U_LIB.S9S_MB_2U(SCH_1):M_B_CPU0_SA_DQS_DN'<8>:
 C_SIGNAL='@s9s_mb_2u_lib.s9s_mb_2u(sch_1):m_b_cpu0_sa_dqs_dn(8)';
NODE_NAME     U2 AA58
 '@S9S_MB_2U_LIB.S9S_MB_2U(SCH_1):PAGE21_I169@PURE_QUANTA.SOCKET4677_AZIF0045P001C01CS(CHIPS)':
 'DDR1_SA_DQS_DN8': CDS_PINID='DDR1_SA_DQS_DN8';
NODE_NAME     J4 189
 '@S9S_MB_2U_LIB.S9S_MB_2U(SCH_1):PAGE85_I178@PURE_QUANTA.SCONN288_ADR50017P087CC(CHIPS)':
 'DQS8_A_C||TDQS8_A_C': CDS_PINID='\dqs8_a_c||tdqs8_a_c\';
NODE_NAME     J3 189
 '@S9S_MB_2U_LIB.S9S_MB_2U(SCH_1):PAGE84_I179@PURE_QUANTA.SCONN288_ADR50017P130CC(CHIPS)':
 'DQS8_A_C||TDQS8_A_C': CDS_PINID='\dqs8_a_c||tdqs8_a_c\';
NET_NAME
'M_B_CPU0_SA_DQS_DN<9>'
 '@S9S_MB_2U_LIB.S9S_MB_2U(SCH_1):M_B_CPU0_SA_DQS_DN'<9>:
 C_SIGNAL='@s9s_mb_2u_lib.s9s_mb_2u(sch_1):m_b_cpu0_sa_dqs_dn(9)';
NODE_NAME     U2 M55
 '@S9S_MB_2U_LIB.S9S_MB_2U(SCH_1):PAGE21_I169@PURE_QUANTA.SOCKET4677_AZIF0045P001C01CS(CHIPS)':
 'DDR1_SA_DQS_DN9': CDS_PINID='DDR1_SA_DQS_DN9';
NODE_NAME     J4 200
 '@S9S_MB_2U_LIB.S9S_MB_2U(SCH_1):PAGE85_I178@PURE_QUANTA.SCONN288_ADR50017P087CC(CHIPS)':
 'DQS9_A_C||TDQS9_A_C': CDS_PINID='\dqs9_a_c||tdqs9_a_c\';
NODE_NAME     J3 200
 '@S9S_MB_2U_LIB.S9S_MB_2U(SCH_1):PAGE84_I179@PURE_QUANTA.SCONN288_ADR50017P130CC(CHIPS)':
 'DQS9_A_C||TDQS9_A_C': CDS_PINID='\dqs9_a_c||tdqs9_a_c\';
NET_NAME
'M_B_CPU0_SA_DQS_DP<0>'
 '@S9S_MB_2U_LIB.S9S_MB_2U(SCH_1):M_B_CPU0_SA_DQS_DP'<0>:
 C_SIGNAL='@s9s_mb_2u_lib.s9s_mb_2u(sch_1):m_b_cpu0_sa_dqs_dp(0)';
NODE_NAME     U2 K73
 '@S9S_MB_2U_LIB.S9S_MB_2U(SCH_1):PAGE21_I169@PURE_QUANTA.SOCKET4677_AZIF0045P001C01CS(CHIPS)':
 'DDR1_SA_DQS_DP0': CDS_PINID='DDR1_SA_DQS_DP0';
NODE_NAME     J4 11
 '@S9S_MB_2U_LIB.S9S_MB_2U(SCH_1):PAGE85_I178@PURE_QUANTA.SCONN288_ADR50017P087CC(CHIPS)':
 'DQS0_A_T': CDS_PINID='DQS0_A_T';
NODE_NAME     J3 11
 '@S9S_MB_2U_LIB.S9S_MB_2U(SCH_1):PAGE84_I179@PURE_QUANTA.SCONN288_ADR50017P130CC(CHIPS)':
 'DQS0_A_T': CDS_PINID='DQS0_A_T';
NET_NAME
'M_B_CPU0_SA_DQS_DP<1>'
 '@S9S_MB_2U_LIB.S9S_MB_2U(SCH_1):M_B_CPU0_SA_DQS_DP'<1>:
 C_SIGNAL='@s9s_mb_2u_lib.s9s_mb_2u(sch_1):m_b_cpu0_sa_dqs_dp(1)';
NODE_NAME     U2 U70
 '@S9S_MB_2U_LIB.S9S_MB_2U(SCH_1):PAGE21_I169@PURE_QUANTA.SOCKET4677_AZIF0045P001C01CS(CHIPS)':
 'DDR1_SA_DQS_DP1': CDS_PINID='DDR1_SA_DQS_DP1';
NODE_NAME     J4 22
 '@S9S_MB_2U_LIB.S9S_MB_2U(SCH_1):PAGE85_I178@PURE_QUANTA.SCONN288_ADR50017P087CC(CHIPS)':
 'DQS1_A_T': CDS_PINID='DQS1_A_T';
NODE_NAME     J3 22
 '@S9S_MB_2U_LIB.S9S_MB_2U(SCH_1):PAGE84_I179@PURE_QUANTA.SCONN288_ADR50017P130CC(CHIPS)':
 'DQS1_A_T': CDS_PINID='DQS1_A_T';
NET_NAME
'M_B_CPU0_SA_DQS_DP<2>'
 '@S9S_MB_2U_LIB.S9S_MB_2U(SCH_1):M_B_CPU0_SA_DQS_DP'<2>:
 C_SIGNAL='@s9s_mb_2u_lib.s9s_mb_2u(sch_1):m_b_cpu0_sa_dqs_dp(2)';
NODE_NAME     U2 K61
 '@S9S_MB_2U_LIB.S9S_MB_2U(SCH_1):PAGE21_I169@PURE_QUANTA.SOCKET4677_AZIF0045P001C01CS(CHIPS)':
 'DDR1_SA_DQS_DP2': CDS_PINID='DDR1_SA_DQS_DP2';
NODE_NAME     J4 33
 '@S9S_MB_2U_LIB.S9S_MB_2U(SCH_1):PAGE85_I178@PURE_QUANTA.SCONN288_ADR50017P087CC(CHIPS)':
 'DQS2_A_T': CDS_PINID='DQS2_A_T';
NODE_NAME     J3 33
 '@S9S_MB_2U_LIB.S9S_MB_2U(SCH_1):PAGE84_I179@PURE_QUANTA.SCONN288_ADR50017P130CC(CHIPS)':
 'DQS2_A_T': CDS_PINID='DQS2_A_T';
NET_NAME
'M_B_CPU0_SA_DQS_DP<3>'
 '@S9S_MB_2U_LIB.S9S_MB_2U(SCH_1):M_B_CPU0_SA_DQS_DP'<3>:
 C_SIGNAL='@s9s_mb_2u_lib.s9s_mb_2u(sch_1):m_b_cpu0_sa_dqs_dp(3)';
NODE_NAME     U2 U58
 '@S9S_MB_2U_LIB.S9S_MB_2U(SCH_1):PAGE21_I169@PURE_QUANTA.SOCKET4677_AZIF0045P001C01CS(CHIPS)':
 'DDR1_SA_DQS_DP3': CDS_PINID='DDR1_SA_DQS_DP3';
NODE_NAME     J4 44
 '@S9S_MB_2U_LIB.S9S_MB_2U(SCH_1):PAGE85_I178@PURE_QUANTA.SCONN288_ADR50017P087CC(CHIPS)':
 'DQS3_A_T': CDS_PINID='DQS3_A_T';
NODE_NAME     J3 44
 '@S9S_MB_2U_LIB.S9S_MB_2U(SCH_1):PAGE84_I179@PURE_QUANTA.SCONN288_ADR50017P130CC(CHIPS)':
 'DQS3_A_T': CDS_PINID='DQS3_A_T';
NET_NAME
'M_B_CPU0_SA_DQS_DP<4>'
 '@S9S_MB_2U_LIB.S9S_MB_2U(SCH_1):M_B_CPU0_SA_DQS_DP'<4>:
 C_SIGNAL='@s9s_mb_2u_lib.s9s_mb_2u(sch_1):m_b_cpu0_sa_dqs_dp(4)';
NODE_NAME     U2 K55
 '@S9S_MB_2U_LIB.S9S_MB_2U(SCH_1):PAGE21_I169@PURE_QUANTA.SOCKET4677_AZIF0045P001C01CS(CHIPS)':
 'DDR1_SA_DQS_DP4': CDS_PINID='DDR1_SA_DQS_DP4';
NODE_NAME     J4 55
 '@S9S_MB_2U_LIB.S9S_MB_2U(SCH_1):PAGE85_I178@PURE_QUANTA.SCONN288_ADR50017P087CC(CHIPS)':
 'DQS4_A_T': CDS_PINID='DQS4_A_T';
NODE_NAME     J3 55
 '@S9S_MB_2U_LIB.S9S_MB_2U(SCH_1):PAGE84_I179@PURE_QUANTA.SCONN288_ADR50017P130CC(CHIPS)':
 'DQS4_A_T': CDS_PINID='DQS4_A_T';
NET_NAME
'M_B_CPU0_SA_DQS_DP<5>'
 '@S9S_MB_2U_LIB.S9S_MB_2U(SCH_1):M_B_CPU0_SA_DQS_DP'<5>:
 C_SIGNAL='@s9s_mb_2u_lib.s9s_mb_2u(sch_1):m_b_cpu0_sa_dqs_dp(5)';
NODE_NAME     U2 P73
 '@S9S_MB_2U_LIB.S9S_MB_2U(SCH_1):PAGE21_I169@PURE_QUANTA.SOCKET4677_AZIF0045P001C01CS(CHIPS)':
 'DDR1_SA_DQS_DP5': CDS_PINID='DDR1_SA_DQS_DP5';
NODE_NAME     J4 157
 '@S9S_MB_2U_LIB.S9S_MB_2U(SCH_1):PAGE85_I178@PURE_QUANTA.SCONN288_ADR50017P087CC(CHIPS)':
 'DQS5_A_T||TDQS5_A_T': CDS_PINID='\dqs5_a_t||tdqs5_a_t\';
NODE_NAME     J3 157
 '@S9S_MB_2U_LIB.S9S_MB_2U(SCH_1):PAGE84_I179@PURE_QUANTA.SCONN288_ADR50017P130CC(CHIPS)':
 'DQS5_A_T||TDQS5_A_T': CDS_PINID='\dqs5_a_t||tdqs5_a_t\';
NET_NAME
'M_B_CPU0_SA_DQS_DP<6>'
 '@S9S_MB_2U_LIB.S9S_MB_2U(SCH_1):M_B_CPU0_SA_DQS_DP'<6>:
 C_SIGNAL='@s9s_mb_2u_lib.s9s_mb_2u(sch_1):m_b_cpu0_sa_dqs_dp(6)';
NODE_NAME     U2 W70
 '@S9S_MB_2U_LIB.S9S_MB_2U(SCH_1):PAGE21_I169@PURE_QUANTA.SOCKET4677_AZIF0045P001C01CS(CHIPS)':
 'DDR1_SA_DQS_DP6': CDS_PINID='DDR1_SA_DQS_DP6';
NODE_NAME     J4 168
 '@S9S_MB_2U_LIB.S9S_MB_2U(SCH_1):PAGE85_I178@PURE_QUANTA.SCONN288_ADR50017P087CC(CHIPS)':
 'DQS6_A_T||TDQS6_A_T': CDS_PINID='\dqs6_a_t||tdqs6_a_t\';
NODE_NAME     J3 168
 '@S9S_MB_2U_LIB.S9S_MB_2U(SCH_1):PAGE84_I179@PURE_QUANTA.SCONN288_ADR50017P130CC(CHIPS)':
 'DQS6_A_T||TDQS6_A_T': CDS_PINID='\dqs6_a_t||tdqs6_a_t\';
NET_NAME
'M_B_CPU0_SA_DQS_DP<7>'
 '@S9S_MB_2U_LIB.S9S_MB_2U(SCH_1):M_B_CPU0_SA_DQS_DP'<7>:
 C_SIGNAL='@s9s_mb_2u_lib.s9s_mb_2u(sch_1):m_b_cpu0_sa_dqs_dp(7)';
NODE_NAME     U2 P61
 '@S9S_MB_2U_LIB.S9S_MB_2U(SCH_1):PAGE21_I169@PURE_QUANTA.SOCKET4677_AZIF0045P001C01CS(CHIPS)':
 'DDR1_SA_DQS_DP7': CDS_PINID='DDR1_SA_DQS_DP7';
NODE_NAME     J4 179
 '@S9S_MB_2U_LIB.S9S_MB_2U(SCH_1):PAGE85_I178@PURE_QUANTA.SCONN288_ADR50017P087CC(CHIPS)':
 'DQS7_A_T||TDQS7_A_T': CDS_PINID='\dqs7_a_t||tdqs7_a_t\';
NODE_NAME     J3 179
 '@S9S_MB_2U_LIB.S9S_MB_2U(SCH_1):PAGE84_I179@PURE_QUANTA.SCONN288_ADR50017P130CC(CHIPS)':
 'DQS7_A_T||TDQS7_A_T': CDS_PINID='\dqs7_a_t||tdqs7_a_t\';
NET_NAME
'M_B_CPU0_SA_DQS_DP<8>'
 '@S9S_MB_2U_LIB.S9S_MB_2U(SCH_1):M_B_CPU0_SA_DQS_DP'<8>:
 C_SIGNAL='@s9s_mb_2u_lib.s9s_mb_2u(sch_1):m_b_cpu0_sa_dqs_dp(8)';
NODE_NAME     U2 W58
 '@S9S_MB_2U_LIB.S9S_MB_2U(SCH_1):PAGE21_I169@PURE_QUANTA.SOCKET4677_AZIF0045P001C01CS(CHIPS)':
 'DDR1_SA_DQS_DP8': CDS_PINID='DDR1_SA_DQS_DP8';
NODE_NAME     J4 190
 '@S9S_MB_2U_LIB.S9S_MB_2U(SCH_1):PAGE85_I178@PURE_QUANTA.SCONN288_ADR50017P087CC(CHIPS)':
 'DQS8_A_T||TDQS8_A_T': CDS_PINID='\dqs8_a_t||tdqs8_a_t\';
NODE_NAME     J3 190
 '@S9S_MB_2U_LIB.S9S_MB_2U(SCH_1):PAGE84_I179@PURE_QUANTA.SCONN288_ADR50017P130CC(CHIPS)':
 'DQS8_A_T||TDQS8_A_T': CDS_PINID='\dqs8_a_t||tdqs8_a_t\';
NET_NAME
'M_B_CPU0_SA_DQS_DP<9>'
 '@S9S_MB_2U_LIB.S9S_MB_2U(SCH_1):M_B_CPU0_SA_DQS_DP'<9>:
 C_SIGNAL='@s9s_mb_2u_lib.s9s_mb_2u(sch_1):m_b_cpu0_sa_dqs_dp(9)';
NODE_NAME     U2 P55
 '@S9S_MB_2U_LIB.S9S_MB_2U(SCH_1):PAGE21_I169@PURE_QUANTA.SOCKET4677_AZIF0045P001C01CS(CHIPS)':
 'DDR1_SA_DQS_DP9': CDS_PINID='DDR1_SA_DQS_DP9';
NODE_NAME     J4 201
 '@S9S_MB_2U_LIB.S9S_MB_2U(SCH_1):PAGE85_I178@PURE_QUANTA.SCONN288_ADR50017P087CC(CHIPS)':
 'DQS9_A_T||TDQS9_A_T': CDS_PINID='\dqs9_a_t||tdqs9_a_t\';
NODE_NAME     J3 201
 '@S9S_MB_2U_LIB.S9S_MB_2U(SCH_1):PAGE84_I179@PURE_QUANTA.SCONN288_ADR50017P130CC(CHIPS)':
 'DQS9_A_T||TDQS9_A_T': CDS_PINID='\dqs9_a_t||tdqs9_a_t\';
NET_NAME
'M_B_CPU0_SA_PAR'
 '@S9S_MB_2U_LIB.S9S_MB_2U(SCH_1):M_B_CPU0_SA_PAR':
 C_SIGNAL='@s9s_mb_2u_lib.s9s_mb_2u(sch_1):m_b_cpu0_sa_par';
NODE_NAME     U2 W43
 '@S9S_MB_2U_LIB.S9S_MB_2U(SCH_1):PAGE21_I169@PURE_QUANTA.SOCKET4677_AZIF0045P001C01CS(CHIPS)':
 'DDR1_SA_PAR': CDS_PINID='DDR1_SA_PAR';
NODE_NAME     J4 74
 '@S9S_MB_2U_LIB.S9S_MB_2U(SCH_1):PAGE85_I23@PURE_QUANTA.SCONN288_ADR50017P087CC(CHIPS)':
 'PAR_A': CDS_PINID='PAR_A';
NODE_NAME     J3 74
 '@S9S_MB_2U_LIB.S9S_MB_2U(SCH_1):PAGE84_I180@PURE_QUANTA.SCONN288_ADR50017P130CC(CHIPS)':
 'PAR_A': CDS_PINID='PAR_A';
NET_NAME
'M_B_CPU0_SA_RSP<0>'
 '@S9S_MB_2U_LIB.S9S_MB_2U(SCH_1):M_B_CPU0_SA_RSP'<0>:
 C_SIGNAL='@s9s_mb_2u_lib.s9s_mb_2u(sch_1):m_b_cpu0_sa_rsp(0)';
NODE_NAME     U2 AL48
 '@S9S_MB_2U_LIB.S9S_MB_2U(SCH_1):PAGE21_I169@PURE_QUANTA.SOCKET4677_AZIF0045P001C01CS(CHIPS)':
 'DDR1_A_RSP0': CDS_PINID='DDR1_A_RSP0';
NODE_NAME     J3 86
 '@S9S_MB_2U_LIB.S9S_MB_2U(SCH_1):PAGE84_I180@PURE_QUANTA.SCONN288_ADR50017P130CC(CHIPS)':
 'LBD||RSP_A_N': CDS_PINID='\lbd||rsp_a_n\';
NET_NAME
'M_B_CPU0_SA_RSP<1>'
 '@S9S_MB_2U_LIB.S9S_MB_2U(SCH_1):M_B_CPU0_SA_RSP'<1>:
 C_SIGNAL='@s9s_mb_2u_lib.s9s_mb_2u(sch_1):m_b_cpu0_sa_rsp(1)';
NODE_NAME     U2 AK47
 '@S9S_MB_2U_LIB.S9S_MB_2U(SCH_1):PAGE21_I169@PURE_QUANTA.SOCKET4677_AZIF0045P001C01CS(CHIPS)':
 'DDR1_A_RSP1': CDS_PINID='DDR1_A_RSP1';
NODE_NAME     J4 86
 '@S9S_MB_2U_LIB.S9S_MB_2U(SCH_1):PAGE85_I23@PURE_QUANTA.SCONN288_ADR50017P087CC(CHIPS)':
 'LBD||RSP_A_N': CDS_PINID='\lbd||rsp_a_n\';
NET_NAME
'M_B_CPU0_SB_CA<0>'
 '@S9S_MB_2U_LIB.S9S_MB_2U(SCH_1):M_B_CPU0_SB_CA'<0>:
 C_SIGNAL='@s9s_mb_2u_lib.s9s_mb_2u(sch_1):m_b_cpu0_sb_ca(0)';
NODE_NAME     U2 T44
 '@S9S_MB_2U_LIB.S9S_MB_2U(SCH_1):PAGE21_I169@PURE_QUANTA.SOCKET4677_AZIF0045P001C01CS(CHIPS)':
 'DDR1_SB_CA0': CDS_PINID='DDR1_SB_CA0';
NODE_NAME     J4 76
 '@S9S_MB_2U_LIB.S9S_MB_2U(SCH_1):PAGE85_I23@PURE_QUANTA.SCONN288_ADR50017P087CC(CHIPS)':
 'CA0_B': CDS_PINID='CA0_B';
NODE_NAME     J3 76
 '@S9S_MB_2U_LIB.S9S_MB_2U(SCH_1):PAGE84_I180@PURE_QUANTA.SCONN288_ADR50017P130CC(CHIPS)':
 'CA0_B': CDS_PINID='CA0_B';
NET_NAME
'M_B_CPU0_SB_CA<1>'
 '@S9S_MB_2U_LIB.S9S_MB_2U(SCH_1):M_B_CPU0_SB_CA'<1>:
 C_SIGNAL='@s9s_mb_2u_lib.s9s_mb_2u(sch_1):m_b_cpu0_sb_ca(1)';
NODE_NAME     U2 U43
 '@S9S_MB_2U_LIB.S9S_MB_2U(SCH_1):PAGE21_I169@PURE_QUANTA.SOCKET4677_AZIF0045P001C01CS(CHIPS)':
 'DDR1_SB_CA1': CDS_PINID='DDR1_SB_CA1';
NODE_NAME     J4 221
 '@S9S_MB_2U_LIB.S9S_MB_2U(SCH_1):PAGE85_I23@PURE_QUANTA.SCONN288_ADR50017P087CC(CHIPS)':
 'CA1_B': CDS_PINID='CA1_B';
NODE_NAME     J3 221
 '@S9S_MB_2U_LIB.S9S_MB_2U(SCH_1):PAGE84_I180@PURE_QUANTA.SCONN288_ADR50017P130CC(CHIPS)':
 'CA1_B': CDS_PINID='CA1_B';
NET_NAME
'M_B_CPU0_SB_CA<2>'
 '@S9S_MB_2U_LIB.S9S_MB_2U(SCH_1):M_B_CPU0_SB_CA'<2>:
 C_SIGNAL='@s9s_mb_2u_lib.s9s_mb_2u(sch_1):m_b_cpu0_sb_ca(2)';
NODE_NAME     U2 K44
 '@S9S_MB_2U_LIB.S9S_MB_2U(SCH_1):PAGE21_I169@PURE_QUANTA.SOCKET4677_AZIF0045P001C01CS(CHIPS)':
 'DDR1_SB_CA2': CDS_PINID='DDR1_SB_CA2';
NODE_NAME     J4 78
 '@S9S_MB_2U_LIB.S9S_MB_2U(SCH_1):PAGE85_I23@PURE_QUANTA.SCONN288_ADR50017P087CC(CHIPS)':
 'CA2_B': CDS_PINID='CA2_B';
NODE_NAME     J3 78
 '@S9S_MB_2U_LIB.S9S_MB_2U(SCH_1):PAGE84_I180@PURE_QUANTA.SCONN288_ADR50017P130CC(CHIPS)':
 'CA2_B': CDS_PINID='CA2_B';
NET_NAME
'M_B_CPU0_SB_CA<3>'
 '@S9S_MB_2U_LIB.S9S_MB_2U(SCH_1):M_B_CPU0_SB_CA'<3>:
 C_SIGNAL='@s9s_mb_2u_lib.s9s_mb_2u(sch_1):m_b_cpu0_sb_ca(3)';
NODE_NAME     U2 M44
 '@S9S_MB_2U_LIB.S9S_MB_2U(SCH_1):PAGE21_I169@PURE_QUANTA.SOCKET4677_AZIF0045P001C01CS(CHIPS)':
 'DDR1_SB_CA3': CDS_PINID='DDR1_SB_CA3';
NODE_NAME     J4 223
 '@S9S_MB_2U_LIB.S9S_MB_2U(SCH_1):PAGE85_I23@PURE_QUANTA.SCONN288_ADR50017P087CC(CHIPS)':
 'CA3_B': CDS_PINID='CA3_B';
NODE_NAME     J3 223
 '@S9S_MB_2U_LIB.S9S_MB_2U(SCH_1):PAGE84_I180@PURE_QUANTA.SCONN288_ADR50017P130CC(CHIPS)':
 'CA3_B': CDS_PINID='CA3_B';
NET_NAME
'M_B_CPU0_SB_CA<4>'
 '@S9S_MB_2U_LIB.S9S_MB_2U(SCH_1):M_B_CPU0_SB_CA'<4>:
 C_SIGNAL='@s9s_mb_2u_lib.s9s_mb_2u(sch_1):m_b_cpu0_sb_ca(4)';
NODE_NAME     U2 J43
 '@S9S_MB_2U_LIB.S9S_MB_2U(SCH_1):PAGE21_I169@PURE_QUANTA.SOCKET4677_AZIF0045P001C01CS(CHIPS)':
 'DDR1_SB_CA4': CDS_PINID='DDR1_SB_CA4';
NODE_NAME     J4 80
 '@S9S_MB_2U_LIB.S9S_MB_2U(SCH_1):PAGE85_I23@PURE_QUANTA.SCONN288_ADR50017P087CC(CHIPS)':
 'CA4_B': CDS_PINID='CA4_B';
NODE_NAME     J3 80
 '@S9S_MB_2U_LIB.S9S_MB_2U(SCH_1):PAGE84_I180@PURE_QUANTA.SCONN288_ADR50017P130CC(CHIPS)':
 'CA4_B': CDS_PINID='CA4_B';
NET_NAME
'M_B_CPU0_SB_CA<5>'
 '@S9S_MB_2U_LIB.S9S_MB_2U(SCH_1):M_B_CPU0_SB_CA'<5>:
 C_SIGNAL='@s9s_mb_2u_lib.s9s_mb_2u(sch_1):m_b_cpu0_sb_ca(5)';
NODE_NAME     U2 N43
 '@S9S_MB_2U_LIB.S9S_MB_2U(SCH_1):PAGE21_I169@PURE_QUANTA.SOCKET4677_AZIF0045P001C01CS(CHIPS)':
 'DDR1_SB_CA5': CDS_PINID='DDR1_SB_CA5';
NODE_NAME     J4 225
 '@S9S_MB_2U_LIB.S9S_MB_2U(SCH_1):PAGE85_I23@PURE_QUANTA.SCONN288_ADR50017P087CC(CHIPS)':
 'CA5_B': CDS_PINID='CA5_B';
NODE_NAME     J3 225
 '@S9S_MB_2U_LIB.S9S_MB_2U(SCH_1):PAGE84_I180@PURE_QUANTA.SCONN288_ADR50017P130CC(CHIPS)':
 'CA5_B': CDS_PINID='CA5_B';
NET_NAME
'M_B_CPU0_SB_CA<6>'
 '@S9S_MB_2U_LIB.S9S_MB_2U(SCH_1):M_B_CPU0_SB_CA'<6>:
 C_SIGNAL='@s9s_mb_2u_lib.s9s_mb_2u(sch_1):m_b_cpu0_sb_ca(6)';
NODE_NAME     U2 H42
 '@S9S_MB_2U_LIB.S9S_MB_2U(SCH_1):PAGE21_I169@PURE_QUANTA.SOCKET4677_AZIF0045P001C01CS(CHIPS)':
 'DDR1_SB_CA6': CDS_PINID='DDR1_SB_CA6';
NODE_NAME     J4 82
 '@S9S_MB_2U_LIB.S9S_MB_2U(SCH_1):PAGE85_I23@PURE_QUANTA.SCONN288_ADR50017P087CC(CHIPS)':
 'CA6_B': CDS_PINID='CA6_B';
NODE_NAME     J3 82
 '@S9S_MB_2U_LIB.S9S_MB_2U(SCH_1):PAGE84_I180@PURE_QUANTA.SCONN288_ADR50017P130CC(CHIPS)':
 'CA6_B': CDS_PINID='CA6_B';
NET_NAME
'M_B_CPU0_SB_CB<0>'
 '@S9S_MB_2U_LIB.S9S_MB_2U(SCH_1):M_B_CPU0_SB_CB'<0>:
 C_SIGNAL='@s9s_mb_2u_lib.s9s_mb_2u(sch_1):m_b_cpu0_sb_cb(0)';
NODE_NAME     U2 J35
 '@S9S_MB_2U_LIB.S9S_MB_2U(SCH_1):PAGE21_I169@PURE_QUANTA.SOCKET4677_AZIF0045P001C01CS(CHIPS)':
 'DDR1_SB_ECC0': CDS_PINID='DDR1_SB_ECC0';
NODE_NAME     J4 96
 '@S9S_MB_2U_LIB.S9S_MB_2U(SCH_1):PAGE85_I23@PURE_QUANTA.SCONN288_ADR50017P087CC(CHIPS)':
 'CB0_B': CDS_PINID='CB0_B';
NODE_NAME     J3 96
 '@S9S_MB_2U_LIB.S9S_MB_2U(SCH_1):PAGE84_I180@PURE_QUANTA.SCONN288_ADR50017P130CC(CHIPS)':
 'CB0_B': CDS_PINID='CB0_B';
NET_NAME
'M_B_CPU0_SB_CB<1>'
 '@S9S_MB_2U_LIB.S9S_MB_2U(SCH_1):M_B_CPU0_SB_CB'<1>:
 C_SIGNAL='@s9s_mb_2u_lib.s9s_mb_2u(sch_1):m_b_cpu0_sb_cb(1)';
NODE_NAME     U2 K34
 '@S9S_MB_2U_LIB.S9S_MB_2U(SCH_1):PAGE21_I169@PURE_QUANTA.SOCKET4677_AZIF0045P001C01CS(CHIPS)':
 'DDR1_SB_ECC1': CDS_PINID='DDR1_SB_ECC1';
NODE_NAME     J4 98
 '@S9S_MB_2U_LIB.S9S_MB_2U(SCH_1):PAGE85_I23@PURE_QUANTA.SCONN288_ADR50017P087CC(CHIPS)':
 'CB1_B': CDS_PINID='CB1_B';
NODE_NAME     J3 98
 '@S9S_MB_2U_LIB.S9S_MB_2U(SCH_1):PAGE84_I180@PURE_QUANTA.SCONN288_ADR50017P130CC(CHIPS)':
 'CB1_B': CDS_PINID='CB1_B';
NET_NAME
'M_B_CPU0_SB_CB<2>'
 '@S9S_MB_2U_LIB.S9S_MB_2U(SCH_1):M_B_CPU0_SB_CB'<2>:
 C_SIGNAL='@s9s_mb_2u_lib.s9s_mb_2u(sch_1):m_b_cpu0_sb_cb(2)';
NODE_NAME     U2 N35
 '@S9S_MB_2U_LIB.S9S_MB_2U(SCH_1):PAGE21_I169@PURE_QUANTA.SOCKET4677_AZIF0045P001C01CS(CHIPS)':
 'DDR1_SB_ECC2': CDS_PINID='DDR1_SB_ECC2';
NODE_NAME     J4 241
 '@S9S_MB_2U_LIB.S9S_MB_2U(SCH_1):PAGE85_I23@PURE_QUANTA.SCONN288_ADR50017P087CC(CHIPS)':
 'CB2_B': CDS_PINID='CB2_B';
NODE_NAME     J3 241
 '@S9S_MB_2U_LIB.S9S_MB_2U(SCH_1):PAGE84_I180@PURE_QUANTA.SCONN288_ADR50017P130CC(CHIPS)':
 'CB2_B': CDS_PINID='CB2_B';
NET_NAME
'M_B_CPU0_SB_CB<3>'
 '@S9S_MB_2U_LIB.S9S_MB_2U(SCH_1):M_B_CPU0_SB_CB'<3>:
 C_SIGNAL='@s9s_mb_2u_lib.s9s_mb_2u(sch_1):m_b_cpu0_sb_cb(3)';
NODE_NAME     U2 M34
 '@S9S_MB_2U_LIB.S9S_MB_2U(SCH_1):PAGE21_I169@PURE_QUANTA.SOCKET4677_AZIF0045P001C01CS(CHIPS)':
 'DDR1_SB_ECC3': CDS_PINID='DDR1_SB_ECC3';
NODE_NAME     J4 243
 '@S9S_MB_2U_LIB.S9S_MB_2U(SCH_1):PAGE85_I23@PURE_QUANTA.SCONN288_ADR50017P087CC(CHIPS)':
 'CB3_B': CDS_PINID='CB3_B';
NODE_NAME     J3 243
 '@S9S_MB_2U_LIB.S9S_MB_2U(SCH_1):PAGE84_I180@PURE_QUANTA.SCONN288_ADR50017P130CC(CHIPS)':
 'CB3_B': CDS_PINID='CB3_B';
NET_NAME
'M_B_CPU0_SB_CB<4>'
 '@S9S_MB_2U_LIB.S9S_MB_2U(SCH_1):M_B_CPU0_SB_CB'<4>:
 C_SIGNAL='@s9s_mb_2u_lib.s9s_mb_2u(sch_1):m_b_cpu0_sb_cb(4)';
NODE_NAME     U2 K38
 '@S9S_MB_2U_LIB.S9S_MB_2U(SCH_1):PAGE21_I169@PURE_QUANTA.SOCKET4677_AZIF0045P001C01CS(CHIPS)':
 'DDR1_SB_ECC4': CDS_PINID='DDR1_SB_ECC4';
NODE_NAME     J4 89
 '@S9S_MB_2U_LIB.S9S_MB_2U(SCH_1):PAGE85_I23@PURE_QUANTA.SCONN288_ADR50017P087CC(CHIPS)':
 'CB4_B': CDS_PINID='CB4_B';
NODE_NAME     J3 89
 '@S9S_MB_2U_LIB.S9S_MB_2U(SCH_1):PAGE84_I180@PURE_QUANTA.SCONN288_ADR50017P130CC(CHIPS)':
 'CB4_B': CDS_PINID='CB4_B';
NET_NAME
'M_B_CPU0_SB_CB<5>'
 '@S9S_MB_2U_LIB.S9S_MB_2U(SCH_1):M_B_CPU0_SB_CB'<5>:
 C_SIGNAL='@s9s_mb_2u_lib.s9s_mb_2u(sch_1):m_b_cpu0_sb_cb(5)';
NODE_NAME     U2 J37
 '@S9S_MB_2U_LIB.S9S_MB_2U(SCH_1):PAGE21_I169@PURE_QUANTA.SOCKET4677_AZIF0045P001C01CS(CHIPS)':
 'DDR1_SB_ECC5': CDS_PINID='DDR1_SB_ECC5';
NODE_NAME     J4 91
 '@S9S_MB_2U_LIB.S9S_MB_2U(SCH_1):PAGE85_I23@PURE_QUANTA.SCONN288_ADR50017P087CC(CHIPS)':
 'CB5_B': CDS_PINID='CB5_B';
NODE_NAME     J3 91
 '@S9S_MB_2U_LIB.S9S_MB_2U(SCH_1):PAGE84_I180@PURE_QUANTA.SCONN288_ADR50017P130CC(CHIPS)':
 'CB5_B': CDS_PINID='CB5_B';
NET_NAME
'M_B_CPU0_SB_CB<6>'
 '@S9S_MB_2U_LIB.S9S_MB_2U(SCH_1):M_B_CPU0_SB_CB'<6>:
 C_SIGNAL='@s9s_mb_2u_lib.s9s_mb_2u(sch_1):m_b_cpu0_sb_cb(6)';
NODE_NAME     U2 M38
 '@S9S_MB_2U_LIB.S9S_MB_2U(SCH_1):PAGE21_I169@PURE_QUANTA.SOCKET4677_AZIF0045P001C01CS(CHIPS)':
 'DDR1_SB_ECC6': CDS_PINID='DDR1_SB_ECC6';
NODE_NAME     J4 234
 '@S9S_MB_2U_LIB.S9S_MB_2U(SCH_1):PAGE85_I23@PURE_QUANTA.SCONN288_ADR50017P087CC(CHIPS)':
 'CB6_B': CDS_PINID='CB6_B';
NODE_NAME     J3 234
 '@S9S_MB_2U_LIB.S9S_MB_2U(SCH_1):PAGE84_I180@PURE_QUANTA.SCONN288_ADR50017P130CC(CHIPS)':
 'CB6_B': CDS_PINID='CB6_B';
NET_NAME
'M_B_CPU0_SB_CB<7>'
 '@S9S_MB_2U_LIB.S9S_MB_2U(SCH_1):M_B_CPU0_SB_CB'<7>:
 C_SIGNAL='@s9s_mb_2u_lib.s9s_mb_2u(sch_1):m_b_cpu0_sb_cb(7)';
NODE_NAME     U2 N37
 '@S9S_MB_2U_LIB.S9S_MB_2U(SCH_1):PAGE21_I169@PURE_QUANTA.SOCKET4677_AZIF0045P001C01CS(CHIPS)':
 'DDR1_SB_ECC7': CDS_PINID='DDR1_SB_ECC7';
NODE_NAME     J4 236
 '@S9S_MB_2U_LIB.S9S_MB_2U(SCH_1):PAGE85_I23@PURE_QUANTA.SCONN288_ADR50017P087CC(CHIPS)':
 'CB7_B': CDS_PINID='CB7_B';
NODE_NAME     J3 236
 '@S9S_MB_2U_LIB.S9S_MB_2U(SCH_1):PAGE84_I180@PURE_QUANTA.SCONN288_ADR50017P130CC(CHIPS)':
 'CB7_B': CDS_PINID='CB7_B';
NET_NAME
'M_B_CPU0_SB_CS_N<0>'
 '@S9S_MB_2U_LIB.S9S_MB_2U(SCH_1):M_B_CPU0_SB_CS_N'<0>:
 C_SIGNAL='@s9s_mb_2u_lib.s9s_mb_2u(sch_1):m_b_cpu0_sb_cs_n(0)';
NODE_NAME     U2 J41
 '@S9S_MB_2U_LIB.S9S_MB_2U(SCH_1):PAGE21_I169@PURE_QUANTA.SOCKET4677_AZIF0045P001C01CS(CHIPS)':
 'DDR1_SB_CS_N0': CDS_PINID='DDR1_SB_CS_N0';
NODE_NAME     J3 84
 '@S9S_MB_2U_LIB.S9S_MB_2U(SCH_1):PAGE84_I180@PURE_QUANTA.SCONN288_ADR50017P130CC(CHIPS)':
 'CS0_B_N': CDS_PINID='CS0_B_N';
NET_NAME
'M_B_CPU0_SB_CS_N<1>'
 '@S9S_MB_2U_LIB.S9S_MB_2U(SCH_1):M_B_CPU0_SB_CS_N'<1>:
 C_SIGNAL='@s9s_mb_2u_lib.s9s_mb_2u(sch_1):m_b_cpu0_sb_cs_n(1)';
NODE_NAME     U2 K40
 '@S9S_MB_2U_LIB.S9S_MB_2U(SCH_1):PAGE21_I169@PURE_QUANTA.SOCKET4677_AZIF0045P001C01CS(CHIPS)':
 'DDR1_SB_CS_N1': CDS_PINID='DDR1_SB_CS_N1';
NODE_NAME     J3 229
 '@S9S_MB_2U_LIB.S9S_MB_2U(SCH_1):PAGE84_I180@PURE_QUANTA.SCONN288_ADR50017P130CC(CHIPS)':
 'CS1_B_N': CDS_PINID='CS1_B_N';
NET_NAME
'M_B_CPU0_SB_CS_N<2>'
 '@S9S_MB_2U_LIB.S9S_MB_2U(SCH_1):M_B_CPU0_SB_CS_N'<2>:
 C_SIGNAL='@s9s_mb_2u_lib.s9s_mb_2u(sch_1):m_b_cpu0_sb_cs_n(2)';
NODE_NAME     U2 N41
 '@S9S_MB_2U_LIB.S9S_MB_2U(SCH_1):PAGE21_I169@PURE_QUANTA.SOCKET4677_AZIF0045P001C01CS(CHIPS)':
 'DDR1_SB_CS_N2': CDS_PINID='DDR1_SB_CS_N2';
NODE_NAME     J4 84
 '@S9S_MB_2U_LIB.S9S_MB_2U(SCH_1):PAGE85_I23@PURE_QUANTA.SCONN288_ADR50017P087CC(CHIPS)':
 'CS0_B_N': CDS_PINID='CS0_B_N';
NET_NAME
'M_B_CPU0_SB_CS_N<3>'
 '@S9S_MB_2U_LIB.S9S_MB_2U(SCH_1):M_B_CPU0_SB_CS_N'<3>:
 C_SIGNAL='@s9s_mb_2u_lib.s9s_mb_2u(sch_1):m_b_cpu0_sb_cs_n(3)';
NODE_NAME     U2 M40
 '@S9S_MB_2U_LIB.S9S_MB_2U(SCH_1):PAGE21_I169@PURE_QUANTA.SOCKET4677_AZIF0045P001C01CS(CHIPS)':
 'DDR1_SB_CS_N3': CDS_PINID='DDR1_SB_CS_N3';
NODE_NAME     J4 229
 '@S9S_MB_2U_LIB.S9S_MB_2U(SCH_1):PAGE85_I23@PURE_QUANTA.SCONN288_ADR50017P087CC(CHIPS)':
 'CS1_B_N': CDS_PINID='CS1_B_N';
NET_NAME
'M_B_CPU0_SB_DQ<0>'
 '@S9S_MB_2U_LIB.S9S_MB_2U(SCH_1):M_B_CPU0_SB_DQ'<0>:
 C_SIGNAL='@s9s_mb_2u_lib.s9s_mb_2u(sch_1):m_b_cpu0_sb_dq(0)';
NODE_NAME     U2 U29
 '@S9S_MB_2U_LIB.S9S_MB_2U(SCH_1):PAGE21_I169@PURE_QUANTA.SOCKET4677_AZIF0045P001C01CS(CHIPS)':
 'DDR1_SB_DQ0': CDS_PINID='DDR1_SB_DQ0';
NODE_NAME     J4 100
 '@S9S_MB_2U_LIB.S9S_MB_2U(SCH_1):PAGE85_I23@PURE_QUANTA.SCONN288_ADR50017P087CC(CHIPS)':
 'DQ0_B': CDS_PINID='DQ0_B';
NODE_NAME     J3 100
 '@S9S_MB_2U_LIB.S9S_MB_2U(SCH_1):PAGE84_I180@PURE_QUANTA.SCONN288_ADR50017P130CC(CHIPS)':
 'DQ0_B': CDS_PINID='DQ0_B';
NET_NAME
'M_B_CPU0_SB_DQ<10>'
 '@S9S_MB_2U_LIB.S9S_MB_2U(SCH_1):M_B_CPU0_SB_DQ'<10>:
 C_SIGNAL='@s9s_mb_2u_lib.s9s_mb_2u(sch_1):m_b_cpu0_sb_dq(10)';
NODE_NAME     U2 M26
 '@S9S_MB_2U_LIB.S9S_MB_2U(SCH_1):PAGE21_I169@PURE_QUANTA.SOCKET4677_AZIF0045P001C01CS(CHIPS)':
 'DDR1_SB_DQ10': CDS_PINID='DDR1_SB_DQ10';
NODE_NAME     J4 256
 '@S9S_MB_2U_LIB.S9S_MB_2U(SCH_1):PAGE85_I23@PURE_QUANTA.SCONN288_ADR50017P087CC(CHIPS)':
 'DQ10_B': CDS_PINID='DQ10_B';
NODE_NAME     J3 256
 '@S9S_MB_2U_LIB.S9S_MB_2U(SCH_1):PAGE84_I180@PURE_QUANTA.SCONN288_ADR50017P130CC(CHIPS)':
 'DQ10_B': CDS_PINID='DQ10_B';
NET_NAME
'M_B_CPU0_SB_DQ<11>'
 '@S9S_MB_2U_LIB.S9S_MB_2U(SCH_1):M_B_CPU0_SB_DQ'<11>:
 C_SIGNAL='@s9s_mb_2u_lib.s9s_mb_2u(sch_1):m_b_cpu0_sb_dq(11)';
NODE_NAME     U2 N25
 '@S9S_MB_2U_LIB.S9S_MB_2U(SCH_1):PAGE21_I169@PURE_QUANTA.SOCKET4677_AZIF0045P001C01CS(CHIPS)':
 'DDR1_SB_DQ11': CDS_PINID='DDR1_SB_DQ11';
NODE_NAME     J4 258
 '@S9S_MB_2U_LIB.S9S_MB_2U(SCH_1):PAGE85_I23@PURE_QUANTA.SCONN288_ADR50017P087CC(CHIPS)':
 'DQ11_B': CDS_PINID='DQ11_B';
NODE_NAME     J3 258
 '@S9S_MB_2U_LIB.S9S_MB_2U(SCH_1):PAGE84_I180@PURE_QUANTA.SCONN288_ADR50017P130CC(CHIPS)':
 'DQ11_B': CDS_PINID='DQ11_B';
NET_NAME
'M_B_CPU0_SB_DQ<12>'
 '@S9S_MB_2U_LIB.S9S_MB_2U(SCH_1):M_B_CPU0_SB_DQ'<12>:
 C_SIGNAL='@s9s_mb_2u_lib.s9s_mb_2u(sch_1):m_b_cpu0_sb_dq(12)';
NODE_NAME     U2 J23
 '@S9S_MB_2U_LIB.S9S_MB_2U(SCH_1):PAGE21_I169@PURE_QUANTA.SOCKET4677_AZIF0045P001C01CS(CHIPS)':
 'DDR1_SB_DQ12': CDS_PINID='DDR1_SB_DQ12';
NODE_NAME     J4 118
 '@S9S_MB_2U_LIB.S9S_MB_2U(SCH_1):PAGE85_I23@PURE_QUANTA.SCONN288_ADR50017P087CC(CHIPS)':
 'DQ12_B': CDS_PINID='DQ12_B';
NODE_NAME     J3 118
 '@S9S_MB_2U_LIB.S9S_MB_2U(SCH_1):PAGE84_I180@PURE_QUANTA.SCONN288_ADR50017P130CC(CHIPS)':
 'DQ12_B': CDS_PINID='DQ12_B';
NET_NAME
'M_B_CPU0_SB_DQ<13>'
 '@S9S_MB_2U_LIB.S9S_MB_2U(SCH_1):M_B_CPU0_SB_DQ'<13>:
 C_SIGNAL='@s9s_mb_2u_lib.s9s_mb_2u(sch_1):m_b_cpu0_sb_dq(13)';
NODE_NAME     U2 K22
 '@S9S_MB_2U_LIB.S9S_MB_2U(SCH_1):PAGE21_I169@PURE_QUANTA.SOCKET4677_AZIF0045P001C01CS(CHIPS)':
 'DDR1_SB_DQ13': CDS_PINID='DDR1_SB_DQ13';
NODE_NAME     J4 120
 '@S9S_MB_2U_LIB.S9S_MB_2U(SCH_1):PAGE85_I23@PURE_QUANTA.SCONN288_ADR50017P087CC(CHIPS)':
 'DQ13_B': CDS_PINID='DQ13_B';
NODE_NAME     J3 120
 '@S9S_MB_2U_LIB.S9S_MB_2U(SCH_1):PAGE84_I180@PURE_QUANTA.SCONN288_ADR50017P130CC(CHIPS)':
 'DQ13_B': CDS_PINID='DQ13_B';
NET_NAME
'M_B_CPU0_SB_DQ<14>'
 '@S9S_MB_2U_LIB.S9S_MB_2U(SCH_1):M_B_CPU0_SB_DQ'<14>:
 C_SIGNAL='@s9s_mb_2u_lib.s9s_mb_2u(sch_1):m_b_cpu0_sb_dq(14)';
NODE_NAME     U2 N23
 '@S9S_MB_2U_LIB.S9S_MB_2U(SCH_1):PAGE21_I169@PURE_QUANTA.SOCKET4677_AZIF0045P001C01CS(CHIPS)':
 'DDR1_SB_DQ14': CDS_PINID='DDR1_SB_DQ14';
NODE_NAME     J4 263
 '@S9S_MB_2U_LIB.S9S_MB_2U(SCH_1):PAGE85_I23@PURE_QUANTA.SCONN288_ADR50017P087CC(CHIPS)':
 'DQ14_B': CDS_PINID='DQ14_B';
NODE_NAME     J3 263
 '@S9S_MB_2U_LIB.S9S_MB_2U(SCH_1):PAGE84_I180@PURE_QUANTA.SCONN288_ADR50017P130CC(CHIPS)':
 'DQ14_B': CDS_PINID='DQ14_B';
NET_NAME
'M_B_CPU0_SB_DQ<15>'
 '@S9S_MB_2U_LIB.S9S_MB_2U(SCH_1):M_B_CPU0_SB_DQ'<15>:
 C_SIGNAL='@s9s_mb_2u_lib.s9s_mb_2u(sch_1):m_b_cpu0_sb_dq(15)';
NODE_NAME     U2 M22
 '@S9S_MB_2U_LIB.S9S_MB_2U(SCH_1):PAGE21_I169@PURE_QUANTA.SOCKET4677_AZIF0045P001C01CS(CHIPS)':
 'DDR1_SB_DQ15': CDS_PINID='DDR1_SB_DQ15';
NODE_NAME     J4 265
 '@S9S_MB_2U_LIB.S9S_MB_2U(SCH_1):PAGE85_I23@PURE_QUANTA.SCONN288_ADR50017P087CC(CHIPS)':
 'DQ15_B': CDS_PINID='DQ15_B';
NODE_NAME     J3 265
 '@S9S_MB_2U_LIB.S9S_MB_2U(SCH_1):PAGE84_I180@PURE_QUANTA.SCONN288_ADR50017P130CC(CHIPS)':
 'DQ15_B': CDS_PINID='DQ15_B';
NET_NAME
'M_B_CPU0_SB_DQ<16>'
 '@S9S_MB_2U_LIB.S9S_MB_2U(SCH_1):M_B_CPU0_SB_DQ'<16>:
 C_SIGNAL='@s9s_mb_2u_lib.s9s_mb_2u(sch_1):m_b_cpu0_sb_dq(16)';
NODE_NAME     U2 K20
 '@S9S_MB_2U_LIB.S9S_MB_2U(SCH_1):PAGE21_I169@PURE_QUANTA.SOCKET4677_AZIF0045P001C01CS(CHIPS)':
 'DDR1_SB_DQ16': CDS_PINID='DDR1_SB_DQ16';
NODE_NAME     J4 122
 '@S9S_MB_2U_LIB.S9S_MB_2U(SCH_1):PAGE85_I23@PURE_QUANTA.SCONN288_ADR50017P087CC(CHIPS)':
 'DQ16_B': CDS_PINID='DQ16_B';
NODE_NAME     J3 122
 '@S9S_MB_2U_LIB.S9S_MB_2U(SCH_1):PAGE84_I180@PURE_QUANTA.SCONN288_ADR50017P130CC(CHIPS)':
 'DQ16_B': CDS_PINID='DQ16_B';
NET_NAME
'M_B_CPU0_SB_DQ<17>'
 '@S9S_MB_2U_LIB.S9S_MB_2U(SCH_1):M_B_CPU0_SB_DQ'<17>:
 C_SIGNAL='@s9s_mb_2u_lib.s9s_mb_2u(sch_1):m_b_cpu0_sb_dq(17)';
NODE_NAME     U2 J19
 '@S9S_MB_2U_LIB.S9S_MB_2U(SCH_1):PAGE21_I169@PURE_QUANTA.SOCKET4677_AZIF0045P001C01CS(CHIPS)':
 'DDR1_SB_DQ17': CDS_PINID='DDR1_SB_DQ17';
NODE_NAME     J4 124
 '@S9S_MB_2U_LIB.S9S_MB_2U(SCH_1):PAGE85_I23@PURE_QUANTA.SCONN288_ADR50017P087CC(CHIPS)':
 'DQ17_B': CDS_PINID='DQ17_B';
NODE_NAME     J3 124
 '@S9S_MB_2U_LIB.S9S_MB_2U(SCH_1):PAGE84_I180@PURE_QUANTA.SCONN288_ADR50017P130CC(CHIPS)':
 'DQ17_B': CDS_PINID='DQ17_B';
NET_NAME
'M_B_CPU0_SB_DQ<18>'
 '@S9S_MB_2U_LIB.S9S_MB_2U(SCH_1):M_B_CPU0_SB_DQ'<18>:
 C_SIGNAL='@s9s_mb_2u_lib.s9s_mb_2u(sch_1):m_b_cpu0_sb_dq(18)';
NODE_NAME     U2 M20
 '@S9S_MB_2U_LIB.S9S_MB_2U(SCH_1):PAGE21_I169@PURE_QUANTA.SOCKET4677_AZIF0045P001C01CS(CHIPS)':
 'DDR1_SB_DQ18': CDS_PINID='DDR1_SB_DQ18';
NODE_NAME     J4 267
 '@S9S_MB_2U_LIB.S9S_MB_2U(SCH_1):PAGE85_I23@PURE_QUANTA.SCONN288_ADR50017P087CC(CHIPS)':
 'DQ18_B': CDS_PINID='DQ18_B';
NODE_NAME     J3 267
 '@S9S_MB_2U_LIB.S9S_MB_2U(SCH_1):PAGE84_I180@PURE_QUANTA.SCONN288_ADR50017P130CC(CHIPS)':
 'DQ18_B': CDS_PINID='DQ18_B';
NET_NAME
'M_B_CPU0_SB_DQ<19>'
 '@S9S_MB_2U_LIB.S9S_MB_2U(SCH_1):M_B_CPU0_SB_DQ'<19>:
 C_SIGNAL='@s9s_mb_2u_lib.s9s_mb_2u(sch_1):m_b_cpu0_sb_dq(19)';
NODE_NAME     U2 N19
 '@S9S_MB_2U_LIB.S9S_MB_2U(SCH_1):PAGE21_I169@PURE_QUANTA.SOCKET4677_AZIF0045P001C01CS(CHIPS)':
 'DDR1_SB_DQ19': CDS_PINID='DDR1_SB_DQ19';
NODE_NAME     J4 269
 '@S9S_MB_2U_LIB.S9S_MB_2U(SCH_1):PAGE85_I23@PURE_QUANTA.SCONN288_ADR50017P087CC(CHIPS)':
 'DQ19_B': CDS_PINID='DQ19_B';
NODE_NAME     J3 269
 '@S9S_MB_2U_LIB.S9S_MB_2U(SCH_1):PAGE84_I180@PURE_QUANTA.SCONN288_ADR50017P130CC(CHIPS)':
 'DQ19_B': CDS_PINID='DQ19_B';
NET_NAME
'M_B_CPU0_SB_DQ<1>'
 '@S9S_MB_2U_LIB.S9S_MB_2U(SCH_1):M_B_CPU0_SB_DQ'<1>:
 C_SIGNAL='@s9s_mb_2u_lib.s9s_mb_2u(sch_1):m_b_cpu0_sb_dq(1)';
NODE_NAME     U2 T28
 '@S9S_MB_2U_LIB.S9S_MB_2U(SCH_1):PAGE21_I169@PURE_QUANTA.SOCKET4677_AZIF0045P001C01CS(CHIPS)':
 'DDR1_SB_DQ1': CDS_PINID='DDR1_SB_DQ1';
NODE_NAME     J4 102
 '@S9S_MB_2U_LIB.S9S_MB_2U(SCH_1):PAGE85_I23@PURE_QUANTA.SCONN288_ADR50017P087CC(CHIPS)':
 'DQ1_B': CDS_PINID='DQ1_B';
NODE_NAME     J3 102
 '@S9S_MB_2U_LIB.S9S_MB_2U(SCH_1):PAGE84_I180@PURE_QUANTA.SCONN288_ADR50017P130CC(CHIPS)':
 'DQ1_B': CDS_PINID='DQ1_B';
NET_NAME
'M_B_CPU0_SB_DQ<20>'
 '@S9S_MB_2U_LIB.S9S_MB_2U(SCH_1):M_B_CPU0_SB_DQ'<20>:
 C_SIGNAL='@s9s_mb_2u_lib.s9s_mb_2u(sch_1):m_b_cpu0_sb_dq(20)';
NODE_NAME     U2 J17
 '@S9S_MB_2U_LIB.S9S_MB_2U(SCH_1):PAGE21_I169@PURE_QUANTA.SOCKET4677_AZIF0045P001C01CS(CHIPS)':
 'DDR1_SB_DQ20': CDS_PINID='DDR1_SB_DQ20';
NODE_NAME     J4 129
 '@S9S_MB_2U_LIB.S9S_MB_2U(SCH_1):PAGE85_I23@PURE_QUANTA.SCONN288_ADR50017P087CC(CHIPS)':
 'DQ20_B': CDS_PINID='DQ20_B';
NODE_NAME     J3 129
 '@S9S_MB_2U_LIB.S9S_MB_2U(SCH_1):PAGE84_I180@PURE_QUANTA.SCONN288_ADR50017P130CC(CHIPS)':
 'DQ20_B': CDS_PINID='DQ20_B';
NET_NAME
'M_B_CPU0_SB_DQ<21>'
 '@S9S_MB_2U_LIB.S9S_MB_2U(SCH_1):M_B_CPU0_SB_DQ'<21>:
 C_SIGNAL='@s9s_mb_2u_lib.s9s_mb_2u(sch_1):m_b_cpu0_sb_dq(21)';
NODE_NAME     U2 K16
 '@S9S_MB_2U_LIB.S9S_MB_2U(SCH_1):PAGE21_I169@PURE_QUANTA.SOCKET4677_AZIF0045P001C01CS(CHIPS)':
 'DDR1_SB_DQ21': CDS_PINID='DDR1_SB_DQ21';
NODE_NAME     J4 131
 '@S9S_MB_2U_LIB.S9S_MB_2U(SCH_1):PAGE85_I23@PURE_QUANTA.SCONN288_ADR50017P087CC(CHIPS)':
 'DQ21_B': CDS_PINID='DQ21_B';
NODE_NAME     J3 131
 '@S9S_MB_2U_LIB.S9S_MB_2U(SCH_1):PAGE84_I180@PURE_QUANTA.SCONN288_ADR50017P130CC(CHIPS)':
 'DQ21_B': CDS_PINID='DQ21_B';
NET_NAME
'M_B_CPU0_SB_DQ<22>'
 '@S9S_MB_2U_LIB.S9S_MB_2U(SCH_1):M_B_CPU0_SB_DQ'<22>:
 C_SIGNAL='@s9s_mb_2u_lib.s9s_mb_2u(sch_1):m_b_cpu0_sb_dq(22)';
NODE_NAME     U2 N17
 '@S9S_MB_2U_LIB.S9S_MB_2U(SCH_1):PAGE21_I169@PURE_QUANTA.SOCKET4677_AZIF0045P001C01CS(CHIPS)':
 'DDR1_SB_DQ22': CDS_PINID='DDR1_SB_DQ22';
NODE_NAME     J4 274
 '@S9S_MB_2U_LIB.S9S_MB_2U(SCH_1):PAGE85_I23@PURE_QUANTA.SCONN288_ADR50017P087CC(CHIPS)':
 'DQ22_B': CDS_PINID='DQ22_B';
NODE_NAME     J3 274
 '@S9S_MB_2U_LIB.S9S_MB_2U(SCH_1):PAGE84_I180@PURE_QUANTA.SCONN288_ADR50017P130CC(CHIPS)':
 'DQ22_B': CDS_PINID='DQ22_B';
NET_NAME
'M_B_CPU0_SB_DQ<23>'
 '@S9S_MB_2U_LIB.S9S_MB_2U(SCH_1):M_B_CPU0_SB_DQ'<23>:
 C_SIGNAL='@s9s_mb_2u_lib.s9s_mb_2u(sch_1):m_b_cpu0_sb_dq(23)';
NODE_NAME     U2 M16
 '@S9S_MB_2U_LIB.S9S_MB_2U(SCH_1):PAGE21_I169@PURE_QUANTA.SOCKET4677_AZIF0045P001C01CS(CHIPS)':
 'DDR1_SB_DQ23': CDS_PINID='DDR1_SB_DQ23';
NODE_NAME     J4 276
 '@S9S_MB_2U_LIB.S9S_MB_2U(SCH_1):PAGE85_I23@PURE_QUANTA.SCONN288_ADR50017P087CC(CHIPS)':
 'DQ23_B': CDS_PINID='DQ23_B';
NODE_NAME     J3 276
 '@S9S_MB_2U_LIB.S9S_MB_2U(SCH_1):PAGE84_I180@PURE_QUANTA.SCONN288_ADR50017P130CC(CHIPS)':
 'DQ23_B': CDS_PINID='DQ23_B';
NET_NAME
'M_B_CPU0_SB_DQ<24>'
 '@S9S_MB_2U_LIB.S9S_MB_2U(SCH_1):M_B_CPU0_SB_DQ'<24>:
 C_SIGNAL='@s9s_mb_2u_lib.s9s_mb_2u(sch_1):m_b_cpu0_sb_dq(24)';
NODE_NAME     U2 C17
 '@S9S_MB_2U_LIB.S9S_MB_2U(SCH_1):PAGE21_I169@PURE_QUANTA.SOCKET4677_AZIF0045P001C01CS(CHIPS)':
 'DDR1_SB_DQ24': CDS_PINID='DDR1_SB_DQ24';
NODE_NAME     J4 133
 '@S9S_MB_2U_LIB.S9S_MB_2U(SCH_1):PAGE85_I23@PURE_QUANTA.SCONN288_ADR50017P087CC(CHIPS)':
 'DQ24_B': CDS_PINID='DQ24_B';
NODE_NAME     J3 133
 '@S9S_MB_2U_LIB.S9S_MB_2U(SCH_1):PAGE84_I180@PURE_QUANTA.SCONN288_ADR50017P130CC(CHIPS)':
 'DQ24_B': CDS_PINID='DQ24_B';
NET_NAME
'M_B_CPU0_SB_DQ<25>'
 '@S9S_MB_2U_LIB.S9S_MB_2U(SCH_1):M_B_CPU0_SB_DQ'<25>:
 C_SIGNAL='@s9s_mb_2u_lib.s9s_mb_2u(sch_1):m_b_cpu0_sb_dq(25)';
NODE_NAME     U2 B16
 '@S9S_MB_2U_LIB.S9S_MB_2U(SCH_1):PAGE21_I169@PURE_QUANTA.SOCKET4677_AZIF0045P001C01CS(CHIPS)':
 'DDR1_SB_DQ25': CDS_PINID='DDR1_SB_DQ25';
NODE_NAME     J4 135
 '@S9S_MB_2U_LIB.S9S_MB_2U(SCH_1):PAGE85_I23@PURE_QUANTA.SCONN288_ADR50017P087CC(CHIPS)':
 'DQ25_B': CDS_PINID='DQ25_B';
NODE_NAME     J3 135
 '@S9S_MB_2U_LIB.S9S_MB_2U(SCH_1):PAGE84_I180@PURE_QUANTA.SCONN288_ADR50017P130CC(CHIPS)':
 'DQ25_B': CDS_PINID='DQ25_B';
NET_NAME
'M_B_CPU0_SB_DQ<26>'
 '@S9S_MB_2U_LIB.S9S_MB_2U(SCH_1):M_B_CPU0_SB_DQ'<26>:
 C_SIGNAL='@s9s_mb_2u_lib.s9s_mb_2u(sch_1):m_b_cpu0_sb_dq(26)';
NODE_NAME     U2 E17
 '@S9S_MB_2U_LIB.S9S_MB_2U(SCH_1):PAGE21_I169@PURE_QUANTA.SOCKET4677_AZIF0045P001C01CS(CHIPS)':
 'DDR1_SB_DQ26': CDS_PINID='DDR1_SB_DQ26';
NODE_NAME     J4 278
 '@S9S_MB_2U_LIB.S9S_MB_2U(SCH_1):PAGE85_I23@PURE_QUANTA.SCONN288_ADR50017P087CC(CHIPS)':
 'DQ26_B': CDS_PINID='DQ26_B';
NODE_NAME     J3 278
 '@S9S_MB_2U_LIB.S9S_MB_2U(SCH_1):PAGE84_I180@PURE_QUANTA.SCONN288_ADR50017P130CC(CHIPS)':
 'DQ26_B': CDS_PINID='DQ26_B';
NET_NAME
'M_B_CPU0_SB_DQ<27>'
 '@S9S_MB_2U_LIB.S9S_MB_2U(SCH_1):M_B_CPU0_SB_DQ'<27>:
 C_SIGNAL='@s9s_mb_2u_lib.s9s_mb_2u(sch_1):m_b_cpu0_sb_dq(27)';
NODE_NAME     U2 F16
 '@S9S_MB_2U_LIB.S9S_MB_2U(SCH_1):PAGE21_I169@PURE_QUANTA.SOCKET4677_AZIF0045P001C01CS(CHIPS)':
 'DDR1_SB_DQ27': CDS_PINID='DDR1_SB_DQ27';
NODE_NAME     J4 280
 '@S9S_MB_2U_LIB.S9S_MB_2U(SCH_1):PAGE85_I23@PURE_QUANTA.SCONN288_ADR50017P087CC(CHIPS)':
 'DQ27_B': CDS_PINID='DQ27_B';
NODE_NAME     J3 280
 '@S9S_MB_2U_LIB.S9S_MB_2U(SCH_1):PAGE84_I180@PURE_QUANTA.SCONN288_ADR50017P130CC(CHIPS)':
 'DQ27_B': CDS_PINID='DQ27_B';
NET_NAME
'M_B_CPU0_SB_DQ<28>'
 '@S9S_MB_2U_LIB.S9S_MB_2U(SCH_1):M_B_CPU0_SB_DQ'<28>:
 C_SIGNAL='@s9s_mb_2u_lib.s9s_mb_2u(sch_1):m_b_cpu0_sb_dq(28)';
NODE_NAME     U2 C13
 '@S9S_MB_2U_LIB.S9S_MB_2U(SCH_1):PAGE21_I169@PURE_QUANTA.SOCKET4677_AZIF0045P001C01CS(CHIPS)':
 'DDR1_SB_DQ28': CDS_PINID='DDR1_SB_DQ28';
NODE_NAME     J4 140
 '@S9S_MB_2U_LIB.S9S_MB_2U(SCH_1):PAGE85_I23@PURE_QUANTA.SCONN288_ADR50017P087CC(CHIPS)':
 'DQ28_B': CDS_PINID='DQ28_B';
NODE_NAME     J3 140
 '@S9S_MB_2U_LIB.S9S_MB_2U(SCH_1):PAGE84_I180@PURE_QUANTA.SCONN288_ADR50017P130CC(CHIPS)':
 'DQ28_B': CDS_PINID='DQ28_B';
NET_NAME
'M_B_CPU0_SB_DQ<29>'
 '@S9S_MB_2U_LIB.S9S_MB_2U(SCH_1):M_B_CPU0_SB_DQ'<29>:
 C_SIGNAL='@s9s_mb_2u_lib.s9s_mb_2u(sch_1):m_b_cpu0_sb_dq(29)';
NODE_NAME     U2 E13
 '@S9S_MB_2U_LIB.S9S_MB_2U(SCH_1):PAGE21_I169@PURE_QUANTA.SOCKET4677_AZIF0045P001C01CS(CHIPS)':
 'DDR1_SB_DQ29': CDS_PINID='DDR1_SB_DQ29';
NODE_NAME     J4 142
 '@S9S_MB_2U_LIB.S9S_MB_2U(SCH_1):PAGE85_I23@PURE_QUANTA.SCONN288_ADR50017P087CC(CHIPS)':
 'DQ29_B': CDS_PINID='DQ29_B';
NODE_NAME     J3 142
 '@S9S_MB_2U_LIB.S9S_MB_2U(SCH_1):PAGE84_I180@PURE_QUANTA.SCONN288_ADR50017P130CC(CHIPS)':
 'DQ29_B': CDS_PINID='DQ29_B';
NET_NAME
'M_B_CPU0_SB_DQ<2>'
 '@S9S_MB_2U_LIB.S9S_MB_2U(SCH_1):M_B_CPU0_SB_DQ'<2>:
 C_SIGNAL='@s9s_mb_2u_lib.s9s_mb_2u(sch_1):m_b_cpu0_sb_dq(2)';
NODE_NAME     U2 W29
 '@S9S_MB_2U_LIB.S9S_MB_2U(SCH_1):PAGE21_I169@PURE_QUANTA.SOCKET4677_AZIF0045P001C01CS(CHIPS)':
 'DDR1_SB_DQ2': CDS_PINID='DDR1_SB_DQ2';
NODE_NAME     J4 245
 '@S9S_MB_2U_LIB.S9S_MB_2U(SCH_1):PAGE85_I23@PURE_QUANTA.SCONN288_ADR50017P087CC(CHIPS)':
 'DQ2_B': CDS_PINID='DQ2_B';
NODE_NAME     J3 245
 '@S9S_MB_2U_LIB.S9S_MB_2U(SCH_1):PAGE84_I180@PURE_QUANTA.SCONN288_ADR50017P130CC(CHIPS)':
 'DQ2_B': CDS_PINID='DQ2_B';
NET_NAME
'M_B_CPU0_SB_DQ<30>'
 '@S9S_MB_2U_LIB.S9S_MB_2U(SCH_1):M_B_CPU0_SB_DQ'<30>:
 C_SIGNAL='@s9s_mb_2u_lib.s9s_mb_2u(sch_1):m_b_cpu0_sb_dq(30)';
NODE_NAME     U2 B14
 '@S9S_MB_2U_LIB.S9S_MB_2U(SCH_1):PAGE21_I169@PURE_QUANTA.SOCKET4677_AZIF0045P001C01CS(CHIPS)':
 'DDR1_SB_DQ30': CDS_PINID='DDR1_SB_DQ30';
NODE_NAME     J4 285
 '@S9S_MB_2U_LIB.S9S_MB_2U(SCH_1):PAGE85_I23@PURE_QUANTA.SCONN288_ADR50017P087CC(CHIPS)':
 'DQ30_B': CDS_PINID='DQ30_B';
NODE_NAME     J3 285
 '@S9S_MB_2U_LIB.S9S_MB_2U(SCH_1):PAGE84_I180@PURE_QUANTA.SCONN288_ADR50017P130CC(CHIPS)':
 'DQ30_B': CDS_PINID='DQ30_B';
NET_NAME
'M_B_CPU0_SB_DQ<31>'
 '@S9S_MB_2U_LIB.S9S_MB_2U(SCH_1):M_B_CPU0_SB_DQ'<31>:
 C_SIGNAL='@s9s_mb_2u_lib.s9s_mb_2u(sch_1):m_b_cpu0_sb_dq(31)';
NODE_NAME     U2 F14
 '@S9S_MB_2U_LIB.S9S_MB_2U(SCH_1):PAGE21_I169@PURE_QUANTA.SOCKET4677_AZIF0045P001C01CS(CHIPS)':
 'DDR1_SB_DQ31': CDS_PINID='DDR1_SB_DQ31';
NODE_NAME     J4 287
 '@S9S_MB_2U_LIB.S9S_MB_2U(SCH_1):PAGE85_I23@PURE_QUANTA.SCONN288_ADR50017P087CC(CHIPS)':
 'DQ31_B': CDS_PINID='DQ31_B';
NODE_NAME     J3 287
 '@S9S_MB_2U_LIB.S9S_MB_2U(SCH_1):PAGE84_I180@PURE_QUANTA.SCONN288_ADR50017P130CC(CHIPS)':
 'DQ31_B': CDS_PINID='DQ31_B';
NET_NAME
'M_B_CPU0_SB_DQ<3>'
 '@S9S_MB_2U_LIB.S9S_MB_2U(SCH_1):M_B_CPU0_SB_DQ'<3>:
 C_SIGNAL='@s9s_mb_2u_lib.s9s_mb_2u(sch_1):m_b_cpu0_sb_dq(3)';
NODE_NAME     U2 Y28
 '@S9S_MB_2U_LIB.S9S_MB_2U(SCH_1):PAGE21_I169@PURE_QUANTA.SOCKET4677_AZIF0045P001C01CS(CHIPS)':
 'DDR1_SB_DQ3': CDS_PINID='DDR1_SB_DQ3';
NODE_NAME     J4 247
 '@S9S_MB_2U_LIB.S9S_MB_2U(SCH_1):PAGE85_I23@PURE_QUANTA.SCONN288_ADR50017P087CC(CHIPS)':
 'DQ3_B': CDS_PINID='DQ3_B';
NODE_NAME     J3 247
 '@S9S_MB_2U_LIB.S9S_MB_2U(SCH_1):PAGE84_I180@PURE_QUANTA.SCONN288_ADR50017P130CC(CHIPS)':
 'DQ3_B': CDS_PINID='DQ3_B';
NET_NAME
'M_B_CPU0_SB_DQ<4>'
 '@S9S_MB_2U_LIB.S9S_MB_2U(SCH_1):M_B_CPU0_SB_DQ'<4>:
 C_SIGNAL='@s9s_mb_2u_lib.s9s_mb_2u(sch_1):m_b_cpu0_sb_dq(4)';
NODE_NAME     U2 T26
 '@S9S_MB_2U_LIB.S9S_MB_2U(SCH_1):PAGE21_I169@PURE_QUANTA.SOCKET4677_AZIF0045P001C01CS(CHIPS)':
 'DDR1_SB_DQ4': CDS_PINID='DDR1_SB_DQ4';
NODE_NAME     J4 107
 '@S9S_MB_2U_LIB.S9S_MB_2U(SCH_1):PAGE85_I23@PURE_QUANTA.SCONN288_ADR50017P087CC(CHIPS)':
 'DQ4_B': CDS_PINID='DQ4_B';
NODE_NAME     J3 107
 '@S9S_MB_2U_LIB.S9S_MB_2U(SCH_1):PAGE84_I180@PURE_QUANTA.SCONN288_ADR50017P130CC(CHIPS)':
 'DQ4_B': CDS_PINID='DQ4_B';
NET_NAME
'M_B_CPU0_SB_DQ<5>'
 '@S9S_MB_2U_LIB.S9S_MB_2U(SCH_1):M_B_CPU0_SB_DQ'<5>:
 C_SIGNAL='@s9s_mb_2u_lib.s9s_mb_2u(sch_1):m_b_cpu0_sb_dq(5)';
NODE_NAME     U2 U25
 '@S9S_MB_2U_LIB.S9S_MB_2U(SCH_1):PAGE21_I169@PURE_QUANTA.SOCKET4677_AZIF0045P001C01CS(CHIPS)':
 'DDR1_SB_DQ5': CDS_PINID='DDR1_SB_DQ5';
NODE_NAME     J4 109
 '@S9S_MB_2U_LIB.S9S_MB_2U(SCH_1):PAGE85_I23@PURE_QUANTA.SCONN288_ADR50017P087CC(CHIPS)':
 'DQ5_B': CDS_PINID='DQ5_B';
NODE_NAME     J3 109
 '@S9S_MB_2U_LIB.S9S_MB_2U(SCH_1):PAGE84_I180@PURE_QUANTA.SCONN288_ADR50017P130CC(CHIPS)':
 'DQ5_B': CDS_PINID='DQ5_B';
NET_NAME
'M_B_CPU0_SB_DQ<6>'
 '@S9S_MB_2U_LIB.S9S_MB_2U(SCH_1):M_B_CPU0_SB_DQ'<6>:
 C_SIGNAL='@s9s_mb_2u_lib.s9s_mb_2u(sch_1):m_b_cpu0_sb_dq(6)';
NODE_NAME     U2 Y26
 '@S9S_MB_2U_LIB.S9S_MB_2U(SCH_1):PAGE21_I169@PURE_QUANTA.SOCKET4677_AZIF0045P001C01CS(CHIPS)':
 'DDR1_SB_DQ6': CDS_PINID='DDR1_SB_DQ6';
NODE_NAME     J4 252
 '@S9S_MB_2U_LIB.S9S_MB_2U(SCH_1):PAGE85_I23@PURE_QUANTA.SCONN288_ADR50017P087CC(CHIPS)':
 'DQ6_B': CDS_PINID='DQ6_B';
NODE_NAME     J3 252
 '@S9S_MB_2U_LIB.S9S_MB_2U(SCH_1):PAGE84_I180@PURE_QUANTA.SCONN288_ADR50017P130CC(CHIPS)':
 'DQ6_B': CDS_PINID='DQ6_B';
NET_NAME
'M_B_CPU0_SB_DQ<7>'
 '@S9S_MB_2U_LIB.S9S_MB_2U(SCH_1):M_B_CPU0_SB_DQ'<7>:
 C_SIGNAL='@s9s_mb_2u_lib.s9s_mb_2u(sch_1):m_b_cpu0_sb_dq(7)';
NODE_NAME     U2 W25
 '@S9S_MB_2U_LIB.S9S_MB_2U(SCH_1):PAGE21_I169@PURE_QUANTA.SOCKET4677_AZIF0045P001C01CS(CHIPS)':
 'DDR1_SB_DQ7': CDS_PINID='DDR1_SB_DQ7';
NODE_NAME     J4 254
 '@S9S_MB_2U_LIB.S9S_MB_2U(SCH_1):PAGE85_I23@PURE_QUANTA.SCONN288_ADR50017P087CC(CHIPS)':
 'DQ7_B': CDS_PINID='DQ7_B';
NODE_NAME     J3 254
 '@S9S_MB_2U_LIB.S9S_MB_2U(SCH_1):PAGE84_I180@PURE_QUANTA.SCONN288_ADR50017P130CC(CHIPS)':
 'DQ7_B': CDS_PINID='DQ7_B';
NET_NAME
'M_B_CPU0_SB_DQ<8>'
 '@S9S_MB_2U_LIB.S9S_MB_2U(SCH_1):M_B_CPU0_SB_DQ'<8>:
 C_SIGNAL='@s9s_mb_2u_lib.s9s_mb_2u(sch_1):m_b_cpu0_sb_dq(8)';
NODE_NAME     U2 K26
 '@S9S_MB_2U_LIB.S9S_MB_2U(SCH_1):PAGE21_I169@PURE_QUANTA.SOCKET4677_AZIF0045P001C01CS(CHIPS)':
 'DDR1_SB_DQ8': CDS_PINID='DDR1_SB_DQ8';
NODE_NAME     J4 111
 '@S9S_MB_2U_LIB.S9S_MB_2U(SCH_1):PAGE85_I23@PURE_QUANTA.SCONN288_ADR50017P087CC(CHIPS)':
 'DQ8_B': CDS_PINID='DQ8_B';
NODE_NAME     J3 111
 '@S9S_MB_2U_LIB.S9S_MB_2U(SCH_1):PAGE84_I180@PURE_QUANTA.SCONN288_ADR50017P130CC(CHIPS)':
 'DQ8_B': CDS_PINID='DQ8_B';
NET_NAME
'M_B_CPU0_SB_DQ<9>'
 '@S9S_MB_2U_LIB.S9S_MB_2U(SCH_1):M_B_CPU0_SB_DQ'<9>:
 C_SIGNAL='@s9s_mb_2u_lib.s9s_mb_2u(sch_1):m_b_cpu0_sb_dq(9)';
NODE_NAME     U2 J25
 '@S9S_MB_2U_LIB.S9S_MB_2U(SCH_1):PAGE21_I169@PURE_QUANTA.SOCKET4677_AZIF0045P001C01CS(CHIPS)':
 'DDR1_SB_DQ9': CDS_PINID='DDR1_SB_DQ9';
NODE_NAME     J4 113
 '@S9S_MB_2U_LIB.S9S_MB_2U(SCH_1):PAGE85_I23@PURE_QUANTA.SCONN288_ADR50017P087CC(CHIPS)':
 'DQ9_B': CDS_PINID='DQ9_B';
NODE_NAME     J3 113
 '@S9S_MB_2U_LIB.S9S_MB_2U(SCH_1):PAGE84_I180@PURE_QUANTA.SCONN288_ADR50017P130CC(CHIPS)':
 'DQ9_B': CDS_PINID='DQ9_B';
NET_NAME
'M_B_CPU0_SB_DQS_DN<0>'
 '@S9S_MB_2U_LIB.S9S_MB_2U(SCH_1):M_B_CPU0_SB_DQS_DN'<0>:
 C_SIGNAL='@s9s_mb_2u_lib.s9s_mb_2u(sch_1):m_b_cpu0_sb_dqs_dn(0)';
NODE_NAME     U2 R27
 '@S9S_MB_2U_LIB.S9S_MB_2U(SCH_1):PAGE21_I169@PURE_QUANTA.SOCKET4677_AZIF0045P001C01CS(CHIPS)':
 'DDR1_SB_DQS_DN0': CDS_PINID='DDR1_SB_DQS_DN0';
NODE_NAME     J4 105
 '@S9S_MB_2U_LIB.S9S_MB_2U(SCH_1):PAGE85_I178@PURE_QUANTA.SCONN288_ADR50017P087CC(CHIPS)':
 'DQS0_B_C': CDS_PINID='DQS0_B_C';
NODE_NAME     J3 105
 '@S9S_MB_2U_LIB.S9S_MB_2U(SCH_1):PAGE84_I179@PURE_QUANTA.SCONN288_ADR50017P130CC(CHIPS)':
 'DQS0_B_C': CDS_PINID='DQS0_B_C';
NET_NAME
'M_B_CPU0_SB_DQS_DN<1>'
 '@S9S_MB_2U_LIB.S9S_MB_2U(SCH_1):M_B_CPU0_SB_DQS_DN'<1>:
 C_SIGNAL='@s9s_mb_2u_lib.s9s_mb_2u(sch_1):m_b_cpu0_sb_dqs_dn(1)';
NODE_NAME     U2 H24
 '@S9S_MB_2U_LIB.S9S_MB_2U(SCH_1):PAGE21_I169@PURE_QUANTA.SOCKET4677_AZIF0045P001C01CS(CHIPS)':
 'DDR1_SB_DQS_DN1': CDS_PINID='DDR1_SB_DQS_DN1';
NODE_NAME     J4 116
 '@S9S_MB_2U_LIB.S9S_MB_2U(SCH_1):PAGE85_I178@PURE_QUANTA.SCONN288_ADR50017P087CC(CHIPS)':
 'DQS1_B_C': CDS_PINID='DQS1_B_C';
NODE_NAME     J3 116
 '@S9S_MB_2U_LIB.S9S_MB_2U(SCH_1):PAGE84_I179@PURE_QUANTA.SCONN288_ADR50017P130CC(CHIPS)':
 'DQS1_B_C': CDS_PINID='DQS1_B_C';
NET_NAME
'M_B_CPU0_SB_DQS_DN<2>'
 '@S9S_MB_2U_LIB.S9S_MB_2U(SCH_1):M_B_CPU0_SB_DQS_DN'<2>:
 C_SIGNAL='@s9s_mb_2u_lib.s9s_mb_2u(sch_1):m_b_cpu0_sb_dqs_dn(2)';
NODE_NAME     U2 H18
 '@S9S_MB_2U_LIB.S9S_MB_2U(SCH_1):PAGE21_I169@PURE_QUANTA.SOCKET4677_AZIF0045P001C01CS(CHIPS)':
 'DDR1_SB_DQS_DN2': CDS_PINID='DDR1_SB_DQS_DN2';
NODE_NAME     J4 127
 '@S9S_MB_2U_LIB.S9S_MB_2U(SCH_1):PAGE85_I178@PURE_QUANTA.SCONN288_ADR50017P087CC(CHIPS)':
 'DQS2_B_C': CDS_PINID='DQS2_B_C';
NODE_NAME     J3 127
 '@S9S_MB_2U_LIB.S9S_MB_2U(SCH_1):PAGE84_I179@PURE_QUANTA.SCONN288_ADR50017P130CC(CHIPS)':
 'DQS2_B_C': CDS_PINID='DQS2_B_C';
NET_NAME
'M_B_CPU0_SB_DQS_DN<3>'
 '@S9S_MB_2U_LIB.S9S_MB_2U(SCH_1):M_B_CPU0_SB_DQS_DN'<3>:
 C_SIGNAL='@s9s_mb_2u_lib.s9s_mb_2u(sch_1):m_b_cpu0_sb_dqs_dn(3)';
NODE_NAME     U2 A15
 '@S9S_MB_2U_LIB.S9S_MB_2U(SCH_1):PAGE21_I169@PURE_QUANTA.SOCKET4677_AZIF0045P001C01CS(CHIPS)':
 'DDR1_SB_DQS_DN3': CDS_PINID='DDR1_SB_DQS_DN3';
NODE_NAME     J4 138
 '@S9S_MB_2U_LIB.S9S_MB_2U(SCH_1):PAGE85_I178@PURE_QUANTA.SCONN288_ADR50017P087CC(CHIPS)':
 'DQS3_B_C': CDS_PINID='DQS3_B_C';
NODE_NAME     J3 138
 '@S9S_MB_2U_LIB.S9S_MB_2U(SCH_1):PAGE84_I179@PURE_QUANTA.SCONN288_ADR50017P130CC(CHIPS)':
 'DQS3_B_C': CDS_PINID='DQS3_B_C';
NET_NAME
'M_B_CPU0_SB_DQS_DN<4>'
 '@S9S_MB_2U_LIB.S9S_MB_2U(SCH_1):M_B_CPU0_SB_DQS_DN'<4>:
 C_SIGNAL='@s9s_mb_2u_lib.s9s_mb_2u(sch_1):m_b_cpu0_sb_dqs_dn(4)';
NODE_NAME     U2 P36
 '@S9S_MB_2U_LIB.S9S_MB_2U(SCH_1):PAGE21_I169@PURE_QUANTA.SOCKET4677_AZIF0045P001C01CS(CHIPS)':
 'DDR1_SB_DQS_DN4': CDS_PINID='DDR1_SB_DQS_DN4';
NODE_NAME     J4 238
 '@S9S_MB_2U_LIB.S9S_MB_2U(SCH_1):PAGE85_I178@PURE_QUANTA.SCONN288_ADR50017P087CC(CHIPS)':
 'DQS4_B_C': CDS_PINID='DQS4_B_C';
NODE_NAME     J3 238
 '@S9S_MB_2U_LIB.S9S_MB_2U(SCH_1):PAGE84_I179@PURE_QUANTA.SCONN288_ADR50017P130CC(CHIPS)':
 'DQS4_B_C': CDS_PINID='DQS4_B_C';
NET_NAME
'M_B_CPU0_SB_DQS_DN<5>'
 '@S9S_MB_2U_LIB.S9S_MB_2U(SCH_1):M_B_CPU0_SB_DQS_DN'<5>:
 C_SIGNAL='@s9s_mb_2u_lib.s9s_mb_2u(sch_1):m_b_cpu0_sb_dqs_dn(5)';
NODE_NAME     U2 W27
 '@S9S_MB_2U_LIB.S9S_MB_2U(SCH_1):PAGE21_I169@PURE_QUANTA.SOCKET4677_AZIF0045P001C01CS(CHIPS)':
 'DDR1_SB_DQS_DN5': CDS_PINID='DDR1_SB_DQS_DN5';
NODE_NAME     J4 249
 '@S9S_MB_2U_LIB.S9S_MB_2U(SCH_1):PAGE85_I178@PURE_QUANTA.SCONN288_ADR50017P087CC(CHIPS)':
 'DQS5_B_C||TDQS5_B_C': CDS_PINID='\dqs5_b_c||tdqs5_b_c\';
NODE_NAME     J3 249
 '@S9S_MB_2U_LIB.S9S_MB_2U(SCH_1):PAGE84_I179@PURE_QUANTA.SCONN288_ADR50017P130CC(CHIPS)':
 'DQS5_B_C||TDQS5_B_C': CDS_PINID='\dqs5_b_c||tdqs5_b_c\';
NET_NAME
'M_B_CPU0_SB_DQS_DN<6>'
 '@S9S_MB_2U_LIB.S9S_MB_2U(SCH_1):M_B_CPU0_SB_DQS_DN'<6>:
 C_SIGNAL='@s9s_mb_2u_lib.s9s_mb_2u(sch_1):m_b_cpu0_sb_dqs_dn(6)';
NODE_NAME     U2 M24
 '@S9S_MB_2U_LIB.S9S_MB_2U(SCH_1):PAGE21_I169@PURE_QUANTA.SOCKET4677_AZIF0045P001C01CS(CHIPS)':
 'DDR1_SB_DQS_DN6': CDS_PINID='DDR1_SB_DQS_DN6';
NODE_NAME     J4 260
 '@S9S_MB_2U_LIB.S9S_MB_2U(SCH_1):PAGE85_I178@PURE_QUANTA.SCONN288_ADR50017P087CC(CHIPS)':
 'DQS6_B_C||TDQS6_B_C': CDS_PINID='\dqs6_b_c||tdqs6_b_c\';
NODE_NAME     J3 260
 '@S9S_MB_2U_LIB.S9S_MB_2U(SCH_1):PAGE84_I179@PURE_QUANTA.SCONN288_ADR50017P130CC(CHIPS)':
 'DQS6_B_C||TDQS6_B_C': CDS_PINID='\dqs6_b_c||tdqs6_b_c\';
NET_NAME
'M_B_CPU0_SB_DQS_DN<7>'
 '@S9S_MB_2U_LIB.S9S_MB_2U(SCH_1):M_B_CPU0_SB_DQS_DN'<7>:
 C_SIGNAL='@s9s_mb_2u_lib.s9s_mb_2u(sch_1):m_b_cpu0_sb_dqs_dn(7)';
NODE_NAME     U2 M18
 '@S9S_MB_2U_LIB.S9S_MB_2U(SCH_1):PAGE21_I169@PURE_QUANTA.SOCKET4677_AZIF0045P001C01CS(CHIPS)':
 'DDR1_SB_DQS_DN7': CDS_PINID='DDR1_SB_DQS_DN7';
NODE_NAME     J4 271
 '@S9S_MB_2U_LIB.S9S_MB_2U(SCH_1):PAGE85_I178@PURE_QUANTA.SCONN288_ADR50017P087CC(CHIPS)':
 'DQS7_B_C||TDQS7_B_C': CDS_PINID='\dqs7_b_c||tdqs7_b_c\';
NODE_NAME     J3 271
 '@S9S_MB_2U_LIB.S9S_MB_2U(SCH_1):PAGE84_I179@PURE_QUANTA.SCONN288_ADR50017P130CC(CHIPS)':
 'DQS7_B_C||TDQS7_B_C': CDS_PINID='\dqs7_b_c||tdqs7_b_c\';
NET_NAME
'M_B_CPU0_SB_DQS_DN<8>'
 '@S9S_MB_2U_LIB.S9S_MB_2U(SCH_1):M_B_CPU0_SB_DQS_DN'<8>:
 C_SIGNAL='@s9s_mb_2u_lib.s9s_mb_2u(sch_1):m_b_cpu0_sb_dqs_dn(8)';
NODE_NAME     U2 E15
 '@S9S_MB_2U_LIB.S9S_MB_2U(SCH_1):PAGE21_I169@PURE_QUANTA.SOCKET4677_AZIF0045P001C01CS(CHIPS)':
 'DDR1_SB_DQS_DN8': CDS_PINID='DDR1_SB_DQS_DN8';
NODE_NAME     J4 282
 '@S9S_MB_2U_LIB.S9S_MB_2U(SCH_1):PAGE85_I178@PURE_QUANTA.SCONN288_ADR50017P087CC(CHIPS)':
 'DQS8_B_C||TDQS8_B_C': CDS_PINID='\dqs8_b_c||tdqs8_b_c\';
NODE_NAME     J3 282
 '@S9S_MB_2U_LIB.S9S_MB_2U(SCH_1):PAGE84_I179@PURE_QUANTA.SCONN288_ADR50017P130CC(CHIPS)':
 'DQS8_B_C||TDQS8_B_C': CDS_PINID='\dqs8_b_c||tdqs8_b_c\';
NET_NAME
'M_B_CPU0_SB_DQS_DN<9>'
 '@S9S_MB_2U_LIB.S9S_MB_2U(SCH_1):M_B_CPU0_SB_DQS_DN'<9>:
 C_SIGNAL='@s9s_mb_2u_lib.s9s_mb_2u(sch_1):m_b_cpu0_sb_dqs_dn(9)';
NODE_NAME     U2 K36
 '@S9S_MB_2U_LIB.S9S_MB_2U(SCH_1):PAGE21_I169@PURE_QUANTA.SOCKET4677_AZIF0045P001C01CS(CHIPS)':
 'DDR1_SB_DQS_DN9': CDS_PINID='DDR1_SB_DQS_DN9';
NODE_NAME     J4 94
 '@S9S_MB_2U_LIB.S9S_MB_2U(SCH_1):PAGE85_I178@PURE_QUANTA.SCONN288_ADR50017P087CC(CHIPS)':
 'DQS9_B_C||TDQS9_B_C': CDS_PINID='\dqs9_b_c||tdqs9_b_c\';
NODE_NAME     J3 94
 '@S9S_MB_2U_LIB.S9S_MB_2U(SCH_1):PAGE84_I179@PURE_QUANTA.SCONN288_ADR50017P130CC(CHIPS)':
 'DQS9_B_C||TDQS9_B_C': CDS_PINID='\dqs9_b_c||tdqs9_b_c\';
NET_NAME
'M_B_CPU0_SB_DQS_DP<0>'
 '@S9S_MB_2U_LIB.S9S_MB_2U(SCH_1):M_B_CPU0_SB_DQS_DP'<0>:
 C_SIGNAL='@s9s_mb_2u_lib.s9s_mb_2u(sch_1):m_b_cpu0_sb_dqs_dp(0)';
NODE_NAME     U2 U27
 '@S9S_MB_2U_LIB.S9S_MB_2U(SCH_1):PAGE21_I169@PURE_QUANTA.SOCKET4677_AZIF0045P001C01CS(CHIPS)':
 'DDR1_SB_DQS_DP0': CDS_PINID='DDR1_SB_DQS_DP0';
NODE_NAME     J4 104
 '@S9S_MB_2U_LIB.S9S_MB_2U(SCH_1):PAGE85_I178@PURE_QUANTA.SCONN288_ADR50017P087CC(CHIPS)':
 'DQS0_B_T': CDS_PINID='DQS0_B_T';
NODE_NAME     J3 104
 '@S9S_MB_2U_LIB.S9S_MB_2U(SCH_1):PAGE84_I179@PURE_QUANTA.SCONN288_ADR50017P130CC(CHIPS)':
 'DQS0_B_T': CDS_PINID='DQS0_B_T';
NET_NAME
'M_B_CPU0_SB_DQS_DP<1>'
 '@S9S_MB_2U_LIB.S9S_MB_2U(SCH_1):M_B_CPU0_SB_DQS_DP'<1>:
 C_SIGNAL='@s9s_mb_2u_lib.s9s_mb_2u(sch_1):m_b_cpu0_sb_dqs_dp(1)';
NODE_NAME     U2 K24
 '@S9S_MB_2U_LIB.S9S_MB_2U(SCH_1):PAGE21_I169@PURE_QUANTA.SOCKET4677_AZIF0045P001C01CS(CHIPS)':
 'DDR1_SB_DQS_DP1': CDS_PINID='DDR1_SB_DQS_DP1';
NODE_NAME     J4 115
 '@S9S_MB_2U_LIB.S9S_MB_2U(SCH_1):PAGE85_I178@PURE_QUANTA.SCONN288_ADR50017P087CC(CHIPS)':
 'DQS1_B_T': CDS_PINID='DQS1_B_T';
NODE_NAME     J3 115
 '@S9S_MB_2U_LIB.S9S_MB_2U(SCH_1):PAGE84_I179@PURE_QUANTA.SCONN288_ADR50017P130CC(CHIPS)':
 'DQS1_B_T': CDS_PINID='DQS1_B_T';
NET_NAME
'M_B_CPU0_SB_DQS_DP<2>'
 '@S9S_MB_2U_LIB.S9S_MB_2U(SCH_1):M_B_CPU0_SB_DQS_DP'<2>:
 C_SIGNAL='@s9s_mb_2u_lib.s9s_mb_2u(sch_1):m_b_cpu0_sb_dqs_dp(2)';
NODE_NAME     U2 K18
 '@S9S_MB_2U_LIB.S9S_MB_2U(SCH_1):PAGE21_I169@PURE_QUANTA.SOCKET4677_AZIF0045P001C01CS(CHIPS)':
 'DDR1_SB_DQS_DP2': CDS_PINID='DDR1_SB_DQS_DP2';
NODE_NAME     J4 126
 '@S9S_MB_2U_LIB.S9S_MB_2U(SCH_1):PAGE85_I178@PURE_QUANTA.SCONN288_ADR50017P087CC(CHIPS)':
 'DQS2_B_T': CDS_PINID='DQS2_B_T';
NODE_NAME     J3 126
 '@S9S_MB_2U_LIB.S9S_MB_2U(SCH_1):PAGE84_I179@PURE_QUANTA.SCONN288_ADR50017P130CC(CHIPS)':
 'DQS2_B_T': CDS_PINID='DQS2_B_T';
NET_NAME
'M_B_CPU0_SB_DQS_DP<3>'
 '@S9S_MB_2U_LIB.S9S_MB_2U(SCH_1):M_B_CPU0_SB_DQS_DP'<3>:
 C_SIGNAL='@s9s_mb_2u_lib.s9s_mb_2u(sch_1):m_b_cpu0_sb_dqs_dp(3)';
NODE_NAME     U2 C15
 '@S9S_MB_2U_LIB.S9S_MB_2U(SCH_1):PAGE21_I169@PURE_QUANTA.SOCKET4677_AZIF0045P001C01CS(CHIPS)':
 'DDR1_SB_DQS_DP3': CDS_PINID='DDR1_SB_DQS_DP3';
NODE_NAME     J4 137
 '@S9S_MB_2U_LIB.S9S_MB_2U(SCH_1):PAGE85_I178@PURE_QUANTA.SCONN288_ADR50017P087CC(CHIPS)':
 'DQS3_B_T': CDS_PINID='DQS3_B_T';
NODE_NAME     J3 137
 '@S9S_MB_2U_LIB.S9S_MB_2U(SCH_1):PAGE84_I179@PURE_QUANTA.SCONN288_ADR50017P130CC(CHIPS)':
 'DQS3_B_T': CDS_PINID='DQS3_B_T';
NET_NAME
'M_B_CPU0_SB_DQS_DP<4>'
 '@S9S_MB_2U_LIB.S9S_MB_2U(SCH_1):M_B_CPU0_SB_DQS_DP'<4>:
 C_SIGNAL='@s9s_mb_2u_lib.s9s_mb_2u(sch_1):m_b_cpu0_sb_dqs_dp(4)';
NODE_NAME     U2 M36
 '@S9S_MB_2U_LIB.S9S_MB_2U(SCH_1):PAGE21_I169@PURE_QUANTA.SOCKET4677_AZIF0045P001C01CS(CHIPS)':
 'DDR1_SB_DQS_DP4': CDS_PINID='DDR1_SB_DQS_DP4';
NODE_NAME     J4 239
 '@S9S_MB_2U_LIB.S9S_MB_2U(SCH_1):PAGE85_I178@PURE_QUANTA.SCONN288_ADR50017P087CC(CHIPS)':
 'DQS4_B_T': CDS_PINID='DQS4_B_T';
NODE_NAME     J3 239
 '@S9S_MB_2U_LIB.S9S_MB_2U(SCH_1):PAGE84_I179@PURE_QUANTA.SCONN288_ADR50017P130CC(CHIPS)':
 'DQS4_B_T': CDS_PINID='DQS4_B_T';
NET_NAME
'M_B_CPU0_SB_DQS_DP<5>'
 '@S9S_MB_2U_LIB.S9S_MB_2U(SCH_1):M_B_CPU0_SB_DQS_DP'<5>:
 C_SIGNAL='@s9s_mb_2u_lib.s9s_mb_2u(sch_1):m_b_cpu0_sb_dqs_dp(5)';
NODE_NAME     U2 AA27
 '@S9S_MB_2U_LIB.S9S_MB_2U(SCH_1):PAGE21_I169@PURE_QUANTA.SOCKET4677_AZIF0045P001C01CS(CHIPS)':
 'DDR1_SB_DQS_DP5': CDS_PINID='DDR1_SB_DQS_DP5';
NODE_NAME     J4 250
 '@S9S_MB_2U_LIB.S9S_MB_2U(SCH_1):PAGE85_I178@PURE_QUANTA.SCONN288_ADR50017P087CC(CHIPS)':
 'DQS5_B_T||TDQS5_B_T': CDS_PINID='\dqs5_b_t||tdqs5_b_t\';
NODE_NAME     J3 250
 '@S9S_MB_2U_LIB.S9S_MB_2U(SCH_1):PAGE84_I179@PURE_QUANTA.SCONN288_ADR50017P130CC(CHIPS)':
 'DQS5_B_T||TDQS5_B_T': CDS_PINID='\dqs5_b_t||tdqs5_b_t\';
NET_NAME
'M_B_CPU0_SB_DQS_DP<6>'
 '@S9S_MB_2U_LIB.S9S_MB_2U(SCH_1):M_B_CPU0_SB_DQS_DP'<6>:
 C_SIGNAL='@s9s_mb_2u_lib.s9s_mb_2u(sch_1):m_b_cpu0_sb_dqs_dp(6)';
NODE_NAME     U2 P24
 '@S9S_MB_2U_LIB.S9S_MB_2U(SCH_1):PAGE21_I169@PURE_QUANTA.SOCKET4677_AZIF0045P001C01CS(CHIPS)':
 'DDR1_SB_DQS_DP6': CDS_PINID='DDR1_SB_DQS_DP6';
NODE_NAME     J4 261
 '@S9S_MB_2U_LIB.S9S_MB_2U(SCH_1):PAGE85_I178@PURE_QUANTA.SCONN288_ADR50017P087CC(CHIPS)':
 'DQS6_B_T||TDQS6_B_T': CDS_PINID='\dqs6_b_t||tdqs6_b_t\';
NODE_NAME     J3 261
 '@S9S_MB_2U_LIB.S9S_MB_2U(SCH_1):PAGE84_I179@PURE_QUANTA.SCONN288_ADR50017P130CC(CHIPS)':
 'DQS6_B_T||TDQS6_B_T': CDS_PINID='\dqs6_b_t||tdqs6_b_t\';
NET_NAME
'M_B_CPU0_SB_DQS_DP<7>'
 '@S9S_MB_2U_LIB.S9S_MB_2U(SCH_1):M_B_CPU0_SB_DQS_DP'<7>:
 C_SIGNAL='@s9s_mb_2u_lib.s9s_mb_2u(sch_1):m_b_cpu0_sb_dqs_dp(7)';
NODE_NAME     U2 P18
 '@S9S_MB_2U_LIB.S9S_MB_2U(SCH_1):PAGE21_I169@PURE_QUANTA.SOCKET4677_AZIF0045P001C01CS(CHIPS)':
 'DDR1_SB_DQS_DP7': CDS_PINID='DDR1_SB_DQS_DP7';
NODE_NAME     J4 272
 '@S9S_MB_2U_LIB.S9S_MB_2U(SCH_1):PAGE85_I178@PURE_QUANTA.SCONN288_ADR50017P087CC(CHIPS)':
 'DQS7_B_T||TDQS7_B_T': CDS_PINID='\dqs7_b_t||tdqs7_b_t\';
NODE_NAME     J3 272
 '@S9S_MB_2U_LIB.S9S_MB_2U(SCH_1):PAGE84_I179@PURE_QUANTA.SCONN288_ADR50017P130CC(CHIPS)':
 'DQS7_B_T||TDQS7_B_T': CDS_PINID='\dqs7_b_t||tdqs7_b_t\';
NET_NAME
'M_B_CPU0_SB_DQS_DP<8>'
 '@S9S_MB_2U_LIB.S9S_MB_2U(SCH_1):M_B_CPU0_SB_DQS_DP'<8>:
 C_SIGNAL='@s9s_mb_2u_lib.s9s_mb_2u(sch_1):m_b_cpu0_sb_dqs_dp(8)';
NODE_NAME     U2 G15
 '@S9S_MB_2U_LIB.S9S_MB_2U(SCH_1):PAGE21_I169@PURE_QUANTA.SOCKET4677_AZIF0045P001C01CS(CHIPS)':
 'DDR1_SB_DQS_DP8': CDS_PINID='DDR1_SB_DQS_DP8';
NODE_NAME     J4 283
 '@S9S_MB_2U_LIB.S9S_MB_2U(SCH_1):PAGE85_I178@PURE_QUANTA.SCONN288_ADR50017P087CC(CHIPS)':
 'DQS8_B_T||TDQS8_B_T': CDS_PINID='\dqs8_b_t||tdqs8_b_t\';
NODE_NAME     J3 283
 '@S9S_MB_2U_LIB.S9S_MB_2U(SCH_1):PAGE84_I179@PURE_QUANTA.SCONN288_ADR50017P130CC(CHIPS)':
 'DQS8_B_T||TDQS8_B_T': CDS_PINID='\dqs8_b_t||tdqs8_b_t\';
NET_NAME
'M_B_CPU0_SB_DQS_DP<9>'
 '@S9S_MB_2U_LIB.S9S_MB_2U(SCH_1):M_B_CPU0_SB_DQS_DP'<9>:
 C_SIGNAL='@s9s_mb_2u_lib.s9s_mb_2u(sch_1):m_b_cpu0_sb_dqs_dp(9)';
NODE_NAME     U2 H36
 '@S9S_MB_2U_LIB.S9S_MB_2U(SCH_1):PAGE21_I169@PURE_QUANTA.SOCKET4677_AZIF0045P001C01CS(CHIPS)':
 'DDR1_SB_DQS_DP9': CDS_PINID='DDR1_SB_DQS_DP9';
NODE_NAME     J4 93
 '@S9S_MB_2U_LIB.S9S_MB_2U(SCH_1):PAGE85_I178@PURE_QUANTA.SCONN288_ADR50017P087CC(CHIPS)':
 'DQS9_B_T||TDQS9_B_T||DBI4_B_N': CDS_PINID='\dqs9_b_t||tdqs9_b_t||dbi4_b_n\';
NODE_NAME     J3 93
 '@S9S_MB_2U_LIB.S9S_MB_2U(SCH_1):PAGE84_I179@PURE_QUANTA.SCONN288_ADR50017P130CC(CHIPS)':
 'DQS9_B_T||TDQS9_B_T||DBI4_B_N': CDS_PINID='\dqs9_b_t||tdqs9_b_t||dbi4_b_n\';
NET_NAME
'M_B_CPU0_SB_PAR'
 '@S9S_MB_2U_LIB.S9S_MB_2U(SCH_1):M_B_CPU0_SB_PAR':
 C_SIGNAL='@s9s_mb_2u_lib.s9s_mb_2u(sch_1):m_b_cpu0_sb_par';
NODE_NAME     U2 P42
 '@S9S_MB_2U_LIB.S9S_MB_2U(SCH_1):PAGE21_I169@PURE_QUANTA.SOCKET4677_AZIF0045P001C01CS(CHIPS)':
 'DDR1_SB_PAR': CDS_PINID='DDR1_SB_PAR';
NODE_NAME     J4 227
 '@S9S_MB_2U_LIB.S9S_MB_2U(SCH_1):PAGE85_I23@PURE_QUANTA.SCONN288_ADR50017P087CC(CHIPS)':
 'PAR_B': CDS_PINID='PAR_B';
NODE_NAME     J3 227
 '@S9S_MB_2U_LIB.S9S_MB_2U(SCH_1):PAGE84_I180@PURE_QUANTA.SCONN288_ADR50017P130CC(CHIPS)':
 'PAR_B': CDS_PINID='PAR_B';
NET_NAME
'M_B_CPU0_SB_RSP<0>'
 '@S9S_MB_2U_LIB.S9S_MB_2U(SCH_1):M_B_CPU0_SB_RSP'<0>:
 C_SIGNAL='@s9s_mb_2u_lib.s9s_mb_2u(sch_1):m_b_cpu0_sb_rsp(0)';
NODE_NAME     U2 AN48
 '@S9S_MB_2U_LIB.S9S_MB_2U(SCH_1):PAGE21_I169@PURE_QUANTA.SOCKET4677_AZIF0045P001C01CS(CHIPS)':
 'DDR1_B_RSP0': CDS_PINID='DDR1_B_RSP0';
NODE_NAME     J3 87
 '@S9S_MB_2U_LIB.S9S_MB_2U(SCH_1):PAGE84_I180@PURE_QUANTA.SCONN288_ADR50017P130CC(CHIPS)':
 'LBS||RSP_B_N': CDS_PINID='\lbs||rsp_b_n\';
NET_NAME
'M_B_CPU0_SB_RSP<1>'
 '@S9S_MB_2U_LIB.S9S_MB_2U(SCH_1):M_B_CPU0_SB_RSP'<1>:
 C_SIGNAL='@s9s_mb_2u_lib.s9s_mb_2u(sch_1):m_b_cpu0_sb_rsp(1)';
NODE_NAME     U2 AP47
 '@S9S_MB_2U_LIB.S9S_MB_2U(SCH_1):PAGE21_I169@PURE_QUANTA.SOCKET4677_AZIF0045P001C01CS(CHIPS)':
 'DDR1_B_RSP1': CDS_PINID='DDR1_B_RSP1';
NODE_NAME     J4 87
 '@S9S_MB_2U_LIB.S9S_MB_2U(SCH_1):PAGE85_I23@PURE_QUANTA.SCONN288_ADR50017P087CC(CHIPS)':
 'LBS||RSP_B_N': CDS_PINID='\lbs||rsp_b_n\';
NET_NAME
'M_B_CPU1_ALERT_N'
 '@S9S_MB_2U_LIB.S9S_MB_2U(SCH_1):M_B_CPU1_ALERT_N':
 C_SIGNAL='@s9s_mb_2u_lib.s9s_mb_2u(sch_1):m_b_cpu1_alert_n';
NODE_NAME     U1 AV49
 '@S9S_MB_2U_LIB.S9S_MB_2U(SCH_1):PAGE52_I91@PURE_QUANTA.SOCKET4677_AZIF0045P001C01CS(CHIPS)':
 'DDR1_ALERT_N': CDS_PINID='DDR1_ALERT_N';
NODE_NAME     J19 62
 '@S9S_MB_2U_LIB.S9S_MB_2U(SCH_1):PAGE100_I25@PURE_QUANTA.SCONN288_ADR50017P130CC(CHIPS)':
 'ALERT_N': CDS_PINID='ALERT_N';
NODE_NAME     J20 62
 '@S9S_MB_2U_LIB.S9S_MB_2U(SCH_1):PAGE101_I47@PURE_QUANTA.SCONN288_ADR50017P087CC(CHIPS)':
 'ALERT_N': CDS_PINID='ALERT_N';
NET_NAME
'M_B_CPU1_CLK_DN<0>'
 '@S9S_MB_2U_LIB.S9S_MB_2U(SCH_1):M_B_CPU1_CLK_DN'<0>:
 C_SIGNAL='@s9s_mb_2u_lib.s9s_mb_2u(sch_1):m_b_cpu1_clk_dn(0)';
NODE_NAME     U1 R45
 '@S9S_MB_2U_LIB.S9S_MB_2U(SCH_1):PAGE52_I91@PURE_QUANTA.SOCKET4677_AZIF0045P001C01CS(CHIPS)':
 'DDR1_CLK_DN0': CDS_PINID='DDR1_CLK_DN0';
NODE_NAME     J19 218
 '@S9S_MB_2U_LIB.S9S_MB_2U(SCH_1):PAGE100_I25@PURE_QUANTA.SCONN288_ADR50017P130CC(CHIPS)':
 'CK_C': CDS_PINID='CK_C';
NET_NAME
'M_B_CPU1_CLK_DN<1>'
 '@S9S_MB_2U_LIB.S9S_MB_2U(SCH_1):M_B_CPU1_CLK_DN'<1>:
 C_SIGNAL='@s9s_mb_2u_lib.s9s_mb_2u(sch_1):m_b_cpu1_clk_dn(1)';
NODE_NAME     U1 W45
 '@S9S_MB_2U_LIB.S9S_MB_2U(SCH_1):PAGE52_I91@PURE_QUANTA.SOCKET4677_AZIF0045P001C01CS(CHIPS)':
 'DDR1_CLK_DN1': CDS_PINID='DDR1_CLK_DN1';
NODE_NAME     J20 218
 '@S9S_MB_2U_LIB.S9S_MB_2U(SCH_1):PAGE101_I47@PURE_QUANTA.SCONN288_ADR50017P087CC(CHIPS)':
 'CK_C': CDS_PINID='CK_C';
NET_NAME
'M_B_CPU1_CLK_DP<0>'
 '@S9S_MB_2U_LIB.S9S_MB_2U(SCH_1):M_B_CPU1_CLK_DP'<0>:
 C_SIGNAL='@s9s_mb_2u_lib.s9s_mb_2u(sch_1):m_b_cpu1_clk_dp(0)';
NODE_NAME     U1 U45
 '@S9S_MB_2U_LIB.S9S_MB_2U(SCH_1):PAGE52_I91@PURE_QUANTA.SOCKET4677_AZIF0045P001C01CS(CHIPS)':
 'DDR1_CLK_DP0': CDS_PINID='DDR1_CLK_DP0';
NODE_NAME     J19 217
 '@S9S_MB_2U_LIB.S9S_MB_2U(SCH_1):PAGE100_I25@PURE_QUANTA.SCONN288_ADR50017P130CC(CHIPS)':
 'CK_T': CDS_PINID='CK_T';
NET_NAME
'M_B_CPU1_CLK_DP<1>'
 '@S9S_MB_2U_LIB.S9S_MB_2U(SCH_1):M_B_CPU1_CLK_DP'<1>:
 C_SIGNAL='@s9s_mb_2u_lib.s9s_mb_2u(sch_1):m_b_cpu1_clk_dp(1)';
NODE_NAME     U1 AA45
 '@S9S_MB_2U_LIB.S9S_MB_2U(SCH_1):PAGE52_I91@PURE_QUANTA.SOCKET4677_AZIF0045P001C01CS(CHIPS)':
 'DDR1_CLK_DP1': CDS_PINID='DDR1_CLK_DP1';
NODE_NAME     J20 217
 '@S9S_MB_2U_LIB.S9S_MB_2U(SCH_1):PAGE101_I47@PURE_QUANTA.SCONN288_ADR50017P087CC(CHIPS)':
 'CK_T': CDS_PINID='CK_T';
NET_NAME
'M_B_CPU1_SA_CA<0>'
 '@S9S_MB_2U_LIB.S9S_MB_2U(SCH_1):M_B_CPU1_SA_CA'<0>:
 C_SIGNAL='@s9s_mb_2u_lib.s9s_mb_2u(sch_1):m_b_cpu1_sa_ca(0)';
NODE_NAME     U1 H49
 '@S9S_MB_2U_LIB.S9S_MB_2U(SCH_1):PAGE52_I91@PURE_QUANTA.SOCKET4677_AZIF0045P001C01CS(CHIPS)':
 'DDR1_SA_CA0': CDS_PINID='DDR1_SA_CA0';
NODE_NAME     J19 66
 '@S9S_MB_2U_LIB.S9S_MB_2U(SCH_1):PAGE100_I25@PURE_QUANTA.SCONN288_ADR50017P130CC(CHIPS)':
 'CA0_A': CDS_PINID='CA0_A';
NODE_NAME     J20 66
 '@S9S_MB_2U_LIB.S9S_MB_2U(SCH_1):PAGE101_I47@PURE_QUANTA.SCONN288_ADR50017P087CC(CHIPS)':
 'CA0_A': CDS_PINID='CA0_A';
NET_NAME
'M_B_CPU1_SA_CA<1>'
 '@S9S_MB_2U_LIB.S9S_MB_2U(SCH_1):M_B_CPU1_SA_CA'<1>:
 C_SIGNAL='@s9s_mb_2u_lib.s9s_mb_2u(sch_1):m_b_cpu1_sa_ca(1)';
NODE_NAME     U1 P49
 '@S9S_MB_2U_LIB.S9S_MB_2U(SCH_1):PAGE52_I91@PURE_QUANTA.SOCKET4677_AZIF0045P001C01CS(CHIPS)':
 'DDR1_SA_CA1': CDS_PINID='DDR1_SA_CA1';
NODE_NAME     J19 211
 '@S9S_MB_2U_LIB.S9S_MB_2U(SCH_1):PAGE100_I25@PURE_QUANTA.SCONN288_ADR50017P130CC(CHIPS)':
 'CA1_A': CDS_PINID='CA1_A';
NODE_NAME     J20 211
 '@S9S_MB_2U_LIB.S9S_MB_2U(SCH_1):PAGE101_I47@PURE_QUANTA.SCONN288_ADR50017P087CC(CHIPS)':
 'CA1_A': CDS_PINID='CA1_A';
NET_NAME
'M_B_CPU1_SA_CA<2>'
 '@S9S_MB_2U_LIB.S9S_MB_2U(SCH_1):M_B_CPU1_SA_CA'<2>:
 C_SIGNAL='@s9s_mb_2u_lib.s9s_mb_2u(sch_1):m_b_cpu1_sa_ca(2)';
NODE_NAME     U1 J48
 '@S9S_MB_2U_LIB.S9S_MB_2U(SCH_1):PAGE52_I91@PURE_QUANTA.SOCKET4677_AZIF0045P001C01CS(CHIPS)':
 'DDR1_SA_CA2': CDS_PINID='DDR1_SA_CA2';
NODE_NAME     J19 68
 '@S9S_MB_2U_LIB.S9S_MB_2U(SCH_1):PAGE100_I25@PURE_QUANTA.SCONN288_ADR50017P130CC(CHIPS)':
 'CA2_A': CDS_PINID='CA2_A';
NODE_NAME     J20 68
 '@S9S_MB_2U_LIB.S9S_MB_2U(SCH_1):PAGE101_I47@PURE_QUANTA.SCONN288_ADR50017P087CC(CHIPS)':
 'CA2_A': CDS_PINID='CA2_A';
NET_NAME
'M_B_CPU1_SA_CA<3>'
 '@S9S_MB_2U_LIB.S9S_MB_2U(SCH_1):M_B_CPU1_SA_CA'<3>:
 C_SIGNAL='@s9s_mb_2u_lib.s9s_mb_2u(sch_1):m_b_cpu1_sa_ca(3)';
NODE_NAME     U1 N48
 '@S9S_MB_2U_LIB.S9S_MB_2U(SCH_1):PAGE52_I91@PURE_QUANTA.SOCKET4677_AZIF0045P001C01CS(CHIPS)':
 'DDR1_SA_CA3': CDS_PINID='DDR1_SA_CA3';
NODE_NAME     J19 213
 '@S9S_MB_2U_LIB.S9S_MB_2U(SCH_1):PAGE100_I25@PURE_QUANTA.SCONN288_ADR50017P130CC(CHIPS)':
 'CA3_A': CDS_PINID='CA3_A';
NODE_NAME     J20 213
 '@S9S_MB_2U_LIB.S9S_MB_2U(SCH_1):PAGE101_I47@PURE_QUANTA.SCONN288_ADR50017P087CC(CHIPS)':
 'CA3_A': CDS_PINID='CA3_A';
NET_NAME
'M_B_CPU1_SA_CA<4>'
 '@S9S_MB_2U_LIB.S9S_MB_2U(SCH_1):M_B_CPU1_SA_CA'<4>:
 C_SIGNAL='@s9s_mb_2u_lib.s9s_mb_2u(sch_1):m_b_cpu1_sa_ca(4)';
NODE_NAME     U1 K47
 '@S9S_MB_2U_LIB.S9S_MB_2U(SCH_1):PAGE52_I91@PURE_QUANTA.SOCKET4677_AZIF0045P001C01CS(CHIPS)':
 'DDR1_SA_CA4': CDS_PINID='DDR1_SA_CA4';
NODE_NAME     J19 70
 '@S9S_MB_2U_LIB.S9S_MB_2U(SCH_1):PAGE100_I25@PURE_QUANTA.SCONN288_ADR50017P130CC(CHIPS)':
 'CA4_A': CDS_PINID='CA4_A';
NODE_NAME     J20 70
 '@S9S_MB_2U_LIB.S9S_MB_2U(SCH_1):PAGE101_I47@PURE_QUANTA.SCONN288_ADR50017P087CC(CHIPS)':
 'CA4_A': CDS_PINID='CA4_A';
NET_NAME
'M_B_CPU1_SA_CA<5>'
 '@S9S_MB_2U_LIB.S9S_MB_2U(SCH_1):M_B_CPU1_SA_CA'<5>:
 C_SIGNAL='@s9s_mb_2u_lib.s9s_mb_2u(sch_1):m_b_cpu1_sa_ca(5)';
NODE_NAME     U1 M47
 '@S9S_MB_2U_LIB.S9S_MB_2U(SCH_1):PAGE52_I91@PURE_QUANTA.SOCKET4677_AZIF0045P001C01CS(CHIPS)':
 'DDR1_SA_CA5': CDS_PINID='DDR1_SA_CA5';
NODE_NAME     J19 215
 '@S9S_MB_2U_LIB.S9S_MB_2U(SCH_1):PAGE100_I25@PURE_QUANTA.SCONN288_ADR50017P130CC(CHIPS)':
 'CA5_A': CDS_PINID='CA5_A';
NODE_NAME     J20 215
 '@S9S_MB_2U_LIB.S9S_MB_2U(SCH_1):PAGE101_I47@PURE_QUANTA.SCONN288_ADR50017P087CC(CHIPS)':
 'CA5_A': CDS_PINID='CA5_A';
NET_NAME
'M_B_CPU1_SA_CA<6>'
 '@S9S_MB_2U_LIB.S9S_MB_2U(SCH_1):M_B_CPU1_SA_CA'<6>:
 C_SIGNAL='@s9s_mb_2u_lib.s9s_mb_2u(sch_1):m_b_cpu1_sa_ca(6)';
NODE_NAME     U1 Y44
 '@S9S_MB_2U_LIB.S9S_MB_2U(SCH_1):PAGE52_I91@PURE_QUANTA.SOCKET4677_AZIF0045P001C01CS(CHIPS)':
 'DDR1_SA_CA6': CDS_PINID='DDR1_SA_CA6';
NODE_NAME     J19 72
 '@S9S_MB_2U_LIB.S9S_MB_2U(SCH_1):PAGE100_I25@PURE_QUANTA.SCONN288_ADR50017P130CC(CHIPS)':
 'CA6_A': CDS_PINID='CA6_A';
NODE_NAME     J20 72
 '@S9S_MB_2U_LIB.S9S_MB_2U(SCH_1):PAGE101_I47@PURE_QUANTA.SCONN288_ADR50017P087CC(CHIPS)':
 'CA6_A': CDS_PINID='CA6_A';
NET_NAME
'M_B_CPU1_SA_CB<0>'
 '@S9S_MB_2U_LIB.S9S_MB_2U(SCH_1):M_B_CPU1_SA_CB'<0>:
 C_SIGNAL='@s9s_mb_2u_lib.s9s_mb_2u(sch_1):m_b_cpu1_sa_cb(0)';
NODE_NAME     U1 K57
 '@S9S_MB_2U_LIB.S9S_MB_2U(SCH_1):PAGE52_I91@PURE_QUANTA.SOCKET4677_AZIF0045P001C01CS(CHIPS)':
 'DDR1_SA_ECC0': CDS_PINID='DDR1_SA_ECC0';
NODE_NAME     J19 51
 '@S9S_MB_2U_LIB.S9S_MB_2U(SCH_1):PAGE100_I25@PURE_QUANTA.SCONN288_ADR50017P130CC(CHIPS)':
 'CB0_A': CDS_PINID='CB0_A';
NODE_NAME     J20 51
 '@S9S_MB_2U_LIB.S9S_MB_2U(SCH_1):PAGE101_I47@PURE_QUANTA.SCONN288_ADR50017P087CC(CHIPS)':
 'CB0_A': CDS_PINID='CB0_A';
NET_NAME
'M_B_CPU1_SA_CB<1>'
 '@S9S_MB_2U_LIB.S9S_MB_2U(SCH_1):M_B_CPU1_SA_CB'<1>:
 C_SIGNAL='@s9s_mb_2u_lib.s9s_mb_2u(sch_1):m_b_cpu1_sa_cb(1)';
NODE_NAME     U1 J56
 '@S9S_MB_2U_LIB.S9S_MB_2U(SCH_1):PAGE52_I91@PURE_QUANTA.SOCKET4677_AZIF0045P001C01CS(CHIPS)':
 'DDR1_SA_ECC1': CDS_PINID='DDR1_SA_ECC1';
NODE_NAME     J19 53
 '@S9S_MB_2U_LIB.S9S_MB_2U(SCH_1):PAGE100_I25@PURE_QUANTA.SCONN288_ADR50017P130CC(CHIPS)':
 'CB1_A': CDS_PINID='CB1_A';
NODE_NAME     J20 53
 '@S9S_MB_2U_LIB.S9S_MB_2U(SCH_1):PAGE101_I47@PURE_QUANTA.SCONN288_ADR50017P087CC(CHIPS)':
 'CB1_A': CDS_PINID='CB1_A';
NET_NAME
'M_B_CPU1_SA_CB<2>'
 '@S9S_MB_2U_LIB.S9S_MB_2U(SCH_1):M_B_CPU1_SA_CB'<2>:
 C_SIGNAL='@s9s_mb_2u_lib.s9s_mb_2u(sch_1):m_b_cpu1_sa_cb(2)';
NODE_NAME     U1 M57
 '@S9S_MB_2U_LIB.S9S_MB_2U(SCH_1):PAGE52_I91@PURE_QUANTA.SOCKET4677_AZIF0045P001C01CS(CHIPS)':
 'DDR1_SA_ECC2': CDS_PINID='DDR1_SA_ECC2';
NODE_NAME     J19 196
 '@S9S_MB_2U_LIB.S9S_MB_2U(SCH_1):PAGE100_I25@PURE_QUANTA.SCONN288_ADR50017P130CC(CHIPS)':
 'CB2_A': CDS_PINID='CB2_A';
NODE_NAME     J20 196
 '@S9S_MB_2U_LIB.S9S_MB_2U(SCH_1):PAGE101_I47@PURE_QUANTA.SCONN288_ADR50017P087CC(CHIPS)':
 'CB2_A': CDS_PINID='CB2_A';
NET_NAME
'M_B_CPU1_SA_CB<3>'
 '@S9S_MB_2U_LIB.S9S_MB_2U(SCH_1):M_B_CPU1_SA_CB'<3>:
 C_SIGNAL='@s9s_mb_2u_lib.s9s_mb_2u(sch_1):m_b_cpu1_sa_cb(3)';
NODE_NAME     U1 N56
 '@S9S_MB_2U_LIB.S9S_MB_2U(SCH_1):PAGE52_I91@PURE_QUANTA.SOCKET4677_AZIF0045P001C01CS(CHIPS)':
 'DDR1_SA_ECC3': CDS_PINID='DDR1_SA_ECC3';
NODE_NAME     J19 198
 '@S9S_MB_2U_LIB.S9S_MB_2U(SCH_1):PAGE100_I25@PURE_QUANTA.SCONN288_ADR50017P130CC(CHIPS)':
 'CB3_A': CDS_PINID='CB3_A';
NODE_NAME     J20 198
 '@S9S_MB_2U_LIB.S9S_MB_2U(SCH_1):PAGE101_I47@PURE_QUANTA.SCONN288_ADR50017P087CC(CHIPS)':
 'CB3_A': CDS_PINID='CB3_A';
NET_NAME
'M_B_CPU1_SA_CB<4>'
 '@S9S_MB_2U_LIB.S9S_MB_2U(SCH_1):M_B_CPU1_SA_CB'<4>:
 C_SIGNAL='@s9s_mb_2u_lib.s9s_mb_2u(sch_1):m_b_cpu1_sa_cb(4)';
NODE_NAME     U1 J54
 '@S9S_MB_2U_LIB.S9S_MB_2U(SCH_1):PAGE52_I91@PURE_QUANTA.SOCKET4677_AZIF0045P001C01CS(CHIPS)':
 'DDR1_SA_ECC4': CDS_PINID='DDR1_SA_ECC4';
NODE_NAME     J19 58
 '@S9S_MB_2U_LIB.S9S_MB_2U(SCH_1):PAGE100_I25@PURE_QUANTA.SCONN288_ADR50017P130CC(CHIPS)':
 'CB4_A': CDS_PINID='CB4_A';
NODE_NAME     J20 58
 '@S9S_MB_2U_LIB.S9S_MB_2U(SCH_1):PAGE101_I47@PURE_QUANTA.SCONN288_ADR50017P087CC(CHIPS)':
 'CB4_A': CDS_PINID='CB4_A';
NET_NAME
'M_B_CPU1_SA_CB<5>'
 '@S9S_MB_2U_LIB.S9S_MB_2U(SCH_1):M_B_CPU1_SA_CB'<5>:
 C_SIGNAL='@s9s_mb_2u_lib.s9s_mb_2u(sch_1):m_b_cpu1_sa_cb(5)';
NODE_NAME     U1 K53
 '@S9S_MB_2U_LIB.S9S_MB_2U(SCH_1):PAGE52_I91@PURE_QUANTA.SOCKET4677_AZIF0045P001C01CS(CHIPS)':
 'DDR1_SA_ECC5': CDS_PINID='DDR1_SA_ECC5';
NODE_NAME     J19 60
 '@S9S_MB_2U_LIB.S9S_MB_2U(SCH_1):PAGE100_I25@PURE_QUANTA.SCONN288_ADR50017P130CC(CHIPS)':
 'CB5_A': CDS_PINID='CB5_A';
NODE_NAME     J20 60
 '@S9S_MB_2U_LIB.S9S_MB_2U(SCH_1):PAGE101_I47@PURE_QUANTA.SCONN288_ADR50017P087CC(CHIPS)':
 'CB5_A': CDS_PINID='CB5_A';
NET_NAME
'M_B_CPU1_SA_CB<6>'
 '@S9S_MB_2U_LIB.S9S_MB_2U(SCH_1):M_B_CPU1_SA_CB'<6>:
 C_SIGNAL='@s9s_mb_2u_lib.s9s_mb_2u(sch_1):m_b_cpu1_sa_cb(6)';
NODE_NAME     U1 N54
 '@S9S_MB_2U_LIB.S9S_MB_2U(SCH_1):PAGE52_I91@PURE_QUANTA.SOCKET4677_AZIF0045P001C01CS(CHIPS)':
 'DDR1_SA_ECC6': CDS_PINID='DDR1_SA_ECC6';
NODE_NAME     J19 203
 '@S9S_MB_2U_LIB.S9S_MB_2U(SCH_1):PAGE100_I25@PURE_QUANTA.SCONN288_ADR50017P130CC(CHIPS)':
 'CB6_A': CDS_PINID='CB6_A';
NODE_NAME     J20 203
 '@S9S_MB_2U_LIB.S9S_MB_2U(SCH_1):PAGE101_I47@PURE_QUANTA.SCONN288_ADR50017P087CC(CHIPS)':
 'CB6_A': CDS_PINID='CB6_A';
NET_NAME
'M_B_CPU1_SA_CB<7>'
 '@S9S_MB_2U_LIB.S9S_MB_2U(SCH_1):M_B_CPU1_SA_CB'<7>:
 C_SIGNAL='@s9s_mb_2u_lib.s9s_mb_2u(sch_1):m_b_cpu1_sa_cb(7)';
NODE_NAME     U1 M53
 '@S9S_MB_2U_LIB.S9S_MB_2U(SCH_1):PAGE52_I91@PURE_QUANTA.SOCKET4677_AZIF0045P001C01CS(CHIPS)':
 'DDR1_SA_ECC7': CDS_PINID='DDR1_SA_ECC7';
NODE_NAME     J19 205
 '@S9S_MB_2U_LIB.S9S_MB_2U(SCH_1):PAGE100_I25@PURE_QUANTA.SCONN288_ADR50017P130CC(CHIPS)':
 'CB7_A': CDS_PINID='CB7_A';
NODE_NAME     J20 205
 '@S9S_MB_2U_LIB.S9S_MB_2U(SCH_1):PAGE101_I47@PURE_QUANTA.SCONN288_ADR50017P087CC(CHIPS)':
 'CB7_A': CDS_PINID='CB7_A';
NET_NAME
'M_B_CPU1_SA_CS_N<0>'
 '@S9S_MB_2U_LIB.S9S_MB_2U(SCH_1):M_B_CPU1_SA_CS_N'<0>:
 C_SIGNAL='@s9s_mb_2u_lib.s9s_mb_2u(sch_1):m_b_cpu1_sa_cs_n(0)';
NODE_NAME     U1 K51
 '@S9S_MB_2U_LIB.S9S_MB_2U(SCH_1):PAGE52_I91@PURE_QUANTA.SOCKET4677_AZIF0045P001C01CS(CHIPS)':
 'DDR1_SA_CS_N0': CDS_PINID='DDR1_SA_CS_N0';
NODE_NAME     J19 64
 '@S9S_MB_2U_LIB.S9S_MB_2U(SCH_1):PAGE100_I25@PURE_QUANTA.SCONN288_ADR50017P130CC(CHIPS)':
 'CS0_A_N': CDS_PINID='CS0_A_N';
NET_NAME
'M_B_CPU1_SA_CS_N<1>'
 '@S9S_MB_2U_LIB.S9S_MB_2U(SCH_1):M_B_CPU1_SA_CS_N'<1>:
 C_SIGNAL='@s9s_mb_2u_lib.s9s_mb_2u(sch_1):m_b_cpu1_sa_cs_n(1)';
NODE_NAME     U1 J50
 '@S9S_MB_2U_LIB.S9S_MB_2U(SCH_1):PAGE52_I91@PURE_QUANTA.SOCKET4677_AZIF0045P001C01CS(CHIPS)':
 'DDR1_SA_CS_N1': CDS_PINID='DDR1_SA_CS_N1';
NODE_NAME     J19 209
 '@S9S_MB_2U_LIB.S9S_MB_2U(SCH_1):PAGE100_I25@PURE_QUANTA.SCONN288_ADR50017P130CC(CHIPS)':
 'CS1_A_N': CDS_PINID='CS1_A_N';
NET_NAME
'M_B_CPU1_SA_CS_N<2>'
 '@S9S_MB_2U_LIB.S9S_MB_2U(SCH_1):M_B_CPU1_SA_CS_N'<2>:
 C_SIGNAL='@s9s_mb_2u_lib.s9s_mb_2u(sch_1):m_b_cpu1_sa_cs_n(2)';
NODE_NAME     U1 M51
 '@S9S_MB_2U_LIB.S9S_MB_2U(SCH_1):PAGE52_I91@PURE_QUANTA.SOCKET4677_AZIF0045P001C01CS(CHIPS)':
 'DDR1_SA_CS_N2': CDS_PINID='DDR1_SA_CS_N2';
NODE_NAME     J20 64
 '@S9S_MB_2U_LIB.S9S_MB_2U(SCH_1):PAGE101_I47@PURE_QUANTA.SCONN288_ADR50017P087CC(CHIPS)':
 'CS0_A_N': CDS_PINID='CS0_A_N';
NET_NAME
'M_B_CPU1_SA_CS_N<3>'
 '@S9S_MB_2U_LIB.S9S_MB_2U(SCH_1):M_B_CPU1_SA_CS_N'<3>:
 C_SIGNAL='@s9s_mb_2u_lib.s9s_mb_2u(sch_1):m_b_cpu1_sa_cs_n(3)';
NODE_NAME     U1 N50
 '@S9S_MB_2U_LIB.S9S_MB_2U(SCH_1):PAGE52_I91@PURE_QUANTA.SOCKET4677_AZIF0045P001C01CS(CHIPS)':
 'DDR1_SA_CS_N3': CDS_PINID='DDR1_SA_CS_N3';
NODE_NAME     J20 209
 '@S9S_MB_2U_LIB.S9S_MB_2U(SCH_1):PAGE101_I47@PURE_QUANTA.SCONN288_ADR50017P087CC(CHIPS)':
 'CS1_A_N': CDS_PINID='CS1_A_N';
NET_NAME
'M_B_CPU1_SA_DQ<0>'
 '@S9S_MB_2U_LIB.S9S_MB_2U(SCH_1):M_B_CPU1_SA_DQ'<0>:
 C_SIGNAL='@s9s_mb_2u_lib.s9s_mb_2u(sch_1):m_b_cpu1_sa_dq(0)';
NODE_NAME     U1 K75
 '@S9S_MB_2U_LIB.S9S_MB_2U(SCH_1):PAGE52_I91@PURE_QUANTA.SOCKET4677_AZIF0045P001C01CS(CHIPS)':
 'DDR1_SA_DQ0': CDS_PINID='DDR1_SA_DQ0';
NODE_NAME     J19 7
 '@S9S_MB_2U_LIB.S9S_MB_2U(SCH_1):PAGE100_I25@PURE_QUANTA.SCONN288_ADR50017P130CC(CHIPS)':
 'DQ0_A': CDS_PINID='DQ0_A';
NODE_NAME     J20 7
 '@S9S_MB_2U_LIB.S9S_MB_2U(SCH_1):PAGE101_I47@PURE_QUANTA.SCONN288_ADR50017P087CC(CHIPS)':
 'DQ0_A': CDS_PINID='DQ0_A';
NET_NAME
'M_B_CPU1_SA_DQ<10>'
 '@S9S_MB_2U_LIB.S9S_MB_2U(SCH_1):M_B_CPU1_SA_DQ'<10>:
 C_SIGNAL='@s9s_mb_2u_lib.s9s_mb_2u(sch_1):m_b_cpu1_sa_dq(10)';
NODE_NAME     U1 W72
 '@S9S_MB_2U_LIB.S9S_MB_2U(SCH_1):PAGE52_I91@PURE_QUANTA.SOCKET4677_AZIF0045P001C01CS(CHIPS)':
 'DDR1_SA_DQ10': CDS_PINID='DDR1_SA_DQ10';
NODE_NAME     J19 163
 '@S9S_MB_2U_LIB.S9S_MB_2U(SCH_1):PAGE100_I25@PURE_QUANTA.SCONN288_ADR50017P130CC(CHIPS)':
 'DQ10_A': CDS_PINID='DQ10_A';
NODE_NAME     J20 163
 '@S9S_MB_2U_LIB.S9S_MB_2U(SCH_1):PAGE101_I47@PURE_QUANTA.SCONN288_ADR50017P087CC(CHIPS)':
 'DQ10_A': CDS_PINID='DQ10_A';
NET_NAME
'M_B_CPU1_SA_DQ<11>'
 '@S9S_MB_2U_LIB.S9S_MB_2U(SCH_1):M_B_CPU1_SA_DQ'<11>:
 C_SIGNAL='@s9s_mb_2u_lib.s9s_mb_2u(sch_1):m_b_cpu1_sa_dq(11)';
NODE_NAME     U1 Y71
 '@S9S_MB_2U_LIB.S9S_MB_2U(SCH_1):PAGE52_I91@PURE_QUANTA.SOCKET4677_AZIF0045P001C01CS(CHIPS)':
 'DDR1_SA_DQ11': CDS_PINID='DDR1_SA_DQ11';
NODE_NAME     J19 165
 '@S9S_MB_2U_LIB.S9S_MB_2U(SCH_1):PAGE100_I25@PURE_QUANTA.SCONN288_ADR50017P130CC(CHIPS)':
 'DQ11_A': CDS_PINID='DQ11_A';
NODE_NAME     J20 165
 '@S9S_MB_2U_LIB.S9S_MB_2U(SCH_1):PAGE101_I47@PURE_QUANTA.SCONN288_ADR50017P087CC(CHIPS)':
 'DQ11_A': CDS_PINID='DQ11_A';
NET_NAME
'M_B_CPU1_SA_DQ<12>'
 '@S9S_MB_2U_LIB.S9S_MB_2U(SCH_1):M_B_CPU1_SA_DQ'<12>:
 C_SIGNAL='@s9s_mb_2u_lib.s9s_mb_2u(sch_1):m_b_cpu1_sa_dq(12)';
NODE_NAME     U1 T69
 '@S9S_MB_2U_LIB.S9S_MB_2U(SCH_1):PAGE52_I91@PURE_QUANTA.SOCKET4677_AZIF0045P001C01CS(CHIPS)':
 'DDR1_SA_DQ12': CDS_PINID='DDR1_SA_DQ12';
NODE_NAME     J19 25
 '@S9S_MB_2U_LIB.S9S_MB_2U(SCH_1):PAGE100_I25@PURE_QUANTA.SCONN288_ADR50017P130CC(CHIPS)':
 'DQ12_A': CDS_PINID='DQ12_A';
NODE_NAME     J20 25
 '@S9S_MB_2U_LIB.S9S_MB_2U(SCH_1):PAGE101_I47@PURE_QUANTA.SCONN288_ADR50017P087CC(CHIPS)':
 'DQ12_A': CDS_PINID='DQ12_A';
NET_NAME
'M_B_CPU1_SA_DQ<13>'
 '@S9S_MB_2U_LIB.S9S_MB_2U(SCH_1):M_B_CPU1_SA_DQ'<13>:
 C_SIGNAL='@s9s_mb_2u_lib.s9s_mb_2u(sch_1):m_b_cpu1_sa_dq(13)';
NODE_NAME     U1 U68
 '@S9S_MB_2U_LIB.S9S_MB_2U(SCH_1):PAGE52_I91@PURE_QUANTA.SOCKET4677_AZIF0045P001C01CS(CHIPS)':
 'DDR1_SA_DQ13': CDS_PINID='DDR1_SA_DQ13';
NODE_NAME     J19 27
 '@S9S_MB_2U_LIB.S9S_MB_2U(SCH_1):PAGE100_I25@PURE_QUANTA.SCONN288_ADR50017P130CC(CHIPS)':
 'DQ13_A': CDS_PINID='DQ13_A';
NODE_NAME     J20 27
 '@S9S_MB_2U_LIB.S9S_MB_2U(SCH_1):PAGE101_I47@PURE_QUANTA.SCONN288_ADR50017P087CC(CHIPS)':
 'DQ13_A': CDS_PINID='DQ13_A';
NET_NAME
'M_B_CPU1_SA_DQ<14>'
 '@S9S_MB_2U_LIB.S9S_MB_2U(SCH_1):M_B_CPU1_SA_DQ'<14>:
 C_SIGNAL='@s9s_mb_2u_lib.s9s_mb_2u(sch_1):m_b_cpu1_sa_dq(14)';
NODE_NAME     U1 Y69
 '@S9S_MB_2U_LIB.S9S_MB_2U(SCH_1):PAGE52_I91@PURE_QUANTA.SOCKET4677_AZIF0045P001C01CS(CHIPS)':
 'DDR1_SA_DQ14': CDS_PINID='DDR1_SA_DQ14';
NODE_NAME     J19 170
 '@S9S_MB_2U_LIB.S9S_MB_2U(SCH_1):PAGE100_I25@PURE_QUANTA.SCONN288_ADR50017P130CC(CHIPS)':
 'DQ14_A': CDS_PINID='DQ14_A';
NODE_NAME     J20 170
 '@S9S_MB_2U_LIB.S9S_MB_2U(SCH_1):PAGE101_I47@PURE_QUANTA.SCONN288_ADR50017P087CC(CHIPS)':
 'DQ14_A': CDS_PINID='DQ14_A';
NET_NAME
'M_B_CPU1_SA_DQ<15>'
 '@S9S_MB_2U_LIB.S9S_MB_2U(SCH_1):M_B_CPU1_SA_DQ'<15>:
 C_SIGNAL='@s9s_mb_2u_lib.s9s_mb_2u(sch_1):m_b_cpu1_sa_dq(15)';
NODE_NAME     U1 W68
 '@S9S_MB_2U_LIB.S9S_MB_2U(SCH_1):PAGE52_I91@PURE_QUANTA.SOCKET4677_AZIF0045P001C01CS(CHIPS)':
 'DDR1_SA_DQ15': CDS_PINID='DDR1_SA_DQ15';
NODE_NAME     J19 172
 '@S9S_MB_2U_LIB.S9S_MB_2U(SCH_1):PAGE100_I25@PURE_QUANTA.SCONN288_ADR50017P130CC(CHIPS)':
 'DQ15_A': CDS_PINID='DQ15_A';
NODE_NAME     J20 172
 '@S9S_MB_2U_LIB.S9S_MB_2U(SCH_1):PAGE101_I47@PURE_QUANTA.SCONN288_ADR50017P087CC(CHIPS)':
 'DQ15_A': CDS_PINID='DQ15_A';
NET_NAME
'M_B_CPU1_SA_DQ<16>'
 '@S9S_MB_2U_LIB.S9S_MB_2U(SCH_1):M_B_CPU1_SA_DQ'<16>:
 C_SIGNAL='@s9s_mb_2u_lib.s9s_mb_2u(sch_1):m_b_cpu1_sa_dq(16)';
NODE_NAME     U1 K63
 '@S9S_MB_2U_LIB.S9S_MB_2U(SCH_1):PAGE52_I91@PURE_QUANTA.SOCKET4677_AZIF0045P001C01CS(CHIPS)':
 'DDR1_SA_DQ16': CDS_PINID='DDR1_SA_DQ16';
NODE_NAME     J19 29
 '@S9S_MB_2U_LIB.S9S_MB_2U(SCH_1):PAGE100_I25@PURE_QUANTA.SCONN288_ADR50017P130CC(CHIPS)':
 'DQ16_A': CDS_PINID='DQ16_A';
NODE_NAME     J20 29
 '@S9S_MB_2U_LIB.S9S_MB_2U(SCH_1):PAGE101_I47@PURE_QUANTA.SCONN288_ADR50017P087CC(CHIPS)':
 'DQ16_A': CDS_PINID='DQ16_A';
NET_NAME
'M_B_CPU1_SA_DQ<17>'
 '@S9S_MB_2U_LIB.S9S_MB_2U(SCH_1):M_B_CPU1_SA_DQ'<17>:
 C_SIGNAL='@s9s_mb_2u_lib.s9s_mb_2u(sch_1):m_b_cpu1_sa_dq(17)';
NODE_NAME     U1 J62
 '@S9S_MB_2U_LIB.S9S_MB_2U(SCH_1):PAGE52_I91@PURE_QUANTA.SOCKET4677_AZIF0045P001C01CS(CHIPS)':
 'DDR1_SA_DQ17': CDS_PINID='DDR1_SA_DQ17';
NODE_NAME     J19 31
 '@S9S_MB_2U_LIB.S9S_MB_2U(SCH_1):PAGE100_I25@PURE_QUANTA.SCONN288_ADR50017P130CC(CHIPS)':
 'DQ17_A': CDS_PINID='DQ17_A';
NODE_NAME     J20 31
 '@S9S_MB_2U_LIB.S9S_MB_2U(SCH_1):PAGE101_I47@PURE_QUANTA.SCONN288_ADR50017P087CC(CHIPS)':
 'DQ17_A': CDS_PINID='DQ17_A';
NET_NAME
'M_B_CPU1_SA_DQ<18>'
 '@S9S_MB_2U_LIB.S9S_MB_2U(SCH_1):M_B_CPU1_SA_DQ'<18>:
 C_SIGNAL='@s9s_mb_2u_lib.s9s_mb_2u(sch_1):m_b_cpu1_sa_dq(18)';
NODE_NAME     U1 M63
 '@S9S_MB_2U_LIB.S9S_MB_2U(SCH_1):PAGE52_I91@PURE_QUANTA.SOCKET4677_AZIF0045P001C01CS(CHIPS)':
 'DDR1_SA_DQ18': CDS_PINID='DDR1_SA_DQ18';
NODE_NAME     J19 174
 '@S9S_MB_2U_LIB.S9S_MB_2U(SCH_1):PAGE100_I25@PURE_QUANTA.SCONN288_ADR50017P130CC(CHIPS)':
 'DQ18_A': CDS_PINID='DQ18_A';
NODE_NAME     J20 174
 '@S9S_MB_2U_LIB.S9S_MB_2U(SCH_1):PAGE101_I47@PURE_QUANTA.SCONN288_ADR50017P087CC(CHIPS)':
 'DQ18_A': CDS_PINID='DQ18_A';
NET_NAME
'M_B_CPU1_SA_DQ<19>'
 '@S9S_MB_2U_LIB.S9S_MB_2U(SCH_1):M_B_CPU1_SA_DQ'<19>:
 C_SIGNAL='@s9s_mb_2u_lib.s9s_mb_2u(sch_1):m_b_cpu1_sa_dq(19)';
NODE_NAME     U1 N62
 '@S9S_MB_2U_LIB.S9S_MB_2U(SCH_1):PAGE52_I91@PURE_QUANTA.SOCKET4677_AZIF0045P001C01CS(CHIPS)':
 'DDR1_SA_DQ19': CDS_PINID='DDR1_SA_DQ19';
NODE_NAME     J19 176
 '@S9S_MB_2U_LIB.S9S_MB_2U(SCH_1):PAGE100_I25@PURE_QUANTA.SCONN288_ADR50017P130CC(CHIPS)':
 'DQ19_A': CDS_PINID='DQ19_A';
NODE_NAME     J20 176
 '@S9S_MB_2U_LIB.S9S_MB_2U(SCH_1):PAGE101_I47@PURE_QUANTA.SCONN288_ADR50017P087CC(CHIPS)':
 'DQ19_A': CDS_PINID='DQ19_A';
NET_NAME
'M_B_CPU1_SA_DQ<1>'
 '@S9S_MB_2U_LIB.S9S_MB_2U(SCH_1):M_B_CPU1_SA_DQ'<1>:
 C_SIGNAL='@s9s_mb_2u_lib.s9s_mb_2u(sch_1):m_b_cpu1_sa_dq(1)';
NODE_NAME     U1 J74
 '@S9S_MB_2U_LIB.S9S_MB_2U(SCH_1):PAGE52_I91@PURE_QUANTA.SOCKET4677_AZIF0045P001C01CS(CHIPS)':
 'DDR1_SA_DQ1': CDS_PINID='DDR1_SA_DQ1';
NODE_NAME     J19 9
 '@S9S_MB_2U_LIB.S9S_MB_2U(SCH_1):PAGE100_I25@PURE_QUANTA.SCONN288_ADR50017P130CC(CHIPS)':
 'DQ1_A': CDS_PINID='DQ1_A';
NODE_NAME     J20 9
 '@S9S_MB_2U_LIB.S9S_MB_2U(SCH_1):PAGE101_I47@PURE_QUANTA.SCONN288_ADR50017P087CC(CHIPS)':
 'DQ1_A': CDS_PINID='DQ1_A';
NET_NAME
'M_B_CPU1_SA_DQ<20>'
 '@S9S_MB_2U_LIB.S9S_MB_2U(SCH_1):M_B_CPU1_SA_DQ'<20>:
 C_SIGNAL='@s9s_mb_2u_lib.s9s_mb_2u(sch_1):m_b_cpu1_sa_dq(20)';
NODE_NAME     U1 J60
 '@S9S_MB_2U_LIB.S9S_MB_2U(SCH_1):PAGE52_I91@PURE_QUANTA.SOCKET4677_AZIF0045P001C01CS(CHIPS)':
 'DDR1_SA_DQ20': CDS_PINID='DDR1_SA_DQ20';
NODE_NAME     J19 36
 '@S9S_MB_2U_LIB.S9S_MB_2U(SCH_1):PAGE100_I25@PURE_QUANTA.SCONN288_ADR50017P130CC(CHIPS)':
 'DQ20_A': CDS_PINID='DQ20_A';
NODE_NAME     J20 36
 '@S9S_MB_2U_LIB.S9S_MB_2U(SCH_1):PAGE101_I47@PURE_QUANTA.SCONN288_ADR50017P087CC(CHIPS)':
 'DQ20_A': CDS_PINID='DQ20_A';
NET_NAME
'M_B_CPU1_SA_DQ<21>'
 '@S9S_MB_2U_LIB.S9S_MB_2U(SCH_1):M_B_CPU1_SA_DQ'<21>:
 C_SIGNAL='@s9s_mb_2u_lib.s9s_mb_2u(sch_1):m_b_cpu1_sa_dq(21)';
NODE_NAME     U1 K59
 '@S9S_MB_2U_LIB.S9S_MB_2U(SCH_1):PAGE52_I91@PURE_QUANTA.SOCKET4677_AZIF0045P001C01CS(CHIPS)':
 'DDR1_SA_DQ21': CDS_PINID='DDR1_SA_DQ21';
NODE_NAME     J19 38
 '@S9S_MB_2U_LIB.S9S_MB_2U(SCH_1):PAGE100_I25@PURE_QUANTA.SCONN288_ADR50017P130CC(CHIPS)':
 'DQ21_A': CDS_PINID='DQ21_A';
NODE_NAME     J20 38
 '@S9S_MB_2U_LIB.S9S_MB_2U(SCH_1):PAGE101_I47@PURE_QUANTA.SCONN288_ADR50017P087CC(CHIPS)':
 'DQ21_A': CDS_PINID='DQ21_A';
NET_NAME
'M_B_CPU1_SA_DQ<22>'
 '@S9S_MB_2U_LIB.S9S_MB_2U(SCH_1):M_B_CPU1_SA_DQ'<22>:
 C_SIGNAL='@s9s_mb_2u_lib.s9s_mb_2u(sch_1):m_b_cpu1_sa_dq(22)';
NODE_NAME     U1 N60
 '@S9S_MB_2U_LIB.S9S_MB_2U(SCH_1):PAGE52_I91@PURE_QUANTA.SOCKET4677_AZIF0045P001C01CS(CHIPS)':
 'DDR1_SA_DQ22': CDS_PINID='DDR1_SA_DQ22';
NODE_NAME     J19 181
 '@S9S_MB_2U_LIB.S9S_MB_2U(SCH_1):PAGE100_I25@PURE_QUANTA.SCONN288_ADR50017P130CC(CHIPS)':
 'DQ22_A': CDS_PINID='DQ22_A';
NODE_NAME     J20 181
 '@S9S_MB_2U_LIB.S9S_MB_2U(SCH_1):PAGE101_I47@PURE_QUANTA.SCONN288_ADR50017P087CC(CHIPS)':
 'DQ22_A': CDS_PINID='DQ22_A';
NET_NAME
'M_B_CPU1_SA_DQ<23>'
 '@S9S_MB_2U_LIB.S9S_MB_2U(SCH_1):M_B_CPU1_SA_DQ'<23>:
 C_SIGNAL='@s9s_mb_2u_lib.s9s_mb_2u(sch_1):m_b_cpu1_sa_dq(23)';
NODE_NAME     U1 M59
 '@S9S_MB_2U_LIB.S9S_MB_2U(SCH_1):PAGE52_I91@PURE_QUANTA.SOCKET4677_AZIF0045P001C01CS(CHIPS)':
 'DDR1_SA_DQ23': CDS_PINID='DDR1_SA_DQ23';
NODE_NAME     J19 183
 '@S9S_MB_2U_LIB.S9S_MB_2U(SCH_1):PAGE100_I25@PURE_QUANTA.SCONN288_ADR50017P130CC(CHIPS)':
 'DQ23_A': CDS_PINID='DQ23_A';
NODE_NAME     J20 183
 '@S9S_MB_2U_LIB.S9S_MB_2U(SCH_1):PAGE101_I47@PURE_QUANTA.SCONN288_ADR50017P087CC(CHIPS)':
 'DQ23_A': CDS_PINID='DQ23_A';
NET_NAME
'M_B_CPU1_SA_DQ<24>'
 '@S9S_MB_2U_LIB.S9S_MB_2U(SCH_1):M_B_CPU1_SA_DQ'<24>:
 C_SIGNAL='@s9s_mb_2u_lib.s9s_mb_2u(sch_1):m_b_cpu1_sa_dq(24)';
NODE_NAME     U1 U60
 '@S9S_MB_2U_LIB.S9S_MB_2U(SCH_1):PAGE52_I91@PURE_QUANTA.SOCKET4677_AZIF0045P001C01CS(CHIPS)':
 'DDR1_SA_DQ24': CDS_PINID='DDR1_SA_DQ24';
NODE_NAME     J19 40
 '@S9S_MB_2U_LIB.S9S_MB_2U(SCH_1):PAGE100_I25@PURE_QUANTA.SCONN288_ADR50017P130CC(CHIPS)':
 'DQ24_A': CDS_PINID='DQ24_A';
NODE_NAME     J20 40
 '@S9S_MB_2U_LIB.S9S_MB_2U(SCH_1):PAGE101_I47@PURE_QUANTA.SCONN288_ADR50017P087CC(CHIPS)':
 'DQ24_A': CDS_PINID='DQ24_A';
NET_NAME
'M_B_CPU1_SA_DQ<25>'
 '@S9S_MB_2U_LIB.S9S_MB_2U(SCH_1):M_B_CPU1_SA_DQ'<25>:
 C_SIGNAL='@s9s_mb_2u_lib.s9s_mb_2u(sch_1):m_b_cpu1_sa_dq(25)';
NODE_NAME     U1 T59
 '@S9S_MB_2U_LIB.S9S_MB_2U(SCH_1):PAGE52_I91@PURE_QUANTA.SOCKET4677_AZIF0045P001C01CS(CHIPS)':
 'DDR1_SA_DQ25': CDS_PINID='DDR1_SA_DQ25';
NODE_NAME     J19 42
 '@S9S_MB_2U_LIB.S9S_MB_2U(SCH_1):PAGE100_I25@PURE_QUANTA.SCONN288_ADR50017P130CC(CHIPS)':
 'DQ25_A': CDS_PINID='DQ25_A';
NODE_NAME     J20 42
 '@S9S_MB_2U_LIB.S9S_MB_2U(SCH_1):PAGE101_I47@PURE_QUANTA.SCONN288_ADR50017P087CC(CHIPS)':
 'DQ25_A': CDS_PINID='DQ25_A';
NET_NAME
'M_B_CPU1_SA_DQ<26>'
 '@S9S_MB_2U_LIB.S9S_MB_2U(SCH_1):M_B_CPU1_SA_DQ'<26>:
 C_SIGNAL='@s9s_mb_2u_lib.s9s_mb_2u(sch_1):m_b_cpu1_sa_dq(26)';
NODE_NAME     U1 W60
 '@S9S_MB_2U_LIB.S9S_MB_2U(SCH_1):PAGE52_I91@PURE_QUANTA.SOCKET4677_AZIF0045P001C01CS(CHIPS)':
 'DDR1_SA_DQ26': CDS_PINID='DDR1_SA_DQ26';
NODE_NAME     J19 185
 '@S9S_MB_2U_LIB.S9S_MB_2U(SCH_1):PAGE100_I25@PURE_QUANTA.SCONN288_ADR50017P130CC(CHIPS)':
 'DQ26_A': CDS_PINID='DQ26_A';
NODE_NAME     J20 185
 '@S9S_MB_2U_LIB.S9S_MB_2U(SCH_1):PAGE101_I47@PURE_QUANTA.SCONN288_ADR50017P087CC(CHIPS)':
 'DQ26_A': CDS_PINID='DQ26_A';
NET_NAME
'M_B_CPU1_SA_DQ<27>'
 '@S9S_MB_2U_LIB.S9S_MB_2U(SCH_1):M_B_CPU1_SA_DQ'<27>:
 C_SIGNAL='@s9s_mb_2u_lib.s9s_mb_2u(sch_1):m_b_cpu1_sa_dq(27)';
NODE_NAME     U1 Y59
 '@S9S_MB_2U_LIB.S9S_MB_2U(SCH_1):PAGE52_I91@PURE_QUANTA.SOCKET4677_AZIF0045P001C01CS(CHIPS)':
 'DDR1_SA_DQ27': CDS_PINID='DDR1_SA_DQ27';
NODE_NAME     J19 187
 '@S9S_MB_2U_LIB.S9S_MB_2U(SCH_1):PAGE100_I25@PURE_QUANTA.SCONN288_ADR50017P130CC(CHIPS)':
 'DQ27_A': CDS_PINID='DQ27_A';
NODE_NAME     J20 187
 '@S9S_MB_2U_LIB.S9S_MB_2U(SCH_1):PAGE101_I47@PURE_QUANTA.SCONN288_ADR50017P087CC(CHIPS)':
 'DQ27_A': CDS_PINID='DQ27_A';
NET_NAME
'M_B_CPU1_SA_DQ<28>'
 '@S9S_MB_2U_LIB.S9S_MB_2U(SCH_1):M_B_CPU1_SA_DQ'<28>:
 C_SIGNAL='@s9s_mb_2u_lib.s9s_mb_2u(sch_1):m_b_cpu1_sa_dq(28)';
NODE_NAME     U1 T57
 '@S9S_MB_2U_LIB.S9S_MB_2U(SCH_1):PAGE52_I91@PURE_QUANTA.SOCKET4677_AZIF0045P001C01CS(CHIPS)':
 'DDR1_SA_DQ28': CDS_PINID='DDR1_SA_DQ28';
NODE_NAME     J19 47
 '@S9S_MB_2U_LIB.S9S_MB_2U(SCH_1):PAGE100_I25@PURE_QUANTA.SCONN288_ADR50017P130CC(CHIPS)':
 'DQ28_A': CDS_PINID='DQ28_A';
NODE_NAME     J20 47
 '@S9S_MB_2U_LIB.S9S_MB_2U(SCH_1):PAGE101_I47@PURE_QUANTA.SCONN288_ADR50017P087CC(CHIPS)':
 'DQ28_A': CDS_PINID='DQ28_A';
NET_NAME
'M_B_CPU1_SA_DQ<29>'
 '@S9S_MB_2U_LIB.S9S_MB_2U(SCH_1):M_B_CPU1_SA_DQ'<29>:
 C_SIGNAL='@s9s_mb_2u_lib.s9s_mb_2u(sch_1):m_b_cpu1_sa_dq(29)';
NODE_NAME     U1 U56
 '@S9S_MB_2U_LIB.S9S_MB_2U(SCH_1):PAGE52_I91@PURE_QUANTA.SOCKET4677_AZIF0045P001C01CS(CHIPS)':
 'DDR1_SA_DQ29': CDS_PINID='DDR1_SA_DQ29';
NODE_NAME     J19 49
 '@S9S_MB_2U_LIB.S9S_MB_2U(SCH_1):PAGE100_I25@PURE_QUANTA.SCONN288_ADR50017P130CC(CHIPS)':
 'DQ29_A': CDS_PINID='DQ29_A';
NODE_NAME     J20 49
 '@S9S_MB_2U_LIB.S9S_MB_2U(SCH_1):PAGE101_I47@PURE_QUANTA.SCONN288_ADR50017P087CC(CHIPS)':
 'DQ29_A': CDS_PINID='DQ29_A';
NET_NAME
'M_B_CPU1_SA_DQ<2>'
 '@S9S_MB_2U_LIB.S9S_MB_2U(SCH_1):M_B_CPU1_SA_DQ'<2>:
 C_SIGNAL='@s9s_mb_2u_lib.s9s_mb_2u(sch_1):m_b_cpu1_sa_dq(2)';
NODE_NAME     U1 M75
 '@S9S_MB_2U_LIB.S9S_MB_2U(SCH_1):PAGE52_I91@PURE_QUANTA.SOCKET4677_AZIF0045P001C01CS(CHIPS)':
 'DDR1_SA_DQ2': CDS_PINID='DDR1_SA_DQ2';
NODE_NAME     J19 152
 '@S9S_MB_2U_LIB.S9S_MB_2U(SCH_1):PAGE100_I25@PURE_QUANTA.SCONN288_ADR50017P130CC(CHIPS)':
 'DQ2_A': CDS_PINID='DQ2_A';
NODE_NAME     J20 152
 '@S9S_MB_2U_LIB.S9S_MB_2U(SCH_1):PAGE101_I47@PURE_QUANTA.SCONN288_ADR50017P087CC(CHIPS)':
 'DQ2_A': CDS_PINID='DQ2_A';
NET_NAME
'M_B_CPU1_SA_DQ<30>'
 '@S9S_MB_2U_LIB.S9S_MB_2U(SCH_1):M_B_CPU1_SA_DQ'<30>:
 C_SIGNAL='@s9s_mb_2u_lib.s9s_mb_2u(sch_1):m_b_cpu1_sa_dq(30)';
NODE_NAME     U1 Y57
 '@S9S_MB_2U_LIB.S9S_MB_2U(SCH_1):PAGE52_I91@PURE_QUANTA.SOCKET4677_AZIF0045P001C01CS(CHIPS)':
 'DDR1_SA_DQ30': CDS_PINID='DDR1_SA_DQ30';
NODE_NAME     J19 192
 '@S9S_MB_2U_LIB.S9S_MB_2U(SCH_1):PAGE100_I25@PURE_QUANTA.SCONN288_ADR50017P130CC(CHIPS)':
 'DQ30_A': CDS_PINID='DQ30_A';
NODE_NAME     J20 192
 '@S9S_MB_2U_LIB.S9S_MB_2U(SCH_1):PAGE101_I47@PURE_QUANTA.SCONN288_ADR50017P087CC(CHIPS)':
 'DQ30_A': CDS_PINID='DQ30_A';
NET_NAME
'M_B_CPU1_SA_DQ<31>'
 '@S9S_MB_2U_LIB.S9S_MB_2U(SCH_1):M_B_CPU1_SA_DQ'<31>:
 C_SIGNAL='@s9s_mb_2u_lib.s9s_mb_2u(sch_1):m_b_cpu1_sa_dq(31)';
NODE_NAME     U1 W56
 '@S9S_MB_2U_LIB.S9S_MB_2U(SCH_1):PAGE52_I91@PURE_QUANTA.SOCKET4677_AZIF0045P001C01CS(CHIPS)':
 'DDR1_SA_DQ31': CDS_PINID='DDR1_SA_DQ31';
NODE_NAME     J19 194
 '@S9S_MB_2U_LIB.S9S_MB_2U(SCH_1):PAGE100_I25@PURE_QUANTA.SCONN288_ADR50017P130CC(CHIPS)':
 'DQ31_A': CDS_PINID='DQ31_A';
NODE_NAME     J20 194
 '@S9S_MB_2U_LIB.S9S_MB_2U(SCH_1):PAGE101_I47@PURE_QUANTA.SCONN288_ADR50017P087CC(CHIPS)':
 'DQ31_A': CDS_PINID='DQ31_A';
NET_NAME
'M_B_CPU1_SA_DQ<3>'
 '@S9S_MB_2U_LIB.S9S_MB_2U(SCH_1):M_B_CPU1_SA_DQ'<3>:
 C_SIGNAL='@s9s_mb_2u_lib.s9s_mb_2u(sch_1):m_b_cpu1_sa_dq(3)';
NODE_NAME     U1 N74
 '@S9S_MB_2U_LIB.S9S_MB_2U(SCH_1):PAGE52_I91@PURE_QUANTA.SOCKET4677_AZIF0045P001C01CS(CHIPS)':
 'DDR1_SA_DQ3': CDS_PINID='DDR1_SA_DQ3';
NODE_NAME     J19 154
 '@S9S_MB_2U_LIB.S9S_MB_2U(SCH_1):PAGE100_I25@PURE_QUANTA.SCONN288_ADR50017P130CC(CHIPS)':
 'DQ3_A': CDS_PINID='DQ3_A';
NODE_NAME     J20 154
 '@S9S_MB_2U_LIB.S9S_MB_2U(SCH_1):PAGE101_I47@PURE_QUANTA.SCONN288_ADR50017P087CC(CHIPS)':
 'DQ3_A': CDS_PINID='DQ3_A';
NET_NAME
'M_B_CPU1_SA_DQ<4>'
 '@S9S_MB_2U_LIB.S9S_MB_2U(SCH_1):M_B_CPU1_SA_DQ'<4>:
 C_SIGNAL='@s9s_mb_2u_lib.s9s_mb_2u(sch_1):m_b_cpu1_sa_dq(4)';
NODE_NAME     U1 J72
 '@S9S_MB_2U_LIB.S9S_MB_2U(SCH_1):PAGE52_I91@PURE_QUANTA.SOCKET4677_AZIF0045P001C01CS(CHIPS)':
 'DDR1_SA_DQ4': CDS_PINID='DDR1_SA_DQ4';
NODE_NAME     J19 14
 '@S9S_MB_2U_LIB.S9S_MB_2U(SCH_1):PAGE100_I25@PURE_QUANTA.SCONN288_ADR50017P130CC(CHIPS)':
 'DQ4_A': CDS_PINID='DQ4_A';
NODE_NAME     J20 14
 '@S9S_MB_2U_LIB.S9S_MB_2U(SCH_1):PAGE101_I47@PURE_QUANTA.SCONN288_ADR50017P087CC(CHIPS)':
 'DQ4_A': CDS_PINID='DQ4_A';
NET_NAME
'M_B_CPU1_SA_DQ<5>'
 '@S9S_MB_2U_LIB.S9S_MB_2U(SCH_1):M_B_CPU1_SA_DQ'<5>:
 C_SIGNAL='@s9s_mb_2u_lib.s9s_mb_2u(sch_1):m_b_cpu1_sa_dq(5)';
NODE_NAME     U1 K71
 '@S9S_MB_2U_LIB.S9S_MB_2U(SCH_1):PAGE52_I91@PURE_QUANTA.SOCKET4677_AZIF0045P001C01CS(CHIPS)':
 'DDR1_SA_DQ5': CDS_PINID='DDR1_SA_DQ5';
NODE_NAME     J19 16
 '@S9S_MB_2U_LIB.S9S_MB_2U(SCH_1):PAGE100_I25@PURE_QUANTA.SCONN288_ADR50017P130CC(CHIPS)':
 'DQ5_A': CDS_PINID='DQ5_A';
NODE_NAME     J20 16
 '@S9S_MB_2U_LIB.S9S_MB_2U(SCH_1):PAGE101_I47@PURE_QUANTA.SCONN288_ADR50017P087CC(CHIPS)':
 'DQ5_A': CDS_PINID='DQ5_A';
NET_NAME
'M_B_CPU1_SA_DQ<6>'
 '@S9S_MB_2U_LIB.S9S_MB_2U(SCH_1):M_B_CPU1_SA_DQ'<6>:
 C_SIGNAL='@s9s_mb_2u_lib.s9s_mb_2u(sch_1):m_b_cpu1_sa_dq(6)';
NODE_NAME     U1 N72
 '@S9S_MB_2U_LIB.S9S_MB_2U(SCH_1):PAGE52_I91@PURE_QUANTA.SOCKET4677_AZIF0045P001C01CS(CHIPS)':
 'DDR1_SA_DQ6': CDS_PINID='DDR1_SA_DQ6';
NODE_NAME     J19 159
 '@S9S_MB_2U_LIB.S9S_MB_2U(SCH_1):PAGE100_I25@PURE_QUANTA.SCONN288_ADR50017P130CC(CHIPS)':
 'DQ6_A': CDS_PINID='DQ6_A';
NODE_NAME     J20 159
 '@S9S_MB_2U_LIB.S9S_MB_2U(SCH_1):PAGE101_I47@PURE_QUANTA.SCONN288_ADR50017P087CC(CHIPS)':
 'DQ6_A': CDS_PINID='DQ6_A';
NET_NAME
'M_B_CPU1_SA_DQ<7>'
 '@S9S_MB_2U_LIB.S9S_MB_2U(SCH_1):M_B_CPU1_SA_DQ'<7>:
 C_SIGNAL='@s9s_mb_2u_lib.s9s_mb_2u(sch_1):m_b_cpu1_sa_dq(7)';
NODE_NAME     U1 M71
 '@S9S_MB_2U_LIB.S9S_MB_2U(SCH_1):PAGE52_I91@PURE_QUANTA.SOCKET4677_AZIF0045P001C01CS(CHIPS)':
 'DDR1_SA_DQ7': CDS_PINID='DDR1_SA_DQ7';
NODE_NAME     J19 161
 '@S9S_MB_2U_LIB.S9S_MB_2U(SCH_1):PAGE100_I25@PURE_QUANTA.SCONN288_ADR50017P130CC(CHIPS)':
 'DQ7_A': CDS_PINID='DQ7_A';
NODE_NAME     J20 161
 '@S9S_MB_2U_LIB.S9S_MB_2U(SCH_1):PAGE101_I47@PURE_QUANTA.SCONN288_ADR50017P087CC(CHIPS)':
 'DQ7_A': CDS_PINID='DQ7_A';
NET_NAME
'M_B_CPU1_SA_DQ<8>'
 '@S9S_MB_2U_LIB.S9S_MB_2U(SCH_1):M_B_CPU1_SA_DQ'<8>:
 C_SIGNAL='@s9s_mb_2u_lib.s9s_mb_2u(sch_1):m_b_cpu1_sa_dq(8)';
NODE_NAME     U1 U72
 '@S9S_MB_2U_LIB.S9S_MB_2U(SCH_1):PAGE52_I91@PURE_QUANTA.SOCKET4677_AZIF0045P001C01CS(CHIPS)':
 'DDR1_SA_DQ8': CDS_PINID='DDR1_SA_DQ8';
NODE_NAME     J19 18
 '@S9S_MB_2U_LIB.S9S_MB_2U(SCH_1):PAGE100_I25@PURE_QUANTA.SCONN288_ADR50017P130CC(CHIPS)':
 'DQ8_A': CDS_PINID='DQ8_A';
NODE_NAME     J20 18
 '@S9S_MB_2U_LIB.S9S_MB_2U(SCH_1):PAGE101_I47@PURE_QUANTA.SCONN288_ADR50017P087CC(CHIPS)':
 'DQ8_A': CDS_PINID='DQ8_A';
NET_NAME
'M_B_CPU1_SA_DQ<9>'
 '@S9S_MB_2U_LIB.S9S_MB_2U(SCH_1):M_B_CPU1_SA_DQ'<9>:
 C_SIGNAL='@s9s_mb_2u_lib.s9s_mb_2u(sch_1):m_b_cpu1_sa_dq(9)';
NODE_NAME     U1 T71
 '@S9S_MB_2U_LIB.S9S_MB_2U(SCH_1):PAGE52_I91@PURE_QUANTA.SOCKET4677_AZIF0045P001C01CS(CHIPS)':
 'DDR1_SA_DQ9': CDS_PINID='DDR1_SA_DQ9';
NODE_NAME     J19 20
 '@S9S_MB_2U_LIB.S9S_MB_2U(SCH_1):PAGE100_I25@PURE_QUANTA.SCONN288_ADR50017P130CC(CHIPS)':
 'DQ9_A': CDS_PINID='DQ9_A';
NODE_NAME     J20 20
 '@S9S_MB_2U_LIB.S9S_MB_2U(SCH_1):PAGE101_I47@PURE_QUANTA.SCONN288_ADR50017P087CC(CHIPS)':
 'DQ9_A': CDS_PINID='DQ9_A';
NET_NAME
'M_B_CPU1_SA_DQS_DN<0>'
 '@S9S_MB_2U_LIB.S9S_MB_2U(SCH_1):M_B_CPU1_SA_DQS_DN'<0>:
 C_SIGNAL='@s9s_mb_2u_lib.s9s_mb_2u(sch_1):m_b_cpu1_sa_dqs_dn(0)';
NODE_NAME     U1 H73
 '@S9S_MB_2U_LIB.S9S_MB_2U(SCH_1):PAGE52_I91@PURE_QUANTA.SOCKET4677_AZIF0045P001C01CS(CHIPS)':
 'DDR1_SA_DQS_DN0': CDS_PINID='DDR1_SA_DQS_DN0';
NODE_NAME     J19 12
 '@S9S_MB_2U_LIB.S9S_MB_2U(SCH_1):PAGE100_I178@PURE_QUANTA.SCONN288_ADR50017P130CC(CHIPS)':
 'DQS0_A_C': CDS_PINID='DQS0_A_C';
NODE_NAME     J20 12
 '@S9S_MB_2U_LIB.S9S_MB_2U(SCH_1):PAGE101_I178@PURE_QUANTA.SCONN288_ADR50017P087CC(CHIPS)':
 'DQS0_A_C': CDS_PINID='DQS0_A_C';
NET_NAME
'M_B_CPU1_SA_DQS_DN<1>'
 '@S9S_MB_2U_LIB.S9S_MB_2U(SCH_1):M_B_CPU1_SA_DQS_DN'<1>:
 C_SIGNAL='@s9s_mb_2u_lib.s9s_mb_2u(sch_1):m_b_cpu1_sa_dqs_dn(1)';
NODE_NAME     U1 R70
 '@S9S_MB_2U_LIB.S9S_MB_2U(SCH_1):PAGE52_I91@PURE_QUANTA.SOCKET4677_AZIF0045P001C01CS(CHIPS)':
 'DDR1_SA_DQS_DN1': CDS_PINID='DDR1_SA_DQS_DN1';
NODE_NAME     J19 23
 '@S9S_MB_2U_LIB.S9S_MB_2U(SCH_1):PAGE100_I178@PURE_QUANTA.SCONN288_ADR50017P130CC(CHIPS)':
 'DQS1_A_C': CDS_PINID='DQS1_A_C';
NODE_NAME     J20 23
 '@S9S_MB_2U_LIB.S9S_MB_2U(SCH_1):PAGE101_I178@PURE_QUANTA.SCONN288_ADR50017P087CC(CHIPS)':
 'DQS1_A_C': CDS_PINID='DQS1_A_C';
NET_NAME
'M_B_CPU1_SA_DQS_DN<2>'
 '@S9S_MB_2U_LIB.S9S_MB_2U(SCH_1):M_B_CPU1_SA_DQS_DN'<2>:
 C_SIGNAL='@s9s_mb_2u_lib.s9s_mb_2u(sch_1):m_b_cpu1_sa_dqs_dn(2)';
NODE_NAME     U1 H61
 '@S9S_MB_2U_LIB.S9S_MB_2U(SCH_1):PAGE52_I91@PURE_QUANTA.SOCKET4677_AZIF0045P001C01CS(CHIPS)':
 'DDR1_SA_DQS_DN2': CDS_PINID='DDR1_SA_DQS_DN2';
NODE_NAME     J19 34
 '@S9S_MB_2U_LIB.S9S_MB_2U(SCH_1):PAGE100_I178@PURE_QUANTA.SCONN288_ADR50017P130CC(CHIPS)':
 'DQS2_A_C': CDS_PINID='DQS2_A_C';
NODE_NAME     J20 34
 '@S9S_MB_2U_LIB.S9S_MB_2U(SCH_1):PAGE101_I178@PURE_QUANTA.SCONN288_ADR50017P087CC(CHIPS)':
 'DQS2_A_C': CDS_PINID='DQS2_A_C';
NET_NAME
'M_B_CPU1_SA_DQS_DN<3>'
 '@S9S_MB_2U_LIB.S9S_MB_2U(SCH_1):M_B_CPU1_SA_DQS_DN'<3>:
 C_SIGNAL='@s9s_mb_2u_lib.s9s_mb_2u(sch_1):m_b_cpu1_sa_dqs_dn(3)';
NODE_NAME     U1 R58
 '@S9S_MB_2U_LIB.S9S_MB_2U(SCH_1):PAGE52_I91@PURE_QUANTA.SOCKET4677_AZIF0045P001C01CS(CHIPS)':
 'DDR1_SA_DQS_DN3': CDS_PINID='DDR1_SA_DQS_DN3';
NODE_NAME     J19 45
 '@S9S_MB_2U_LIB.S9S_MB_2U(SCH_1):PAGE100_I178@PURE_QUANTA.SCONN288_ADR50017P130CC(CHIPS)':
 'DQS3_A_C': CDS_PINID='DQS3_A_C';
NODE_NAME     J20 45
 '@S9S_MB_2U_LIB.S9S_MB_2U(SCH_1):PAGE101_I178@PURE_QUANTA.SCONN288_ADR50017P087CC(CHIPS)':
 'DQS3_A_C': CDS_PINID='DQS3_A_C';
NET_NAME
'M_B_CPU1_SA_DQS_DN<4>'
 '@S9S_MB_2U_LIB.S9S_MB_2U(SCH_1):M_B_CPU1_SA_DQS_DN'<4>:
 C_SIGNAL='@s9s_mb_2u_lib.s9s_mb_2u(sch_1):m_b_cpu1_sa_dqs_dn(4)';
NODE_NAME     U1 H55
 '@S9S_MB_2U_LIB.S9S_MB_2U(SCH_1):PAGE52_I91@PURE_QUANTA.SOCKET4677_AZIF0045P001C01CS(CHIPS)':
 'DDR1_SA_DQS_DN4': CDS_PINID='DDR1_SA_DQS_DN4';
NODE_NAME     J19 56
 '@S9S_MB_2U_LIB.S9S_MB_2U(SCH_1):PAGE100_I178@PURE_QUANTA.SCONN288_ADR50017P130CC(CHIPS)':
 'DQS4_A_C': CDS_PINID='DQS4_A_C';
NODE_NAME     J20 56
 '@S9S_MB_2U_LIB.S9S_MB_2U(SCH_1):PAGE101_I178@PURE_QUANTA.SCONN288_ADR50017P087CC(CHIPS)':
 'DQS4_A_C': CDS_PINID='DQS4_A_C';
NET_NAME
'M_B_CPU1_SA_DQS_DN<5>'
 '@S9S_MB_2U_LIB.S9S_MB_2U(SCH_1):M_B_CPU1_SA_DQS_DN'<5>:
 C_SIGNAL='@s9s_mb_2u_lib.s9s_mb_2u(sch_1):m_b_cpu1_sa_dqs_dn(5)';
NODE_NAME     U1 M73
 '@S9S_MB_2U_LIB.S9S_MB_2U(SCH_1):PAGE52_I91@PURE_QUANTA.SOCKET4677_AZIF0045P001C01CS(CHIPS)':
 'DDR1_SA_DQS_DN5': CDS_PINID='DDR1_SA_DQS_DN5';
NODE_NAME     J19 156
 '@S9S_MB_2U_LIB.S9S_MB_2U(SCH_1):PAGE100_I178@PURE_QUANTA.SCONN288_ADR50017P130CC(CHIPS)':
 'DQS5_A_C||TDQS5_A_C||DQS5_A_T||TDQS5_A_T': CDS_PINID='\dqs5_a_c||tdqs5_a_c||dqs5_a_t||tdqs5_a_t\';
NODE_NAME     J20 156
 '@S9S_MB_2U_LIB.S9S_MB_2U(SCH_1):PAGE101_I178@PURE_QUANTA.SCONN288_ADR50017P087CC(CHIPS)':
 'DQS5_A_C||TDQS5_A_C||DQS5_A_T||TDQS5_A_T': CDS_PINID='\dqs5_a_c||tdqs5_a_c||dqs5_a_t||tdqs5_a_t\';
NET_NAME
'M_B_CPU1_SA_DQS_DN<6>'
 '@S9S_MB_2U_LIB.S9S_MB_2U(SCH_1):M_B_CPU1_SA_DQS_DN'<6>:
 C_SIGNAL='@s9s_mb_2u_lib.s9s_mb_2u(sch_1):m_b_cpu1_sa_dqs_dn(6)';
NODE_NAME     U1 AA70
 '@S9S_MB_2U_LIB.S9S_MB_2U(SCH_1):PAGE52_I91@PURE_QUANTA.SOCKET4677_AZIF0045P001C01CS(CHIPS)':
 'DDR1_SA_DQS_DN6': CDS_PINID='DDR1_SA_DQS_DN6';
NODE_NAME     J19 167
 '@S9S_MB_2U_LIB.S9S_MB_2U(SCH_1):PAGE100_I178@PURE_QUANTA.SCONN288_ADR50017P130CC(CHIPS)':
 'DQS6_A_C||TDQS6_A_C||DQS6_A_T||TDQS6_A_T': CDS_PINID='\dqs6_a_c||tdqs6_a_c||dqs6_a_t||tdqs6_a_t\';
NODE_NAME     J20 167
 '@S9S_MB_2U_LIB.S9S_MB_2U(SCH_1):PAGE101_I178@PURE_QUANTA.SCONN288_ADR50017P087CC(CHIPS)':
 'DQS6_A_C||TDQS6_A_C||DQS6_A_T||TDQS6_A_T': CDS_PINID='\dqs6_a_c||tdqs6_a_c||dqs6_a_t||tdqs6_a_t\';
NET_NAME
'M_B_CPU1_SA_DQS_DN<7>'
 '@S9S_MB_2U_LIB.S9S_MB_2U(SCH_1):M_B_CPU1_SA_DQS_DN'<7>:
 C_SIGNAL='@s9s_mb_2u_lib.s9s_mb_2u(sch_1):m_b_cpu1_sa_dqs_dn(7)';
NODE_NAME     U1 M61
 '@S9S_MB_2U_LIB.S9S_MB_2U(SCH_1):PAGE52_I91@PURE_QUANTA.SOCKET4677_AZIF0045P001C01CS(CHIPS)':
 'DDR1_SA_DQS_DN7': CDS_PINID='DDR1_SA_DQS_DN7';
NODE_NAME     J19 178
 '@S9S_MB_2U_LIB.S9S_MB_2U(SCH_1):PAGE100_I178@PURE_QUANTA.SCONN288_ADR50017P130CC(CHIPS)':
 'DQS7_A_C||TDQS7_A_C': CDS_PINID='\dqs7_a_c||tdqs7_a_c\';
NODE_NAME     J20 178
 '@S9S_MB_2U_LIB.S9S_MB_2U(SCH_1):PAGE101_I178@PURE_QUANTA.SCONN288_ADR50017P087CC(CHIPS)':
 'DQS7_A_C||TDQS7_A_C': CDS_PINID='\dqs7_a_c||tdqs7_a_c\';
NET_NAME
'M_B_CPU1_SA_DQS_DN<8>'
 '@S9S_MB_2U_LIB.S9S_MB_2U(SCH_1):M_B_CPU1_SA_DQS_DN'<8>:
 C_SIGNAL='@s9s_mb_2u_lib.s9s_mb_2u(sch_1):m_b_cpu1_sa_dqs_dn(8)';
NODE_NAME     U1 AA58
 '@S9S_MB_2U_LIB.S9S_MB_2U(SCH_1):PAGE52_I91@PURE_QUANTA.SOCKET4677_AZIF0045P001C01CS(CHIPS)':
 'DDR1_SA_DQS_DN8': CDS_PINID='DDR1_SA_DQS_DN8';
NODE_NAME     J19 189
 '@S9S_MB_2U_LIB.S9S_MB_2U(SCH_1):PAGE100_I178@PURE_QUANTA.SCONN288_ADR50017P130CC(CHIPS)':
 'DQS8_A_C||TDQS8_A_C': CDS_PINID='\dqs8_a_c||tdqs8_a_c\';
NODE_NAME     J20 189
 '@S9S_MB_2U_LIB.S9S_MB_2U(SCH_1):PAGE101_I178@PURE_QUANTA.SCONN288_ADR50017P087CC(CHIPS)':
 'DQS8_A_C||TDQS8_A_C': CDS_PINID='\dqs8_a_c||tdqs8_a_c\';
NET_NAME
'M_B_CPU1_SA_DQS_DN<9>'
 '@S9S_MB_2U_LIB.S9S_MB_2U(SCH_1):M_B_CPU1_SA_DQS_DN'<9>:
 C_SIGNAL='@s9s_mb_2u_lib.s9s_mb_2u(sch_1):m_b_cpu1_sa_dqs_dn(9)';
NODE_NAME     U1 M55
 '@S9S_MB_2U_LIB.S9S_MB_2U(SCH_1):PAGE52_I91@PURE_QUANTA.SOCKET4677_AZIF0045P001C01CS(CHIPS)':
 'DDR1_SA_DQS_DN9': CDS_PINID='DDR1_SA_DQS_DN9';
NODE_NAME     J19 200
 '@S9S_MB_2U_LIB.S9S_MB_2U(SCH_1):PAGE100_I178@PURE_QUANTA.SCONN288_ADR50017P130CC(CHIPS)':
 'DQS9_A_C||TDQS9_A_C': CDS_PINID='\dqs9_a_c||tdqs9_a_c\';
NODE_NAME     J20 200
 '@S9S_MB_2U_LIB.S9S_MB_2U(SCH_1):PAGE101_I178@PURE_QUANTA.SCONN288_ADR50017P087CC(CHIPS)':
 'DQS9_A_C||TDQS9_A_C': CDS_PINID='\dqs9_a_c||tdqs9_a_c\';
NET_NAME
'M_B_CPU1_SA_DQS_DP<0>'
 '@S9S_MB_2U_LIB.S9S_MB_2U(SCH_1):M_B_CPU1_SA_DQS_DP'<0>:
 C_SIGNAL='@s9s_mb_2u_lib.s9s_mb_2u(sch_1):m_b_cpu1_sa_dqs_dp(0)';
NODE_NAME     U1 K73
 '@S9S_MB_2U_LIB.S9S_MB_2U(SCH_1):PAGE52_I91@PURE_QUANTA.SOCKET4677_AZIF0045P001C01CS(CHIPS)':
 'DDR1_SA_DQS_DP0': CDS_PINID='DDR1_SA_DQS_DP0';
NODE_NAME     J19 11
 '@S9S_MB_2U_LIB.S9S_MB_2U(SCH_1):PAGE100_I178@PURE_QUANTA.SCONN288_ADR50017P130CC(CHIPS)':
 'DQS0_A_T': CDS_PINID='DQS0_A_T';
NODE_NAME     J20 11
 '@S9S_MB_2U_LIB.S9S_MB_2U(SCH_1):PAGE101_I178@PURE_QUANTA.SCONN288_ADR50017P087CC(CHIPS)':
 'DQS0_A_T': CDS_PINID='DQS0_A_T';
NET_NAME
'M_B_CPU1_SA_DQS_DP<1>'
 '@S9S_MB_2U_LIB.S9S_MB_2U(SCH_1):M_B_CPU1_SA_DQS_DP'<1>:
 C_SIGNAL='@s9s_mb_2u_lib.s9s_mb_2u(sch_1):m_b_cpu1_sa_dqs_dp(1)';
NODE_NAME     U1 U70
 '@S9S_MB_2U_LIB.S9S_MB_2U(SCH_1):PAGE52_I91@PURE_QUANTA.SOCKET4677_AZIF0045P001C01CS(CHIPS)':
 'DDR1_SA_DQS_DP1': CDS_PINID='DDR1_SA_DQS_DP1';
NODE_NAME     J19 22
 '@S9S_MB_2U_LIB.S9S_MB_2U(SCH_1):PAGE100_I178@PURE_QUANTA.SCONN288_ADR50017P130CC(CHIPS)':
 'DQS1_A_T': CDS_PINID='DQS1_A_T';
NODE_NAME     J20 22
 '@S9S_MB_2U_LIB.S9S_MB_2U(SCH_1):PAGE101_I178@PURE_QUANTA.SCONN288_ADR50017P087CC(CHIPS)':
 'DQS1_A_T': CDS_PINID='DQS1_A_T';
NET_NAME
'M_B_CPU1_SA_DQS_DP<2>'
 '@S9S_MB_2U_LIB.S9S_MB_2U(SCH_1):M_B_CPU1_SA_DQS_DP'<2>:
 C_SIGNAL='@s9s_mb_2u_lib.s9s_mb_2u(sch_1):m_b_cpu1_sa_dqs_dp(2)';
NODE_NAME     U1 K61
 '@S9S_MB_2U_LIB.S9S_MB_2U(SCH_1):PAGE52_I91@PURE_QUANTA.SOCKET4677_AZIF0045P001C01CS(CHIPS)':
 'DDR1_SA_DQS_DP2': CDS_PINID='DDR1_SA_DQS_DP2';
NODE_NAME     J19 33
 '@S9S_MB_2U_LIB.S9S_MB_2U(SCH_1):PAGE100_I178@PURE_QUANTA.SCONN288_ADR50017P130CC(CHIPS)':
 'DQS2_A_T': CDS_PINID='DQS2_A_T';
NODE_NAME     J20 33
 '@S9S_MB_2U_LIB.S9S_MB_2U(SCH_1):PAGE101_I178@PURE_QUANTA.SCONN288_ADR50017P087CC(CHIPS)':
 'DQS2_A_T': CDS_PINID='DQS2_A_T';
NET_NAME
'M_B_CPU1_SA_DQS_DP<3>'
 '@S9S_MB_2U_LIB.S9S_MB_2U(SCH_1):M_B_CPU1_SA_DQS_DP'<3>:
 C_SIGNAL='@s9s_mb_2u_lib.s9s_mb_2u(sch_1):m_b_cpu1_sa_dqs_dp(3)';
NODE_NAME     U1 U58
 '@S9S_MB_2U_LIB.S9S_MB_2U(SCH_1):PAGE52_I91@PURE_QUANTA.SOCKET4677_AZIF0045P001C01CS(CHIPS)':
 'DDR1_SA_DQS_DP3': CDS_PINID='DDR1_SA_DQS_DP3';
NODE_NAME     J19 44
 '@S9S_MB_2U_LIB.S9S_MB_2U(SCH_1):PAGE100_I178@PURE_QUANTA.SCONN288_ADR50017P130CC(CHIPS)':
 'DQS3_A_T': CDS_PINID='DQS3_A_T';
NODE_NAME     J20 44
 '@S9S_MB_2U_LIB.S9S_MB_2U(SCH_1):PAGE101_I178@PURE_QUANTA.SCONN288_ADR50017P087CC(CHIPS)':
 'DQS3_A_T': CDS_PINID='DQS3_A_T';
NET_NAME
'M_B_CPU1_SA_DQS_DP<4>'
 '@S9S_MB_2U_LIB.S9S_MB_2U(SCH_1):M_B_CPU1_SA_DQS_DP'<4>:
 C_SIGNAL='@s9s_mb_2u_lib.s9s_mb_2u(sch_1):m_b_cpu1_sa_dqs_dp(4)';
NODE_NAME     U1 K55
 '@S9S_MB_2U_LIB.S9S_MB_2U(SCH_1):PAGE52_I91@PURE_QUANTA.SOCKET4677_AZIF0045P001C01CS(CHIPS)':
 'DDR1_SA_DQS_DP4': CDS_PINID='DDR1_SA_DQS_DP4';
NODE_NAME     J19 55
 '@S9S_MB_2U_LIB.S9S_MB_2U(SCH_1):PAGE100_I178@PURE_QUANTA.SCONN288_ADR50017P130CC(CHIPS)':
 'DQS4_A_T': CDS_PINID='DQS4_A_T';
NODE_NAME     J20 55
 '@S9S_MB_2U_LIB.S9S_MB_2U(SCH_1):PAGE101_I178@PURE_QUANTA.SCONN288_ADR50017P087CC(CHIPS)':
 'DQS4_A_T': CDS_PINID='DQS4_A_T';
NET_NAME
'M_B_CPU1_SA_DQS_DP<5>'
 '@S9S_MB_2U_LIB.S9S_MB_2U(SCH_1):M_B_CPU1_SA_DQS_DP'<5>:
 C_SIGNAL='@s9s_mb_2u_lib.s9s_mb_2u(sch_1):m_b_cpu1_sa_dqs_dp(5)';
NODE_NAME     U1 P73
 '@S9S_MB_2U_LIB.S9S_MB_2U(SCH_1):PAGE52_I91@PURE_QUANTA.SOCKET4677_AZIF0045P001C01CS(CHIPS)':
 'DDR1_SA_DQS_DP5': CDS_PINID='DDR1_SA_DQS_DP5';
NODE_NAME     J19 157
 '@S9S_MB_2U_LIB.S9S_MB_2U(SCH_1):PAGE100_I178@PURE_QUANTA.SCONN288_ADR50017P130CC(CHIPS)':
 'DQS5_A_T||TDQS5_A_T': CDS_PINID='\dqs5_a_t||tdqs5_a_t\';
NODE_NAME     J20 157
 '@S9S_MB_2U_LIB.S9S_MB_2U(SCH_1):PAGE101_I178@PURE_QUANTA.SCONN288_ADR50017P087CC(CHIPS)':
 'DQS5_A_T||TDQS5_A_T': CDS_PINID='\dqs5_a_t||tdqs5_a_t\';
NET_NAME
'M_B_CPU1_SA_DQS_DP<6>'
 '@S9S_MB_2U_LIB.S9S_MB_2U(SCH_1):M_B_CPU1_SA_DQS_DP'<6>:
 C_SIGNAL='@s9s_mb_2u_lib.s9s_mb_2u(sch_1):m_b_cpu1_sa_dqs_dp(6)';
NODE_NAME     U1 W70
 '@S9S_MB_2U_LIB.S9S_MB_2U(SCH_1):PAGE52_I91@PURE_QUANTA.SOCKET4677_AZIF0045P001C01CS(CHIPS)':
 'DDR1_SA_DQS_DP6': CDS_PINID='DDR1_SA_DQS_DP6';
NODE_NAME     J19 168
 '@S9S_MB_2U_LIB.S9S_MB_2U(SCH_1):PAGE100_I178@PURE_QUANTA.SCONN288_ADR50017P130CC(CHIPS)':
 'DQS6_A_T||TDQS6_A_T': CDS_PINID='\dqs6_a_t||tdqs6_a_t\';
NODE_NAME     J20 168
 '@S9S_MB_2U_LIB.S9S_MB_2U(SCH_1):PAGE101_I178@PURE_QUANTA.SCONN288_ADR50017P087CC(CHIPS)':
 'DQS6_A_T||TDQS6_A_T': CDS_PINID='\dqs6_a_t||tdqs6_a_t\';
NET_NAME
'M_B_CPU1_SA_DQS_DP<7>'
 '@S9S_MB_2U_LIB.S9S_MB_2U(SCH_1):M_B_CPU1_SA_DQS_DP'<7>:
 C_SIGNAL='@s9s_mb_2u_lib.s9s_mb_2u(sch_1):m_b_cpu1_sa_dqs_dp(7)';
NODE_NAME     U1 P61
 '@S9S_MB_2U_LIB.S9S_MB_2U(SCH_1):PAGE52_I91@PURE_QUANTA.SOCKET4677_AZIF0045P001C01CS(CHIPS)':
 'DDR1_SA_DQS_DP7': CDS_PINID='DDR1_SA_DQS_DP7';
NODE_NAME     J19 179
 '@S9S_MB_2U_LIB.S9S_MB_2U(SCH_1):PAGE100_I178@PURE_QUANTA.SCONN288_ADR50017P130CC(CHIPS)':
 'DQS7_A_T||TDQS7_A_T': CDS_PINID='\dqs7_a_t||tdqs7_a_t\';
NODE_NAME     J20 179
 '@S9S_MB_2U_LIB.S9S_MB_2U(SCH_1):PAGE101_I178@PURE_QUANTA.SCONN288_ADR50017P087CC(CHIPS)':
 'DQS7_A_T||TDQS7_A_T': CDS_PINID='\dqs7_a_t||tdqs7_a_t\';
NET_NAME
'M_B_CPU1_SA_DQS_DP<8>'
 '@S9S_MB_2U_LIB.S9S_MB_2U(SCH_1):M_B_CPU1_SA_DQS_DP'<8>:
 C_SIGNAL='@s9s_mb_2u_lib.s9s_mb_2u(sch_1):m_b_cpu1_sa_dqs_dp(8)';
NODE_NAME     U1 W58
 '@S9S_MB_2U_LIB.S9S_MB_2U(SCH_1):PAGE52_I91@PURE_QUANTA.SOCKET4677_AZIF0045P001C01CS(CHIPS)':
 'DDR1_SA_DQS_DP8': CDS_PINID='DDR1_SA_DQS_DP8';
NODE_NAME     J19 190
 '@S9S_MB_2U_LIB.S9S_MB_2U(SCH_1):PAGE100_I178@PURE_QUANTA.SCONN288_ADR50017P130CC(CHIPS)':
 'DQS8_A_T||TDQS8_A_T': CDS_PINID='\dqs8_a_t||tdqs8_a_t\';
NODE_NAME     J20 190
 '@S9S_MB_2U_LIB.S9S_MB_2U(SCH_1):PAGE101_I178@PURE_QUANTA.SCONN288_ADR50017P087CC(CHIPS)':
 'DQS8_A_T||TDQS8_A_T': CDS_PINID='\dqs8_a_t||tdqs8_a_t\';
NET_NAME
'M_B_CPU1_SA_DQS_DP<9>'
 '@S9S_MB_2U_LIB.S9S_MB_2U(SCH_1):M_B_CPU1_SA_DQS_DP'<9>:
 C_SIGNAL='@s9s_mb_2u_lib.s9s_mb_2u(sch_1):m_b_cpu1_sa_dqs_dp(9)';
NODE_NAME     U1 P55
 '@S9S_MB_2U_LIB.S9S_MB_2U(SCH_1):PAGE52_I91@PURE_QUANTA.SOCKET4677_AZIF0045P001C01CS(CHIPS)':
 'DDR1_SA_DQS_DP9': CDS_PINID='DDR1_SA_DQS_DP9';
NODE_NAME     J19 201
 '@S9S_MB_2U_LIB.S9S_MB_2U(SCH_1):PAGE100_I178@PURE_QUANTA.SCONN288_ADR50017P130CC(CHIPS)':
 'DQS9_A_T||TDQS9_A_T': CDS_PINID='\dqs9_a_t||tdqs9_a_t\';
NODE_NAME     J20 201
 '@S9S_MB_2U_LIB.S9S_MB_2U(SCH_1):PAGE101_I178@PURE_QUANTA.SCONN288_ADR50017P087CC(CHIPS)':
 'DQS9_A_T||TDQS9_A_T': CDS_PINID='\dqs9_a_t||tdqs9_a_t\';
NET_NAME
'M_B_CPU1_SA_PAR'
 '@S9S_MB_2U_LIB.S9S_MB_2U(SCH_1):M_B_CPU1_SA_PAR':
 C_SIGNAL='@s9s_mb_2u_lib.s9s_mb_2u(sch_1):m_b_cpu1_sa_par';
NODE_NAME     U1 W43
 '@S9S_MB_2U_LIB.S9S_MB_2U(SCH_1):PAGE52_I91@PURE_QUANTA.SOCKET4677_AZIF0045P001C01CS(CHIPS)':
 'DDR1_SA_PAR': CDS_PINID='DDR1_SA_PAR';
NODE_NAME     J19 74
 '@S9S_MB_2U_LIB.S9S_MB_2U(SCH_1):PAGE100_I25@PURE_QUANTA.SCONN288_ADR50017P130CC(CHIPS)':
 'PAR_A': CDS_PINID='PAR_A';
NODE_NAME     J20 74
 '@S9S_MB_2U_LIB.S9S_MB_2U(SCH_1):PAGE101_I47@PURE_QUANTA.SCONN288_ADR50017P087CC(CHIPS)':
 'PAR_A': CDS_PINID='PAR_A';
NET_NAME
'M_B_CPU1_SA_RSP<0>'
 '@S9S_MB_2U_LIB.S9S_MB_2U(SCH_1):M_B_CPU1_SA_RSP'<0>:
 C_SIGNAL='@s9s_mb_2u_lib.s9s_mb_2u(sch_1):m_b_cpu1_sa_rsp(0)';
NODE_NAME     U1 AL48
 '@S9S_MB_2U_LIB.S9S_MB_2U(SCH_1):PAGE52_I91@PURE_QUANTA.SOCKET4677_AZIF0045P001C01CS(CHIPS)':
 'DDR1_A_RSP0': CDS_PINID='DDR1_A_RSP0';
NODE_NAME     J19 86
 '@S9S_MB_2U_LIB.S9S_MB_2U(SCH_1):PAGE100_I25@PURE_QUANTA.SCONN288_ADR50017P130CC(CHIPS)':
 'LBD||RSP_A_N': CDS_PINID='\lbd||rsp_a_n\';
NET_NAME
'M_B_CPU1_SA_RSP<1>'
 '@S9S_MB_2U_LIB.S9S_MB_2U(SCH_1):M_B_CPU1_SA_RSP'<1>:
 C_SIGNAL='@s9s_mb_2u_lib.s9s_mb_2u(sch_1):m_b_cpu1_sa_rsp(1)';
NODE_NAME     U1 AK47
 '@S9S_MB_2U_LIB.S9S_MB_2U(SCH_1):PAGE52_I91@PURE_QUANTA.SOCKET4677_AZIF0045P001C01CS(CHIPS)':
 'DDR1_A_RSP1': CDS_PINID='DDR1_A_RSP1';
NODE_NAME     J20 86
 '@S9S_MB_2U_LIB.S9S_MB_2U(SCH_1):PAGE101_I47@PURE_QUANTA.SCONN288_ADR50017P087CC(CHIPS)':
 'LBD||RSP_A_N': CDS_PINID='\lbd||rsp_a_n\';
NET_NAME
'M_B_CPU1_SB_CA<0>'
 '@S9S_MB_2U_LIB.S9S_MB_2U(SCH_1):M_B_CPU1_SB_CA'<0>:
 C_SIGNAL='@s9s_mb_2u_lib.s9s_mb_2u(sch_1):m_b_cpu1_sb_ca(0)';
NODE_NAME     U1 T44
 '@S9S_MB_2U_LIB.S9S_MB_2U(SCH_1):PAGE52_I91@PURE_QUANTA.SOCKET4677_AZIF0045P001C01CS(CHIPS)':
 'DDR1_SB_CA0': CDS_PINID='DDR1_SB_CA0';
NODE_NAME     J19 76
 '@S9S_MB_2U_LIB.S9S_MB_2U(SCH_1):PAGE100_I25@PURE_QUANTA.SCONN288_ADR50017P130CC(CHIPS)':
 'CA0_B': CDS_PINID='CA0_B';
NODE_NAME     J20 76
 '@S9S_MB_2U_LIB.S9S_MB_2U(SCH_1):PAGE101_I47@PURE_QUANTA.SCONN288_ADR50017P087CC(CHIPS)':
 'CA0_B': CDS_PINID='CA0_B';
NET_NAME
'M_B_CPU1_SB_CA<1>'
 '@S9S_MB_2U_LIB.S9S_MB_2U(SCH_1):M_B_CPU1_SB_CA'<1>:
 C_SIGNAL='@s9s_mb_2u_lib.s9s_mb_2u(sch_1):m_b_cpu1_sb_ca(1)';
NODE_NAME     U1 U43
 '@S9S_MB_2U_LIB.S9S_MB_2U(SCH_1):PAGE52_I91@PURE_QUANTA.SOCKET4677_AZIF0045P001C01CS(CHIPS)':
 'DDR1_SB_CA1': CDS_PINID='DDR1_SB_CA1';
NODE_NAME     J19 221
 '@S9S_MB_2U_LIB.S9S_MB_2U(SCH_1):PAGE100_I25@PURE_QUANTA.SCONN288_ADR50017P130CC(CHIPS)':
 'CA1_B': CDS_PINID='CA1_B';
NODE_NAME     J20 221
 '@S9S_MB_2U_LIB.S9S_MB_2U(SCH_1):PAGE101_I47@PURE_QUANTA.SCONN288_ADR50017P087CC(CHIPS)':
 'CA1_B': CDS_PINID='CA1_B';
NET_NAME
'M_B_CPU1_SB_CA<2>'
 '@S9S_MB_2U_LIB.S9S_MB_2U(SCH_1):M_B_CPU1_SB_CA'<2>:
 C_SIGNAL='@s9s_mb_2u_lib.s9s_mb_2u(sch_1):m_b_cpu1_sb_ca(2)';
NODE_NAME     U1 K44
 '@S9S_MB_2U_LIB.S9S_MB_2U(SCH_1):PAGE52_I91@PURE_QUANTA.SOCKET4677_AZIF0045P001C01CS(CHIPS)':
 'DDR1_SB_CA2': CDS_PINID='DDR1_SB_CA2';
NODE_NAME     J19 78
 '@S9S_MB_2U_LIB.S9S_MB_2U(SCH_1):PAGE100_I25@PURE_QUANTA.SCONN288_ADR50017P130CC(CHIPS)':
 'CA2_B': CDS_PINID='CA2_B';
NODE_NAME     J20 78
 '@S9S_MB_2U_LIB.S9S_MB_2U(SCH_1):PAGE101_I47@PURE_QUANTA.SCONN288_ADR50017P087CC(CHIPS)':
 'CA2_B': CDS_PINID='CA2_B';
NET_NAME
'M_B_CPU1_SB_CA<3>'
 '@S9S_MB_2U_LIB.S9S_MB_2U(SCH_1):M_B_CPU1_SB_CA'<3>:
 C_SIGNAL='@s9s_mb_2u_lib.s9s_mb_2u(sch_1):m_b_cpu1_sb_ca(3)';
NODE_NAME     U1 M44
 '@S9S_MB_2U_LIB.S9S_MB_2U(SCH_1):PAGE52_I91@PURE_QUANTA.SOCKET4677_AZIF0045P001C01CS(CHIPS)':
 'DDR1_SB_CA3': CDS_PINID='DDR1_SB_CA3';
NODE_NAME     J19 223
 '@S9S_MB_2U_LIB.S9S_MB_2U(SCH_1):PAGE100_I25@PURE_QUANTA.SCONN288_ADR50017P130CC(CHIPS)':
 'CA3_B': CDS_PINID='CA3_B';
NODE_NAME     J20 223
 '@S9S_MB_2U_LIB.S9S_MB_2U(SCH_1):PAGE101_I47@PURE_QUANTA.SCONN288_ADR50017P087CC(CHIPS)':
 'CA3_B': CDS_PINID='CA3_B';
NET_NAME
'M_B_CPU1_SB_CA<4>'
 '@S9S_MB_2U_LIB.S9S_MB_2U(SCH_1):M_B_CPU1_SB_CA'<4>:
 C_SIGNAL='@s9s_mb_2u_lib.s9s_mb_2u(sch_1):m_b_cpu1_sb_ca(4)';
NODE_NAME     U1 J43
 '@S9S_MB_2U_LIB.S9S_MB_2U(SCH_1):PAGE52_I91@PURE_QUANTA.SOCKET4677_AZIF0045P001C01CS(CHIPS)':
 'DDR1_SB_CA4': CDS_PINID='DDR1_SB_CA4';
NODE_NAME     J19 80
 '@S9S_MB_2U_LIB.S9S_MB_2U(SCH_1):PAGE100_I25@PURE_QUANTA.SCONN288_ADR50017P130CC(CHIPS)':
 'CA4_B': CDS_PINID='CA4_B';
NODE_NAME     J20 80
 '@S9S_MB_2U_LIB.S9S_MB_2U(SCH_1):PAGE101_I47@PURE_QUANTA.SCONN288_ADR50017P087CC(CHIPS)':
 'CA4_B': CDS_PINID='CA4_B';
NET_NAME
'M_B_CPU1_SB_CA<5>'
 '@S9S_MB_2U_LIB.S9S_MB_2U(SCH_1):M_B_CPU1_SB_CA'<5>:
 C_SIGNAL='@s9s_mb_2u_lib.s9s_mb_2u(sch_1):m_b_cpu1_sb_ca(5)';
NODE_NAME     U1 N43
 '@S9S_MB_2U_LIB.S9S_MB_2U(SCH_1):PAGE52_I91@PURE_QUANTA.SOCKET4677_AZIF0045P001C01CS(CHIPS)':
 'DDR1_SB_CA5': CDS_PINID='DDR1_SB_CA5';
NODE_NAME     J19 225
 '@S9S_MB_2U_LIB.S9S_MB_2U(SCH_1):PAGE100_I25@PURE_QUANTA.SCONN288_ADR50017P130CC(CHIPS)':
 'CA5_B': CDS_PINID='CA5_B';
NODE_NAME     J20 225
 '@S9S_MB_2U_LIB.S9S_MB_2U(SCH_1):PAGE101_I47@PURE_QUANTA.SCONN288_ADR50017P087CC(CHIPS)':
 'CA5_B': CDS_PINID='CA5_B';
NET_NAME
'M_B_CPU1_SB_CA<6>'
 '@S9S_MB_2U_LIB.S9S_MB_2U(SCH_1):M_B_CPU1_SB_CA'<6>:
 C_SIGNAL='@s9s_mb_2u_lib.s9s_mb_2u(sch_1):m_b_cpu1_sb_ca(6)';
NODE_NAME     U1 H42
 '@S9S_MB_2U_LIB.S9S_MB_2U(SCH_1):PAGE52_I91@PURE_QUANTA.SOCKET4677_AZIF0045P001C01CS(CHIPS)':
 'DDR1_SB_CA6': CDS_PINID='DDR1_SB_CA6';
NODE_NAME     J19 82
 '@S9S_MB_2U_LIB.S9S_MB_2U(SCH_1):PAGE100_I25@PURE_QUANTA.SCONN288_ADR50017P130CC(CHIPS)':
 'CA6_B': CDS_PINID='CA6_B';
NODE_NAME     J20 82
 '@S9S_MB_2U_LIB.S9S_MB_2U(SCH_1):PAGE101_I47@PURE_QUANTA.SCONN288_ADR50017P087CC(CHIPS)':
 'CA6_B': CDS_PINID='CA6_B';
NET_NAME
'M_B_CPU1_SB_CB<0>'
 '@S9S_MB_2U_LIB.S9S_MB_2U(SCH_1):M_B_CPU1_SB_CB'<0>:
 C_SIGNAL='@s9s_mb_2u_lib.s9s_mb_2u(sch_1):m_b_cpu1_sb_cb(0)';
NODE_NAME     U1 J35
 '@S9S_MB_2U_LIB.S9S_MB_2U(SCH_1):PAGE52_I91@PURE_QUANTA.SOCKET4677_AZIF0045P001C01CS(CHIPS)':
 'DDR1_SB_ECC0': CDS_PINID='DDR1_SB_ECC0';
NODE_NAME     J19 96
 '@S9S_MB_2U_LIB.S9S_MB_2U(SCH_1):PAGE100_I25@PURE_QUANTA.SCONN288_ADR50017P130CC(CHIPS)':
 'CB0_B': CDS_PINID='CB0_B';
NODE_NAME     J20 96
 '@S9S_MB_2U_LIB.S9S_MB_2U(SCH_1):PAGE101_I47@PURE_QUANTA.SCONN288_ADR50017P087CC(CHIPS)':
 'CB0_B': CDS_PINID='CB0_B';
NET_NAME
'M_B_CPU1_SB_CB<1>'
 '@S9S_MB_2U_LIB.S9S_MB_2U(SCH_1):M_B_CPU1_SB_CB'<1>:
 C_SIGNAL='@s9s_mb_2u_lib.s9s_mb_2u(sch_1):m_b_cpu1_sb_cb(1)';
NODE_NAME     U1 K34
 '@S9S_MB_2U_LIB.S9S_MB_2U(SCH_1):PAGE52_I91@PURE_QUANTA.SOCKET4677_AZIF0045P001C01CS(CHIPS)':
 'DDR1_SB_ECC1': CDS_PINID='DDR1_SB_ECC1';
NODE_NAME     J19 98
 '@S9S_MB_2U_LIB.S9S_MB_2U(SCH_1):PAGE100_I25@PURE_QUANTA.SCONN288_ADR50017P130CC(CHIPS)':
 'CB1_B': CDS_PINID='CB1_B';
NODE_NAME     J20 98
 '@S9S_MB_2U_LIB.S9S_MB_2U(SCH_1):PAGE101_I47@PURE_QUANTA.SCONN288_ADR50017P087CC(CHIPS)':
 'CB1_B': CDS_PINID='CB1_B';
NET_NAME
'M_B_CPU1_SB_CB<2>'
 '@S9S_MB_2U_LIB.S9S_MB_2U(SCH_1):M_B_CPU1_SB_CB'<2>:
 C_SIGNAL='@s9s_mb_2u_lib.s9s_mb_2u(sch_1):m_b_cpu1_sb_cb(2)';
NODE_NAME     U1 N35
 '@S9S_MB_2U_LIB.S9S_MB_2U(SCH_1):PAGE52_I91@PURE_QUANTA.SOCKET4677_AZIF0045P001C01CS(CHIPS)':
 'DDR1_SB_ECC2': CDS_PINID='DDR1_SB_ECC2';
NODE_NAME     J19 241
 '@S9S_MB_2U_LIB.S9S_MB_2U(SCH_1):PAGE100_I25@PURE_QUANTA.SCONN288_ADR50017P130CC(CHIPS)':
 'CB2_B': CDS_PINID='CB2_B';
NODE_NAME     J20 241
 '@S9S_MB_2U_LIB.S9S_MB_2U(SCH_1):PAGE101_I47@PURE_QUANTA.SCONN288_ADR50017P087CC(CHIPS)':
 'CB2_B': CDS_PINID='CB2_B';
NET_NAME
'M_B_CPU1_SB_CB<3>'
 '@S9S_MB_2U_LIB.S9S_MB_2U(SCH_1):M_B_CPU1_SB_CB'<3>:
 C_SIGNAL='@s9s_mb_2u_lib.s9s_mb_2u(sch_1):m_b_cpu1_sb_cb(3)';
NODE_NAME     U1 M34
 '@S9S_MB_2U_LIB.S9S_MB_2U(SCH_1):PAGE52_I91@PURE_QUANTA.SOCKET4677_AZIF0045P001C01CS(CHIPS)':
 'DDR1_SB_ECC3': CDS_PINID='DDR1_SB_ECC3';
NODE_NAME     J19 243
 '@S9S_MB_2U_LIB.S9S_MB_2U(SCH_1):PAGE100_I25@PURE_QUANTA.SCONN288_ADR50017P130CC(CHIPS)':
 'CB3_B': CDS_PINID='CB3_B';
NODE_NAME     J20 243
 '@S9S_MB_2U_LIB.S9S_MB_2U(SCH_1):PAGE101_I47@PURE_QUANTA.SCONN288_ADR50017P087CC(CHIPS)':
 'CB3_B': CDS_PINID='CB3_B';
NET_NAME
'M_B_CPU1_SB_CB<4>'
 '@S9S_MB_2U_LIB.S9S_MB_2U(SCH_1):M_B_CPU1_SB_CB'<4>:
 C_SIGNAL='@s9s_mb_2u_lib.s9s_mb_2u(sch_1):m_b_cpu1_sb_cb(4)';
NODE_NAME     U1 K38
 '@S9S_MB_2U_LIB.S9S_MB_2U(SCH_1):PAGE52_I91@PURE_QUANTA.SOCKET4677_AZIF0045P001C01CS(CHIPS)':
 'DDR1_SB_ECC4': CDS_PINID='DDR1_SB_ECC4';
NODE_NAME     J19 89
 '@S9S_MB_2U_LIB.S9S_MB_2U(SCH_1):PAGE100_I25@PURE_QUANTA.SCONN288_ADR50017P130CC(CHIPS)':
 'CB4_B': CDS_PINID='CB4_B';
NODE_NAME     J20 89
 '@S9S_MB_2U_LIB.S9S_MB_2U(SCH_1):PAGE101_I47@PURE_QUANTA.SCONN288_ADR50017P087CC(CHIPS)':
 'CB4_B': CDS_PINID='CB4_B';
NET_NAME
'M_B_CPU1_SB_CB<5>'
 '@S9S_MB_2U_LIB.S9S_MB_2U(SCH_1):M_B_CPU1_SB_CB'<5>:
 C_SIGNAL='@s9s_mb_2u_lib.s9s_mb_2u(sch_1):m_b_cpu1_sb_cb(5)';
NODE_NAME     U1 J37
 '@S9S_MB_2U_LIB.S9S_MB_2U(SCH_1):PAGE52_I91@PURE_QUANTA.SOCKET4677_AZIF0045P001C01CS(CHIPS)':
 'DDR1_SB_ECC5': CDS_PINID='DDR1_SB_ECC5';
NODE_NAME     J19 91
 '@S9S_MB_2U_LIB.S9S_MB_2U(SCH_1):PAGE100_I25@PURE_QUANTA.SCONN288_ADR50017P130CC(CHIPS)':
 'CB5_B': CDS_PINID='CB5_B';
NODE_NAME     J20 91
 '@S9S_MB_2U_LIB.S9S_MB_2U(SCH_1):PAGE101_I47@PURE_QUANTA.SCONN288_ADR50017P087CC(CHIPS)':
 'CB5_B': CDS_PINID='CB5_B';
NET_NAME
'M_B_CPU1_SB_CB<6>'
 '@S9S_MB_2U_LIB.S9S_MB_2U(SCH_1):M_B_CPU1_SB_CB'<6>:
 C_SIGNAL='@s9s_mb_2u_lib.s9s_mb_2u(sch_1):m_b_cpu1_sb_cb(6)';
NODE_NAME     U1 M38
 '@S9S_MB_2U_LIB.S9S_MB_2U(SCH_1):PAGE52_I91@PURE_QUANTA.SOCKET4677_AZIF0045P001C01CS(CHIPS)':
 'DDR1_SB_ECC6': CDS_PINID='DDR1_SB_ECC6';
NODE_NAME     J19 234
 '@S9S_MB_2U_LIB.S9S_MB_2U(SCH_1):PAGE100_I25@PURE_QUANTA.SCONN288_ADR50017P130CC(CHIPS)':
 'CB6_B': CDS_PINID='CB6_B';
NODE_NAME     J20 234
 '@S9S_MB_2U_LIB.S9S_MB_2U(SCH_1):PAGE101_I47@PURE_QUANTA.SCONN288_ADR50017P087CC(CHIPS)':
 'CB6_B': CDS_PINID='CB6_B';
NET_NAME
'M_B_CPU1_SB_CB<7>'
 '@S9S_MB_2U_LIB.S9S_MB_2U(SCH_1):M_B_CPU1_SB_CB'<7>:
 C_SIGNAL='@s9s_mb_2u_lib.s9s_mb_2u(sch_1):m_b_cpu1_sb_cb(7)';
NODE_NAME     U1 N37
 '@S9S_MB_2U_LIB.S9S_MB_2U(SCH_1):PAGE52_I91@PURE_QUANTA.SOCKET4677_AZIF0045P001C01CS(CHIPS)':
 'DDR1_SB_ECC7': CDS_PINID='DDR1_SB_ECC7';
NODE_NAME     J19 236
 '@S9S_MB_2U_LIB.S9S_MB_2U(SCH_1):PAGE100_I25@PURE_QUANTA.SCONN288_ADR50017P130CC(CHIPS)':
 'CB7_B': CDS_PINID='CB7_B';
NODE_NAME     J20 236
 '@S9S_MB_2U_LIB.S9S_MB_2U(SCH_1):PAGE101_I47@PURE_QUANTA.SCONN288_ADR50017P087CC(CHIPS)':
 'CB7_B': CDS_PINID='CB7_B';
NET_NAME
'M_B_CPU1_SB_CS_N<0>'
 '@S9S_MB_2U_LIB.S9S_MB_2U(SCH_1):M_B_CPU1_SB_CS_N'<0>:
 C_SIGNAL='@s9s_mb_2u_lib.s9s_mb_2u(sch_1):m_b_cpu1_sb_cs_n(0)';
NODE_NAME     U1 J41
 '@S9S_MB_2U_LIB.S9S_MB_2U(SCH_1):PAGE52_I91@PURE_QUANTA.SOCKET4677_AZIF0045P001C01CS(CHIPS)':
 'DDR1_SB_CS_N0': CDS_PINID='DDR1_SB_CS_N0';
NODE_NAME     J19 84
 '@S9S_MB_2U_LIB.S9S_MB_2U(SCH_1):PAGE100_I25@PURE_QUANTA.SCONN288_ADR50017P130CC(CHIPS)':
 'CS0_B_N': CDS_PINID='CS0_B_N';
NET_NAME
'M_B_CPU1_SB_CS_N<1>'
 '@S9S_MB_2U_LIB.S9S_MB_2U(SCH_1):M_B_CPU1_SB_CS_N'<1>:
 C_SIGNAL='@s9s_mb_2u_lib.s9s_mb_2u(sch_1):m_b_cpu1_sb_cs_n(1)';
NODE_NAME     U1 K40
 '@S9S_MB_2U_LIB.S9S_MB_2U(SCH_1):PAGE52_I91@PURE_QUANTA.SOCKET4677_AZIF0045P001C01CS(CHIPS)':
 'DDR1_SB_CS_N1': CDS_PINID='DDR1_SB_CS_N1';
NODE_NAME     J19 229
 '@S9S_MB_2U_LIB.S9S_MB_2U(SCH_1):PAGE100_I25@PURE_QUANTA.SCONN288_ADR50017P130CC(CHIPS)':
 'CS1_B_N': CDS_PINID='CS1_B_N';
NET_NAME
'M_B_CPU1_SB_CS_N<2>'
 '@S9S_MB_2U_LIB.S9S_MB_2U(SCH_1):M_B_CPU1_SB_CS_N'<2>:
 C_SIGNAL='@s9s_mb_2u_lib.s9s_mb_2u(sch_1):m_b_cpu1_sb_cs_n(2)';
NODE_NAME     U1 N41
 '@S9S_MB_2U_LIB.S9S_MB_2U(SCH_1):PAGE52_I91@PURE_QUANTA.SOCKET4677_AZIF0045P001C01CS(CHIPS)':
 'DDR1_SB_CS_N2': CDS_PINID='DDR1_SB_CS_N2';
NODE_NAME     J20 84
 '@S9S_MB_2U_LIB.S9S_MB_2U(SCH_1):PAGE101_I47@PURE_QUANTA.SCONN288_ADR50017P087CC(CHIPS)':
 'CS0_B_N': CDS_PINID='CS0_B_N';
NET_NAME
'M_B_CPU1_SB_CS_N<3>'
 '@S9S_MB_2U_LIB.S9S_MB_2U(SCH_1):M_B_CPU1_SB_CS_N'<3>:
 C_SIGNAL='@s9s_mb_2u_lib.s9s_mb_2u(sch_1):m_b_cpu1_sb_cs_n(3)';
NODE_NAME     U1 M40
 '@S9S_MB_2U_LIB.S9S_MB_2U(SCH_1):PAGE52_I91@PURE_QUANTA.SOCKET4677_AZIF0045P001C01CS(CHIPS)':
 'DDR1_SB_CS_N3': CDS_PINID='DDR1_SB_CS_N3';
NODE_NAME     J20 229
 '@S9S_MB_2U_LIB.S9S_MB_2U(SCH_1):PAGE101_I47@PURE_QUANTA.SCONN288_ADR50017P087CC(CHIPS)':
 'CS1_B_N': CDS_PINID='CS1_B_N';
NET_NAME
'M_B_CPU1_SB_DQ<0>'
 '@S9S_MB_2U_LIB.S9S_MB_2U(SCH_1):M_B_CPU1_SB_DQ'<0>:
 C_SIGNAL='@s9s_mb_2u_lib.s9s_mb_2u(sch_1):m_b_cpu1_sb_dq(0)';
NODE_NAME     U1 U29
 '@S9S_MB_2U_LIB.S9S_MB_2U(SCH_1):PAGE52_I91@PURE_QUANTA.SOCKET4677_AZIF0045P001C01CS(CHIPS)':
 'DDR1_SB_DQ0': CDS_PINID='DDR1_SB_DQ0';
NODE_NAME     J19 100
 '@S9S_MB_2U_LIB.S9S_MB_2U(SCH_1):PAGE100_I25@PURE_QUANTA.SCONN288_ADR50017P130CC(CHIPS)':
 'DQ0_B': CDS_PINID='DQ0_B';
NODE_NAME     J20 100
 '@S9S_MB_2U_LIB.S9S_MB_2U(SCH_1):PAGE101_I47@PURE_QUANTA.SCONN288_ADR50017P087CC(CHIPS)':
 'DQ0_B': CDS_PINID='DQ0_B';
NET_NAME
'M_B_CPU1_SB_DQ<10>'
 '@S9S_MB_2U_LIB.S9S_MB_2U(SCH_1):M_B_CPU1_SB_DQ'<10>:
 C_SIGNAL='@s9s_mb_2u_lib.s9s_mb_2u(sch_1):m_b_cpu1_sb_dq(10)';
NODE_NAME     U1 M26
 '@S9S_MB_2U_LIB.S9S_MB_2U(SCH_1):PAGE52_I91@PURE_QUANTA.SOCKET4677_AZIF0045P001C01CS(CHIPS)':
 'DDR1_SB_DQ10': CDS_PINID='DDR1_SB_DQ10';
NODE_NAME     J19 256
 '@S9S_MB_2U_LIB.S9S_MB_2U(SCH_1):PAGE100_I25@PURE_QUANTA.SCONN288_ADR50017P130CC(CHIPS)':
 'DQ10_B': CDS_PINID='DQ10_B';
NODE_NAME     J20 256
 '@S9S_MB_2U_LIB.S9S_MB_2U(SCH_1):PAGE101_I47@PURE_QUANTA.SCONN288_ADR50017P087CC(CHIPS)':
 'DQ10_B': CDS_PINID='DQ10_B';
NET_NAME
'M_B_CPU1_SB_DQ<11>'
 '@S9S_MB_2U_LIB.S9S_MB_2U(SCH_1):M_B_CPU1_SB_DQ'<11>:
 C_SIGNAL='@s9s_mb_2u_lib.s9s_mb_2u(sch_1):m_b_cpu1_sb_dq(11)';
NODE_NAME     U1 N25
 '@S9S_MB_2U_LIB.S9S_MB_2U(SCH_1):PAGE52_I91@PURE_QUANTA.SOCKET4677_AZIF0045P001C01CS(CHIPS)':
 'DDR1_SB_DQ11': CDS_PINID='DDR1_SB_DQ11';
NODE_NAME     J19 258
 '@S9S_MB_2U_LIB.S9S_MB_2U(SCH_1):PAGE100_I25@PURE_QUANTA.SCONN288_ADR50017P130CC(CHIPS)':
 'DQ11_B': CDS_PINID='DQ11_B';
NODE_NAME     J20 258
 '@S9S_MB_2U_LIB.S9S_MB_2U(SCH_1):PAGE101_I47@PURE_QUANTA.SCONN288_ADR50017P087CC(CHIPS)':
 'DQ11_B': CDS_PINID='DQ11_B';
NET_NAME
'M_B_CPU1_SB_DQ<12>'
 '@S9S_MB_2U_LIB.S9S_MB_2U(SCH_1):M_B_CPU1_SB_DQ'<12>:
 C_SIGNAL='@s9s_mb_2u_lib.s9s_mb_2u(sch_1):m_b_cpu1_sb_dq(12)';
NODE_NAME     U1 J23
 '@S9S_MB_2U_LIB.S9S_MB_2U(SCH_1):PAGE52_I91@PURE_QUANTA.SOCKET4677_AZIF0045P001C01CS(CHIPS)':
 'DDR1_SB_DQ12': CDS_PINID='DDR1_SB_DQ12';
NODE_NAME     J19 118
 '@S9S_MB_2U_LIB.S9S_MB_2U(SCH_1):PAGE100_I25@PURE_QUANTA.SCONN288_ADR50017P130CC(CHIPS)':
 'DQ12_B': CDS_PINID='DQ12_B';
NODE_NAME     J20 118
 '@S9S_MB_2U_LIB.S9S_MB_2U(SCH_1):PAGE101_I47@PURE_QUANTA.SCONN288_ADR50017P087CC(CHIPS)':
 'DQ12_B': CDS_PINID='DQ12_B';
NET_NAME
'M_B_CPU1_SB_DQ<13>'
 '@S9S_MB_2U_LIB.S9S_MB_2U(SCH_1):M_B_CPU1_SB_DQ'<13>:
 C_SIGNAL='@s9s_mb_2u_lib.s9s_mb_2u(sch_1):m_b_cpu1_sb_dq(13)';
NODE_NAME     U1 K22
 '@S9S_MB_2U_LIB.S9S_MB_2U(SCH_1):PAGE52_I91@PURE_QUANTA.SOCKET4677_AZIF0045P001C01CS(CHIPS)':
 'DDR1_SB_DQ13': CDS_PINID='DDR1_SB_DQ13';
NODE_NAME     J19 120
 '@S9S_MB_2U_LIB.S9S_MB_2U(SCH_1):PAGE100_I25@PURE_QUANTA.SCONN288_ADR50017P130CC(CHIPS)':
 'DQ13_B': CDS_PINID='DQ13_B';
NODE_NAME     J20 120
 '@S9S_MB_2U_LIB.S9S_MB_2U(SCH_1):PAGE101_I47@PURE_QUANTA.SCONN288_ADR50017P087CC(CHIPS)':
 'DQ13_B': CDS_PINID='DQ13_B';
NET_NAME
'M_B_CPU1_SB_DQ<14>'
 '@S9S_MB_2U_LIB.S9S_MB_2U(SCH_1):M_B_CPU1_SB_DQ'<14>:
 C_SIGNAL='@s9s_mb_2u_lib.s9s_mb_2u(sch_1):m_b_cpu1_sb_dq(14)';
NODE_NAME     U1 N23
 '@S9S_MB_2U_LIB.S9S_MB_2U(SCH_1):PAGE52_I91@PURE_QUANTA.SOCKET4677_AZIF0045P001C01CS(CHIPS)':
 'DDR1_SB_DQ14': CDS_PINID='DDR1_SB_DQ14';
NODE_NAME     J19 263
 '@S9S_MB_2U_LIB.S9S_MB_2U(SCH_1):PAGE100_I25@PURE_QUANTA.SCONN288_ADR50017P130CC(CHIPS)':
 'DQ14_B': CDS_PINID='DQ14_B';
NODE_NAME     J20 263
 '@S9S_MB_2U_LIB.S9S_MB_2U(SCH_1):PAGE101_I47@PURE_QUANTA.SCONN288_ADR50017P087CC(CHIPS)':
 'DQ14_B': CDS_PINID='DQ14_B';
NET_NAME
'M_B_CPU1_SB_DQ<15>'
 '@S9S_MB_2U_LIB.S9S_MB_2U(SCH_1):M_B_CPU1_SB_DQ'<15>:
 C_SIGNAL='@s9s_mb_2u_lib.s9s_mb_2u(sch_1):m_b_cpu1_sb_dq(15)';
NODE_NAME     U1 M22
 '@S9S_MB_2U_LIB.S9S_MB_2U(SCH_1):PAGE52_I91@PURE_QUANTA.SOCKET4677_AZIF0045P001C01CS(CHIPS)':
 'DDR1_SB_DQ15': CDS_PINID='DDR1_SB_DQ15';
NODE_NAME     J19 265
 '@S9S_MB_2U_LIB.S9S_MB_2U(SCH_1):PAGE100_I25@PURE_QUANTA.SCONN288_ADR50017P130CC(CHIPS)':
 'DQ15_B': CDS_PINID='DQ15_B';
NODE_NAME     J20 265
 '@S9S_MB_2U_LIB.S9S_MB_2U(SCH_1):PAGE101_I47@PURE_QUANTA.SCONN288_ADR50017P087CC(CHIPS)':
 'DQ15_B': CDS_PINID='DQ15_B';
NET_NAME
'M_B_CPU1_SB_DQ<16>'
 '@S9S_MB_2U_LIB.S9S_MB_2U(SCH_1):M_B_CPU1_SB_DQ'<16>:
 C_SIGNAL='@s9s_mb_2u_lib.s9s_mb_2u(sch_1):m_b_cpu1_sb_dq(16)';
NODE_NAME     U1 K20
 '@S9S_MB_2U_LIB.S9S_MB_2U(SCH_1):PAGE52_I91@PURE_QUANTA.SOCKET4677_AZIF0045P001C01CS(CHIPS)':
 'DDR1_SB_DQ16': CDS_PINID='DDR1_SB_DQ16';
NODE_NAME     J19 122
 '@S9S_MB_2U_LIB.S9S_MB_2U(SCH_1):PAGE100_I25@PURE_QUANTA.SCONN288_ADR50017P130CC(CHIPS)':
 'DQ16_B': CDS_PINID='DQ16_B';
NODE_NAME     J20 122
 '@S9S_MB_2U_LIB.S9S_MB_2U(SCH_1):PAGE101_I47@PURE_QUANTA.SCONN288_ADR50017P087CC(CHIPS)':
 'DQ16_B': CDS_PINID='DQ16_B';
NET_NAME
'M_B_CPU1_SB_DQ<17>'
 '@S9S_MB_2U_LIB.S9S_MB_2U(SCH_1):M_B_CPU1_SB_DQ'<17>:
 C_SIGNAL='@s9s_mb_2u_lib.s9s_mb_2u(sch_1):m_b_cpu1_sb_dq(17)';
NODE_NAME     U1 J19
 '@S9S_MB_2U_LIB.S9S_MB_2U(SCH_1):PAGE52_I91@PURE_QUANTA.SOCKET4677_AZIF0045P001C01CS(CHIPS)':
 'DDR1_SB_DQ17': CDS_PINID='DDR1_SB_DQ17';
NODE_NAME     J19 124
 '@S9S_MB_2U_LIB.S9S_MB_2U(SCH_1):PAGE100_I25@PURE_QUANTA.SCONN288_ADR50017P130CC(CHIPS)':
 'DQ17_B': CDS_PINID='DQ17_B';
NODE_NAME     J20 124
 '@S9S_MB_2U_LIB.S9S_MB_2U(SCH_1):PAGE101_I47@PURE_QUANTA.SCONN288_ADR50017P087CC(CHIPS)':
 'DQ17_B': CDS_PINID='DQ17_B';
NET_NAME
'M_B_CPU1_SB_DQ<18>'
 '@S9S_MB_2U_LIB.S9S_MB_2U(SCH_1):M_B_CPU1_SB_DQ'<18>:
 C_SIGNAL='@s9s_mb_2u_lib.s9s_mb_2u(sch_1):m_b_cpu1_sb_dq(18)';
NODE_NAME     U1 M20
 '@S9S_MB_2U_LIB.S9S_MB_2U(SCH_1):PAGE52_I91@PURE_QUANTA.SOCKET4677_AZIF0045P001C01CS(CHIPS)':
 'DDR1_SB_DQ18': CDS_PINID='DDR1_SB_DQ18';
NODE_NAME     J19 267
 '@S9S_MB_2U_LIB.S9S_MB_2U(SCH_1):PAGE100_I25@PURE_QUANTA.SCONN288_ADR50017P130CC(CHIPS)':
 'DQ18_B': CDS_PINID='DQ18_B';
NODE_NAME     J20 267
 '@S9S_MB_2U_LIB.S9S_MB_2U(SCH_1):PAGE101_I47@PURE_QUANTA.SCONN288_ADR50017P087CC(CHIPS)':
 'DQ18_B': CDS_PINID='DQ18_B';
NET_NAME
'M_B_CPU1_SB_DQ<19>'
 '@S9S_MB_2U_LIB.S9S_MB_2U(SCH_1):M_B_CPU1_SB_DQ'<19>:
 C_SIGNAL='@s9s_mb_2u_lib.s9s_mb_2u(sch_1):m_b_cpu1_sb_dq(19)';
NODE_NAME     U1 N19
 '@S9S_MB_2U_LIB.S9S_MB_2U(SCH_1):PAGE52_I91@PURE_QUANTA.SOCKET4677_AZIF0045P001C01CS(CHIPS)':
 'DDR1_SB_DQ19': CDS_PINID='DDR1_SB_DQ19';
NODE_NAME     J19 269
 '@S9S_MB_2U_LIB.S9S_MB_2U(SCH_1):PAGE100_I25@PURE_QUANTA.SCONN288_ADR50017P130CC(CHIPS)':
 'DQ19_B': CDS_PINID='DQ19_B';
NODE_NAME     J20 269
 '@S9S_MB_2U_LIB.S9S_MB_2U(SCH_1):PAGE101_I47@PURE_QUANTA.SCONN288_ADR50017P087CC(CHIPS)':
 'DQ19_B': CDS_PINID='DQ19_B';
NET_NAME
'M_B_CPU1_SB_DQ<1>'
 '@S9S_MB_2U_LIB.S9S_MB_2U(SCH_1):M_B_CPU1_SB_DQ'<1>:
 C_SIGNAL='@s9s_mb_2u_lib.s9s_mb_2u(sch_1):m_b_cpu1_sb_dq(1)';
NODE_NAME     U1 T28
 '@S9S_MB_2U_LIB.S9S_MB_2U(SCH_1):PAGE52_I91@PURE_QUANTA.SOCKET4677_AZIF0045P001C01CS(CHIPS)':
 'DDR1_SB_DQ1': CDS_PINID='DDR1_SB_DQ1';
NODE_NAME     J19 102
 '@S9S_MB_2U_LIB.S9S_MB_2U(SCH_1):PAGE100_I25@PURE_QUANTA.SCONN288_ADR50017P130CC(CHIPS)':
 'DQ1_B': CDS_PINID='DQ1_B';
NODE_NAME     J20 102
 '@S9S_MB_2U_LIB.S9S_MB_2U(SCH_1):PAGE101_I47@PURE_QUANTA.SCONN288_ADR50017P087CC(CHIPS)':
 'DQ1_B': CDS_PINID='DQ1_B';
NET_NAME
'M_B_CPU1_SB_DQ<20>'
 '@S9S_MB_2U_LIB.S9S_MB_2U(SCH_1):M_B_CPU1_SB_DQ'<20>:
 C_SIGNAL='@s9s_mb_2u_lib.s9s_mb_2u(sch_1):m_b_cpu1_sb_dq(20)';
NODE_NAME     U1 J17
 '@S9S_MB_2U_LIB.S9S_MB_2U(SCH_1):PAGE52_I91@PURE_QUANTA.SOCKET4677_AZIF0045P001C01CS(CHIPS)':
 'DDR1_SB_DQ20': CDS_PINID='DDR1_SB_DQ20';
NODE_NAME     J19 129
 '@S9S_MB_2U_LIB.S9S_MB_2U(SCH_1):PAGE100_I25@PURE_QUANTA.SCONN288_ADR50017P130CC(CHIPS)':
 'DQ20_B': CDS_PINID='DQ20_B';
NODE_NAME     J20 129
 '@S9S_MB_2U_LIB.S9S_MB_2U(SCH_1):PAGE101_I47@PURE_QUANTA.SCONN288_ADR50017P087CC(CHIPS)':
 'DQ20_B': CDS_PINID='DQ20_B';
NET_NAME
'M_B_CPU1_SB_DQ<21>'
 '@S9S_MB_2U_LIB.S9S_MB_2U(SCH_1):M_B_CPU1_SB_DQ'<21>:
 C_SIGNAL='@s9s_mb_2u_lib.s9s_mb_2u(sch_1):m_b_cpu1_sb_dq(21)';
NODE_NAME     U1 K16
 '@S9S_MB_2U_LIB.S9S_MB_2U(SCH_1):PAGE52_I91@PURE_QUANTA.SOCKET4677_AZIF0045P001C01CS(CHIPS)':
 'DDR1_SB_DQ21': CDS_PINID='DDR1_SB_DQ21';
NODE_NAME     J19 131
 '@S9S_MB_2U_LIB.S9S_MB_2U(SCH_1):PAGE100_I25@PURE_QUANTA.SCONN288_ADR50017P130CC(CHIPS)':
 'DQ21_B': CDS_PINID='DQ21_B';
NODE_NAME     J20 131
 '@S9S_MB_2U_LIB.S9S_MB_2U(SCH_1):PAGE101_I47@PURE_QUANTA.SCONN288_ADR50017P087CC(CHIPS)':
 'DQ21_B': CDS_PINID='DQ21_B';
NET_NAME
'M_B_CPU1_SB_DQ<22>'
 '@S9S_MB_2U_LIB.S9S_MB_2U(SCH_1):M_B_CPU1_SB_DQ'<22>:
 C_SIGNAL='@s9s_mb_2u_lib.s9s_mb_2u(sch_1):m_b_cpu1_sb_dq(22)';
NODE_NAME     U1 N17
 '@S9S_MB_2U_LIB.S9S_MB_2U(SCH_1):PAGE52_I91@PURE_QUANTA.SOCKET4677_AZIF0045P001C01CS(CHIPS)':
 'DDR1_SB_DQ22': CDS_PINID='DDR1_SB_DQ22';
NODE_NAME     J19 274
 '@S9S_MB_2U_LIB.S9S_MB_2U(SCH_1):PAGE100_I25@PURE_QUANTA.SCONN288_ADR50017P130CC(CHIPS)':
 'DQ22_B': CDS_PINID='DQ22_B';
NODE_NAME     J20 274
 '@S9S_MB_2U_LIB.S9S_MB_2U(SCH_1):PAGE101_I47@PURE_QUANTA.SCONN288_ADR50017P087CC(CHIPS)':
 'DQ22_B': CDS_PINID='DQ22_B';
NET_NAME
'M_B_CPU1_SB_DQ<23>'
 '@S9S_MB_2U_LIB.S9S_MB_2U(SCH_1):M_B_CPU1_SB_DQ'<23>:
 C_SIGNAL='@s9s_mb_2u_lib.s9s_mb_2u(sch_1):m_b_cpu1_sb_dq(23)';
NODE_NAME     U1 M16
 '@S9S_MB_2U_LIB.S9S_MB_2U(SCH_1):PAGE52_I91@PURE_QUANTA.SOCKET4677_AZIF0045P001C01CS(CHIPS)':
 'DDR1_SB_DQ23': CDS_PINID='DDR1_SB_DQ23';
NODE_NAME     J19 276
 '@S9S_MB_2U_LIB.S9S_MB_2U(SCH_1):PAGE100_I25@PURE_QUANTA.SCONN288_ADR50017P130CC(CHIPS)':
 'DQ23_B': CDS_PINID='DQ23_B';
NODE_NAME     J20 276
 '@S9S_MB_2U_LIB.S9S_MB_2U(SCH_1):PAGE101_I47@PURE_QUANTA.SCONN288_ADR50017P087CC(CHIPS)':
 'DQ23_B': CDS_PINID='DQ23_B';
NET_NAME
'M_B_CPU1_SB_DQ<24>'
 '@S9S_MB_2U_LIB.S9S_MB_2U(SCH_1):M_B_CPU1_SB_DQ'<24>:
 C_SIGNAL='@s9s_mb_2u_lib.s9s_mb_2u(sch_1):m_b_cpu1_sb_dq(24)';
NODE_NAME     U1 C17
 '@S9S_MB_2U_LIB.S9S_MB_2U(SCH_1):PAGE52_I91@PURE_QUANTA.SOCKET4677_AZIF0045P001C01CS(CHIPS)':
 'DDR1_SB_DQ24': CDS_PINID='DDR1_SB_DQ24';
NODE_NAME     J19 133
 '@S9S_MB_2U_LIB.S9S_MB_2U(SCH_1):PAGE100_I25@PURE_QUANTA.SCONN288_ADR50017P130CC(CHIPS)':
 'DQ24_B': CDS_PINID='DQ24_B';
NODE_NAME     J20 133
 '@S9S_MB_2U_LIB.S9S_MB_2U(SCH_1):PAGE101_I47@PURE_QUANTA.SCONN288_ADR50017P087CC(CHIPS)':
 'DQ24_B': CDS_PINID='DQ24_B';
NET_NAME
'M_B_CPU1_SB_DQ<25>'
 '@S9S_MB_2U_LIB.S9S_MB_2U(SCH_1):M_B_CPU1_SB_DQ'<25>:
 C_SIGNAL='@s9s_mb_2u_lib.s9s_mb_2u(sch_1):m_b_cpu1_sb_dq(25)';
NODE_NAME     U1 B16
 '@S9S_MB_2U_LIB.S9S_MB_2U(SCH_1):PAGE52_I91@PURE_QUANTA.SOCKET4677_AZIF0045P001C01CS(CHIPS)':
 'DDR1_SB_DQ25': CDS_PINID='DDR1_SB_DQ25';
NODE_NAME     J19 135
 '@S9S_MB_2U_LIB.S9S_MB_2U(SCH_1):PAGE100_I25@PURE_QUANTA.SCONN288_ADR50017P130CC(CHIPS)':
 'DQ25_B': CDS_PINID='DQ25_B';
NODE_NAME     J20 135
 '@S9S_MB_2U_LIB.S9S_MB_2U(SCH_1):PAGE101_I47@PURE_QUANTA.SCONN288_ADR50017P087CC(CHIPS)':
 'DQ25_B': CDS_PINID='DQ25_B';
NET_NAME
'M_B_CPU1_SB_DQ<26>'
 '@S9S_MB_2U_LIB.S9S_MB_2U(SCH_1):M_B_CPU1_SB_DQ'<26>:
 C_SIGNAL='@s9s_mb_2u_lib.s9s_mb_2u(sch_1):m_b_cpu1_sb_dq(26)';
NODE_NAME     U1 E17
 '@S9S_MB_2U_LIB.S9S_MB_2U(SCH_1):PAGE52_I91@PURE_QUANTA.SOCKET4677_AZIF0045P001C01CS(CHIPS)':
 'DDR1_SB_DQ26': CDS_PINID='DDR1_SB_DQ26';
NODE_NAME     J19 278
 '@S9S_MB_2U_LIB.S9S_MB_2U(SCH_1):PAGE100_I25@PURE_QUANTA.SCONN288_ADR50017P130CC(CHIPS)':
 'DQ26_B': CDS_PINID='DQ26_B';
NODE_NAME     J20 278
 '@S9S_MB_2U_LIB.S9S_MB_2U(SCH_1):PAGE101_I47@PURE_QUANTA.SCONN288_ADR50017P087CC(CHIPS)':
 'DQ26_B': CDS_PINID='DQ26_B';
NET_NAME
'M_B_CPU1_SB_DQ<27>'
 '@S9S_MB_2U_LIB.S9S_MB_2U(SCH_1):M_B_CPU1_SB_DQ'<27>:
 C_SIGNAL='@s9s_mb_2u_lib.s9s_mb_2u(sch_1):m_b_cpu1_sb_dq(27)';
NODE_NAME     U1 F16
 '@S9S_MB_2U_LIB.S9S_MB_2U(SCH_1):PAGE52_I91@PURE_QUANTA.SOCKET4677_AZIF0045P001C01CS(CHIPS)':
 'DDR1_SB_DQ27': CDS_PINID='DDR1_SB_DQ27';
NODE_NAME     J19 280
 '@S9S_MB_2U_LIB.S9S_MB_2U(SCH_1):PAGE100_I25@PURE_QUANTA.SCONN288_ADR50017P130CC(CHIPS)':
 'DQ27_B': CDS_PINID='DQ27_B';
NODE_NAME     J20 280
 '@S9S_MB_2U_LIB.S9S_MB_2U(SCH_1):PAGE101_I47@PURE_QUANTA.SCONN288_ADR50017P087CC(CHIPS)':
 'DQ27_B': CDS_PINID='DQ27_B';
NET_NAME
'M_B_CPU1_SB_DQ<28>'
 '@S9S_MB_2U_LIB.S9S_MB_2U(SCH_1):M_B_CPU1_SB_DQ'<28>:
 C_SIGNAL='@s9s_mb_2u_lib.s9s_mb_2u(sch_1):m_b_cpu1_sb_dq(28)';
NODE_NAME     U1 C13
 '@S9S_MB_2U_LIB.S9S_MB_2U(SCH_1):PAGE52_I91@PURE_QUANTA.SOCKET4677_AZIF0045P001C01CS(CHIPS)':
 'DDR1_SB_DQ28': CDS_PINID='DDR1_SB_DQ28';
NODE_NAME     J19 140
 '@S9S_MB_2U_LIB.S9S_MB_2U(SCH_1):PAGE100_I25@PURE_QUANTA.SCONN288_ADR50017P130CC(CHIPS)':
 'DQ28_B': CDS_PINID='DQ28_B';
NODE_NAME     J20 140
 '@S9S_MB_2U_LIB.S9S_MB_2U(SCH_1):PAGE101_I47@PURE_QUANTA.SCONN288_ADR50017P087CC(CHIPS)':
 'DQ28_B': CDS_PINID='DQ28_B';
NET_NAME
'M_B_CPU1_SB_DQ<29>'
 '@S9S_MB_2U_LIB.S9S_MB_2U(SCH_1):M_B_CPU1_SB_DQ'<29>:
 C_SIGNAL='@s9s_mb_2u_lib.s9s_mb_2u(sch_1):m_b_cpu1_sb_dq(29)';
NODE_NAME     U1 E13
 '@S9S_MB_2U_LIB.S9S_MB_2U(SCH_1):PAGE52_I91@PURE_QUANTA.SOCKET4677_AZIF0045P001C01CS(CHIPS)':
 'DDR1_SB_DQ29': CDS_PINID='DDR1_SB_DQ29';
NODE_NAME     J19 142
 '@S9S_MB_2U_LIB.S9S_MB_2U(SCH_1):PAGE100_I25@PURE_QUANTA.SCONN288_ADR50017P130CC(CHIPS)':
 'DQ29_B': CDS_PINID='DQ29_B';
NODE_NAME     J20 142
 '@S9S_MB_2U_LIB.S9S_MB_2U(SCH_1):PAGE101_I47@PURE_QUANTA.SCONN288_ADR50017P087CC(CHIPS)':
 'DQ29_B': CDS_PINID='DQ29_B';
NET_NAME
'M_B_CPU1_SB_DQ<2>'
 '@S9S_MB_2U_LIB.S9S_MB_2U(SCH_1):M_B_CPU1_SB_DQ'<2>:
 C_SIGNAL='@s9s_mb_2u_lib.s9s_mb_2u(sch_1):m_b_cpu1_sb_dq(2)';
NODE_NAME     U1 W29
 '@S9S_MB_2U_LIB.S9S_MB_2U(SCH_1):PAGE52_I91@PURE_QUANTA.SOCKET4677_AZIF0045P001C01CS(CHIPS)':
 'DDR1_SB_DQ2': CDS_PINID='DDR1_SB_DQ2';
NODE_NAME     J19 245
 '@S9S_MB_2U_LIB.S9S_MB_2U(SCH_1):PAGE100_I25@PURE_QUANTA.SCONN288_ADR50017P130CC(CHIPS)':
 'DQ2_B': CDS_PINID='DQ2_B';
NODE_NAME     J20 245
 '@S9S_MB_2U_LIB.S9S_MB_2U(SCH_1):PAGE101_I47@PURE_QUANTA.SCONN288_ADR50017P087CC(CHIPS)':
 'DQ2_B': CDS_PINID='DQ2_B';
NET_NAME
'M_B_CPU1_SB_DQ<30>'
 '@S9S_MB_2U_LIB.S9S_MB_2U(SCH_1):M_B_CPU1_SB_DQ'<30>:
 C_SIGNAL='@s9s_mb_2u_lib.s9s_mb_2u(sch_1):m_b_cpu1_sb_dq(30)';
NODE_NAME     U1 B14
 '@S9S_MB_2U_LIB.S9S_MB_2U(SCH_1):PAGE52_I91@PURE_QUANTA.SOCKET4677_AZIF0045P001C01CS(CHIPS)':
 'DDR1_SB_DQ30': CDS_PINID='DDR1_SB_DQ30';
NODE_NAME     J19 285
 '@S9S_MB_2U_LIB.S9S_MB_2U(SCH_1):PAGE100_I25@PURE_QUANTA.SCONN288_ADR50017P130CC(CHIPS)':
 'DQ30_B': CDS_PINID='DQ30_B';
NODE_NAME     J20 285
 '@S9S_MB_2U_LIB.S9S_MB_2U(SCH_1):PAGE101_I47@PURE_QUANTA.SCONN288_ADR50017P087CC(CHIPS)':
 'DQ30_B': CDS_PINID='DQ30_B';
NET_NAME
'M_B_CPU1_SB_DQ<31>'
 '@S9S_MB_2U_LIB.S9S_MB_2U(SCH_1):M_B_CPU1_SB_DQ'<31>:
 C_SIGNAL='@s9s_mb_2u_lib.s9s_mb_2u(sch_1):m_b_cpu1_sb_dq(31)';
NODE_NAME     U1 F14
 '@S9S_MB_2U_LIB.S9S_MB_2U(SCH_1):PAGE52_I91@PURE_QUANTA.SOCKET4677_AZIF0045P001C01CS(CHIPS)':
 'DDR1_SB_DQ31': CDS_PINID='DDR1_SB_DQ31';
NODE_NAME     J19 287
 '@S9S_MB_2U_LIB.S9S_MB_2U(SCH_1):PAGE100_I25@PURE_QUANTA.SCONN288_ADR50017P130CC(CHIPS)':
 'DQ31_B': CDS_PINID='DQ31_B';
NODE_NAME     J20 287
 '@S9S_MB_2U_LIB.S9S_MB_2U(SCH_1):PAGE101_I47@PURE_QUANTA.SCONN288_ADR50017P087CC(CHIPS)':
 'DQ31_B': CDS_PINID='DQ31_B';
NET_NAME
'M_B_CPU1_SB_DQ<3>'
 '@S9S_MB_2U_LIB.S9S_MB_2U(SCH_1):M_B_CPU1_SB_DQ'<3>:
 C_SIGNAL='@s9s_mb_2u_lib.s9s_mb_2u(sch_1):m_b_cpu1_sb_dq(3)';
NODE_NAME     U1 Y28
 '@S9S_MB_2U_LIB.S9S_MB_2U(SCH_1):PAGE52_I91@PURE_QUANTA.SOCKET4677_AZIF0045P001C01CS(CHIPS)':
 'DDR1_SB_DQ3': CDS_PINID='DDR1_SB_DQ3';
NODE_NAME     J19 247
 '@S9S_MB_2U_LIB.S9S_MB_2U(SCH_1):PAGE100_I25@PURE_QUANTA.SCONN288_ADR50017P130CC(CHIPS)':
 'DQ3_B': CDS_PINID='DQ3_B';
NODE_NAME     J20 247
 '@S9S_MB_2U_LIB.S9S_MB_2U(SCH_1):PAGE101_I47@PURE_QUANTA.SCONN288_ADR50017P087CC(CHIPS)':
 'DQ3_B': CDS_PINID='DQ3_B';
NET_NAME
'M_B_CPU1_SB_DQ<4>'
 '@S9S_MB_2U_LIB.S9S_MB_2U(SCH_1):M_B_CPU1_SB_DQ'<4>:
 C_SIGNAL='@s9s_mb_2u_lib.s9s_mb_2u(sch_1):m_b_cpu1_sb_dq(4)';
NODE_NAME     U1 T26
 '@S9S_MB_2U_LIB.S9S_MB_2U(SCH_1):PAGE52_I91@PURE_QUANTA.SOCKET4677_AZIF0045P001C01CS(CHIPS)':
 'DDR1_SB_DQ4': CDS_PINID='DDR1_SB_DQ4';
NODE_NAME     J19 107
 '@S9S_MB_2U_LIB.S9S_MB_2U(SCH_1):PAGE100_I25@PURE_QUANTA.SCONN288_ADR50017P130CC(CHIPS)':
 'DQ4_B': CDS_PINID='DQ4_B';
NODE_NAME     J20 107
 '@S9S_MB_2U_LIB.S9S_MB_2U(SCH_1):PAGE101_I47@PURE_QUANTA.SCONN288_ADR50017P087CC(CHIPS)':
 'DQ4_B': CDS_PINID='DQ4_B';
NET_NAME
'M_B_CPU1_SB_DQ<5>'
 '@S9S_MB_2U_LIB.S9S_MB_2U(SCH_1):M_B_CPU1_SB_DQ'<5>:
 C_SIGNAL='@s9s_mb_2u_lib.s9s_mb_2u(sch_1):m_b_cpu1_sb_dq(5)';
NODE_NAME     U1 U25
 '@S9S_MB_2U_LIB.S9S_MB_2U(SCH_1):PAGE52_I91@PURE_QUANTA.SOCKET4677_AZIF0045P001C01CS(CHIPS)':
 'DDR1_SB_DQ5': CDS_PINID='DDR1_SB_DQ5';
NODE_NAME     J19 109
 '@S9S_MB_2U_LIB.S9S_MB_2U(SCH_1):PAGE100_I25@PURE_QUANTA.SCONN288_ADR50017P130CC(CHIPS)':
 'DQ5_B': CDS_PINID='DQ5_B';
NODE_NAME     J20 109
 '@S9S_MB_2U_LIB.S9S_MB_2U(SCH_1):PAGE101_I47@PURE_QUANTA.SCONN288_ADR50017P087CC(CHIPS)':
 'DQ5_B': CDS_PINID='DQ5_B';
NET_NAME
'M_B_CPU1_SB_DQ<6>'
 '@S9S_MB_2U_LIB.S9S_MB_2U(SCH_1):M_B_CPU1_SB_DQ'<6>:
 C_SIGNAL='@s9s_mb_2u_lib.s9s_mb_2u(sch_1):m_b_cpu1_sb_dq(6)';
NODE_NAME     U1 Y26
 '@S9S_MB_2U_LIB.S9S_MB_2U(SCH_1):PAGE52_I91@PURE_QUANTA.SOCKET4677_AZIF0045P001C01CS(CHIPS)':
 'DDR1_SB_DQ6': CDS_PINID='DDR1_SB_DQ6';
NODE_NAME     J19 252
 '@S9S_MB_2U_LIB.S9S_MB_2U(SCH_1):PAGE100_I25@PURE_QUANTA.SCONN288_ADR50017P130CC(CHIPS)':
 'DQ6_B': CDS_PINID='DQ6_B';
NODE_NAME     J20 252
 '@S9S_MB_2U_LIB.S9S_MB_2U(SCH_1):PAGE101_I47@PURE_QUANTA.SCONN288_ADR50017P087CC(CHIPS)':
 'DQ6_B': CDS_PINID='DQ6_B';
NET_NAME
'M_B_CPU1_SB_DQ<7>'
 '@S9S_MB_2U_LIB.S9S_MB_2U(SCH_1):M_B_CPU1_SB_DQ'<7>:
 C_SIGNAL='@s9s_mb_2u_lib.s9s_mb_2u(sch_1):m_b_cpu1_sb_dq(7)';
NODE_NAME     U1 W25
 '@S9S_MB_2U_LIB.S9S_MB_2U(SCH_1):PAGE52_I91@PURE_QUANTA.SOCKET4677_AZIF0045P001C01CS(CHIPS)':
 'DDR1_SB_DQ7': CDS_PINID='DDR1_SB_DQ7';
NODE_NAME     J19 254
 '@S9S_MB_2U_LIB.S9S_MB_2U(SCH_1):PAGE100_I25@PURE_QUANTA.SCONN288_ADR50017P130CC(CHIPS)':
 'DQ7_B': CDS_PINID='DQ7_B';
NODE_NAME     J20 254
 '@S9S_MB_2U_LIB.S9S_MB_2U(SCH_1):PAGE101_I47@PURE_QUANTA.SCONN288_ADR50017P087CC(CHIPS)':
 'DQ7_B': CDS_PINID='DQ7_B';
NET_NAME
'M_B_CPU1_SB_DQ<8>'
 '@S9S_MB_2U_LIB.S9S_MB_2U(SCH_1):M_B_CPU1_SB_DQ'<8>:
 C_SIGNAL='@s9s_mb_2u_lib.s9s_mb_2u(sch_1):m_b_cpu1_sb_dq(8)';
NODE_NAME     U1 K26
 '@S9S_MB_2U_LIB.S9S_MB_2U(SCH_1):PAGE52_I91@PURE_QUANTA.SOCKET4677_AZIF0045P001C01CS(CHIPS)':
 'DDR1_SB_DQ8': CDS_PINID='DDR1_SB_DQ8';
NODE_NAME     J19 111
 '@S9S_MB_2U_LIB.S9S_MB_2U(SCH_1):PAGE100_I25@PURE_QUANTA.SCONN288_ADR50017P130CC(CHIPS)':
 'DQ8_B': CDS_PINID='DQ8_B';
NODE_NAME     J20 111
 '@S9S_MB_2U_LIB.S9S_MB_2U(SCH_1):PAGE101_I47@PURE_QUANTA.SCONN288_ADR50017P087CC(CHIPS)':
 'DQ8_B': CDS_PINID='DQ8_B';
NET_NAME
'M_B_CPU1_SB_DQ<9>'
 '@S9S_MB_2U_LIB.S9S_MB_2U(SCH_1):M_B_CPU1_SB_DQ'<9>:
 C_SIGNAL='@s9s_mb_2u_lib.s9s_mb_2u(sch_1):m_b_cpu1_sb_dq(9)';
NODE_NAME     U1 J25
 '@S9S_MB_2U_LIB.S9S_MB_2U(SCH_1):PAGE52_I91@PURE_QUANTA.SOCKET4677_AZIF0045P001C01CS(CHIPS)':
 'DDR1_SB_DQ9': CDS_PINID='DDR1_SB_DQ9';
NODE_NAME     J19 113
 '@S9S_MB_2U_LIB.S9S_MB_2U(SCH_1):PAGE100_I25@PURE_QUANTA.SCONN288_ADR50017P130CC(CHIPS)':
 'DQ9_B': CDS_PINID='DQ9_B';
NODE_NAME     J20 113
 '@S9S_MB_2U_LIB.S9S_MB_2U(SCH_1):PAGE101_I47@PURE_QUANTA.SCONN288_ADR50017P087CC(CHIPS)':
 'DQ9_B': CDS_PINID='DQ9_B';
NET_NAME
'M_B_CPU1_SB_DQS_DN<0>'
 '@S9S_MB_2U_LIB.S9S_MB_2U(SCH_1):M_B_CPU1_SB_DQS_DN'<0>:
 C_SIGNAL='@s9s_mb_2u_lib.s9s_mb_2u(sch_1):m_b_cpu1_sb_dqs_dn(0)';
NODE_NAME     U1 R27
 '@S9S_MB_2U_LIB.S9S_MB_2U(SCH_1):PAGE52_I91@PURE_QUANTA.SOCKET4677_AZIF0045P001C01CS(CHIPS)':
 'DDR1_SB_DQS_DN0': CDS_PINID='DDR1_SB_DQS_DN0';
NODE_NAME     J19 105
 '@S9S_MB_2U_LIB.S9S_MB_2U(SCH_1):PAGE100_I178@PURE_QUANTA.SCONN288_ADR50017P130CC(CHIPS)':
 'DQS0_B_C': CDS_PINID='DQS0_B_C';
NODE_NAME     J20 105
 '@S9S_MB_2U_LIB.S9S_MB_2U(SCH_1):PAGE101_I178@PURE_QUANTA.SCONN288_ADR50017P087CC(CHIPS)':
 'DQS0_B_C': CDS_PINID='DQS0_B_C';
NET_NAME
'M_B_CPU1_SB_DQS_DN<1>'
 '@S9S_MB_2U_LIB.S9S_MB_2U(SCH_1):M_B_CPU1_SB_DQS_DN'<1>:
 C_SIGNAL='@s9s_mb_2u_lib.s9s_mb_2u(sch_1):m_b_cpu1_sb_dqs_dn(1)';
NODE_NAME     U1 H24
 '@S9S_MB_2U_LIB.S9S_MB_2U(SCH_1):PAGE52_I91@PURE_QUANTA.SOCKET4677_AZIF0045P001C01CS(CHIPS)':
 'DDR1_SB_DQS_DN1': CDS_PINID='DDR1_SB_DQS_DN1';
NODE_NAME     J19 116
 '@S9S_MB_2U_LIB.S9S_MB_2U(SCH_1):PAGE100_I178@PURE_QUANTA.SCONN288_ADR50017P130CC(CHIPS)':
 'DQS1_B_C': CDS_PINID='DQS1_B_C';
NODE_NAME     J20 116
 '@S9S_MB_2U_LIB.S9S_MB_2U(SCH_1):PAGE101_I178@PURE_QUANTA.SCONN288_ADR50017P087CC(CHIPS)':
 'DQS1_B_C': CDS_PINID='DQS1_B_C';
NET_NAME
'M_B_CPU1_SB_DQS_DN<2>'
 '@S9S_MB_2U_LIB.S9S_MB_2U(SCH_1):M_B_CPU1_SB_DQS_DN'<2>:
 C_SIGNAL='@s9s_mb_2u_lib.s9s_mb_2u(sch_1):m_b_cpu1_sb_dqs_dn(2)';
NODE_NAME     U1 H18
 '@S9S_MB_2U_LIB.S9S_MB_2U(SCH_1):PAGE52_I91@PURE_QUANTA.SOCKET4677_AZIF0045P001C01CS(CHIPS)':
 'DDR1_SB_DQS_DN2': CDS_PINID='DDR1_SB_DQS_DN2';
NODE_NAME     J19 127
 '@S9S_MB_2U_LIB.S9S_MB_2U(SCH_1):PAGE100_I178@PURE_QUANTA.SCONN288_ADR50017P130CC(CHIPS)':
 'DQS2_B_C': CDS_PINID='DQS2_B_C';
NODE_NAME     J20 127
 '@S9S_MB_2U_LIB.S9S_MB_2U(SCH_1):PAGE101_I178@PURE_QUANTA.SCONN288_ADR50017P087CC(CHIPS)':
 'DQS2_B_C': CDS_PINID='DQS2_B_C';
NET_NAME
'M_B_CPU1_SB_DQS_DN<3>'
 '@S9S_MB_2U_LIB.S9S_MB_2U(SCH_1):M_B_CPU1_SB_DQS_DN'<3>:
 C_SIGNAL='@s9s_mb_2u_lib.s9s_mb_2u(sch_1):m_b_cpu1_sb_dqs_dn(3)';
NODE_NAME     U1 A15
 '@S9S_MB_2U_LIB.S9S_MB_2U(SCH_1):PAGE52_I91@PURE_QUANTA.SOCKET4677_AZIF0045P001C01CS(CHIPS)':
 'DDR1_SB_DQS_DN3': CDS_PINID='DDR1_SB_DQS_DN3';
NODE_NAME     J19 138
 '@S9S_MB_2U_LIB.S9S_MB_2U(SCH_1):PAGE100_I178@PURE_QUANTA.SCONN288_ADR50017P130CC(CHIPS)':
 'DQS3_B_C': CDS_PINID='DQS3_B_C';
NODE_NAME     J20 138
 '@S9S_MB_2U_LIB.S9S_MB_2U(SCH_1):PAGE101_I178@PURE_QUANTA.SCONN288_ADR50017P087CC(CHIPS)':
 'DQS3_B_C': CDS_PINID='DQS3_B_C';
NET_NAME
'M_B_CPU1_SB_DQS_DN<4>'
 '@S9S_MB_2U_LIB.S9S_MB_2U(SCH_1):M_B_CPU1_SB_DQS_DN'<4>:
 C_SIGNAL='@s9s_mb_2u_lib.s9s_mb_2u(sch_1):m_b_cpu1_sb_dqs_dn(4)';
NODE_NAME     U1 P36
 '@S9S_MB_2U_LIB.S9S_MB_2U(SCH_1):PAGE52_I91@PURE_QUANTA.SOCKET4677_AZIF0045P001C01CS(CHIPS)':
 'DDR1_SB_DQS_DN4': CDS_PINID='DDR1_SB_DQS_DN4';
NODE_NAME     J19 238
 '@S9S_MB_2U_LIB.S9S_MB_2U(SCH_1):PAGE100_I178@PURE_QUANTA.SCONN288_ADR50017P130CC(CHIPS)':
 'DQS4_B_C': CDS_PINID='DQS4_B_C';
NODE_NAME     J20 238
 '@S9S_MB_2U_LIB.S9S_MB_2U(SCH_1):PAGE101_I178@PURE_QUANTA.SCONN288_ADR50017P087CC(CHIPS)':
 'DQS4_B_C': CDS_PINID='DQS4_B_C';
NET_NAME
'M_B_CPU1_SB_DQS_DN<5>'
 '@S9S_MB_2U_LIB.S9S_MB_2U(SCH_1):M_B_CPU1_SB_DQS_DN'<5>:
 C_SIGNAL='@s9s_mb_2u_lib.s9s_mb_2u(sch_1):m_b_cpu1_sb_dqs_dn(5)';
NODE_NAME     U1 W27
 '@S9S_MB_2U_LIB.S9S_MB_2U(SCH_1):PAGE52_I91@PURE_QUANTA.SOCKET4677_AZIF0045P001C01CS(CHIPS)':
 'DDR1_SB_DQS_DN5': CDS_PINID='DDR1_SB_DQS_DN5';
NODE_NAME     J19 249
 '@S9S_MB_2U_LIB.S9S_MB_2U(SCH_1):PAGE100_I178@PURE_QUANTA.SCONN288_ADR50017P130CC(CHIPS)':
 'DQS5_B_C||TDQS5_B_C': CDS_PINID='\dqs5_b_c||tdqs5_b_c\';
NODE_NAME     J20 249
 '@S9S_MB_2U_LIB.S9S_MB_2U(SCH_1):PAGE101_I178@PURE_QUANTA.SCONN288_ADR50017P087CC(CHIPS)':
 'DQS5_B_C||TDQS5_B_C': CDS_PINID='\dqs5_b_c||tdqs5_b_c\';
NET_NAME
'M_B_CPU1_SB_DQS_DN<6>'
 '@S9S_MB_2U_LIB.S9S_MB_2U(SCH_1):M_B_CPU1_SB_DQS_DN'<6>:
 C_SIGNAL='@s9s_mb_2u_lib.s9s_mb_2u(sch_1):m_b_cpu1_sb_dqs_dn(6)';
NODE_NAME     U1 M24
 '@S9S_MB_2U_LIB.S9S_MB_2U(SCH_1):PAGE52_I91@PURE_QUANTA.SOCKET4677_AZIF0045P001C01CS(CHIPS)':
 'DDR1_SB_DQS_DN6': CDS_PINID='DDR1_SB_DQS_DN6';
NODE_NAME     J19 260
 '@S9S_MB_2U_LIB.S9S_MB_2U(SCH_1):PAGE100_I178@PURE_QUANTA.SCONN288_ADR50017P130CC(CHIPS)':
 'DQS6_B_C||TDQS6_B_C': CDS_PINID='\dqs6_b_c||tdqs6_b_c\';
NODE_NAME     J20 260
 '@S9S_MB_2U_LIB.S9S_MB_2U(SCH_1):PAGE101_I178@PURE_QUANTA.SCONN288_ADR50017P087CC(CHIPS)':
 'DQS6_B_C||TDQS6_B_C': CDS_PINID='\dqs6_b_c||tdqs6_b_c\';
NET_NAME
'M_B_CPU1_SB_DQS_DN<7>'
 '@S9S_MB_2U_LIB.S9S_MB_2U(SCH_1):M_B_CPU1_SB_DQS_DN'<7>:
 C_SIGNAL='@s9s_mb_2u_lib.s9s_mb_2u(sch_1):m_b_cpu1_sb_dqs_dn(7)';
NODE_NAME     U1 M18
 '@S9S_MB_2U_LIB.S9S_MB_2U(SCH_1):PAGE52_I91@PURE_QUANTA.SOCKET4677_AZIF0045P001C01CS(CHIPS)':
 'DDR1_SB_DQS_DN7': CDS_PINID='DDR1_SB_DQS_DN7';
NODE_NAME     J19 271
 '@S9S_MB_2U_LIB.S9S_MB_2U(SCH_1):PAGE100_I178@PURE_QUANTA.SCONN288_ADR50017P130CC(CHIPS)':
 'DQS7_B_C||TDQS7_B_C': CDS_PINID='\dqs7_b_c||tdqs7_b_c\';
NODE_NAME     J20 271
 '@S9S_MB_2U_LIB.S9S_MB_2U(SCH_1):PAGE101_I178@PURE_QUANTA.SCONN288_ADR50017P087CC(CHIPS)':
 'DQS7_B_C||TDQS7_B_C': CDS_PINID='\dqs7_b_c||tdqs7_b_c\';
NET_NAME
'M_B_CPU1_SB_DQS_DN<8>'
 '@S9S_MB_2U_LIB.S9S_MB_2U(SCH_1):M_B_CPU1_SB_DQS_DN'<8>:
 C_SIGNAL='@s9s_mb_2u_lib.s9s_mb_2u(sch_1):m_b_cpu1_sb_dqs_dn(8)';
NODE_NAME     U1 E15
 '@S9S_MB_2U_LIB.S9S_MB_2U(SCH_1):PAGE52_I91@PURE_QUANTA.SOCKET4677_AZIF0045P001C01CS(CHIPS)':
 'DDR1_SB_DQS_DN8': CDS_PINID='DDR1_SB_DQS_DN8';
NODE_NAME     J19 282
 '@S9S_MB_2U_LIB.S9S_MB_2U(SCH_1):PAGE100_I178@PURE_QUANTA.SCONN288_ADR50017P130CC(CHIPS)':
 'DQS8_B_C||TDQS8_B_C': CDS_PINID='\dqs8_b_c||tdqs8_b_c\';
NODE_NAME     J20 282
 '@S9S_MB_2U_LIB.S9S_MB_2U(SCH_1):PAGE101_I178@PURE_QUANTA.SCONN288_ADR50017P087CC(CHIPS)':
 'DQS8_B_C||TDQS8_B_C': CDS_PINID='\dqs8_b_c||tdqs8_b_c\';
NET_NAME
'M_B_CPU1_SB_DQS_DN<9>'
 '@S9S_MB_2U_LIB.S9S_MB_2U(SCH_1):M_B_CPU1_SB_DQS_DN'<9>:
 C_SIGNAL='@s9s_mb_2u_lib.s9s_mb_2u(sch_1):m_b_cpu1_sb_dqs_dn(9)';
NODE_NAME     U1 K36
 '@S9S_MB_2U_LIB.S9S_MB_2U(SCH_1):PAGE52_I91@PURE_QUANTA.SOCKET4677_AZIF0045P001C01CS(CHIPS)':
 'DDR1_SB_DQS_DN9': CDS_PINID='DDR1_SB_DQS_DN9';
NODE_NAME     J19 94
 '@S9S_MB_2U_LIB.S9S_MB_2U(SCH_1):PAGE100_I178@PURE_QUANTA.SCONN288_ADR50017P130CC(CHIPS)':
 'DQS9_B_C||TDQS9_B_C': CDS_PINID='\dqs9_b_c||tdqs9_b_c\';
NODE_NAME     J20 94
 '@S9S_MB_2U_LIB.S9S_MB_2U(SCH_1):PAGE101_I178@PURE_QUANTA.SCONN288_ADR50017P087CC(CHIPS)':
 'DQS9_B_C||TDQS9_B_C': CDS_PINID='\dqs9_b_c||tdqs9_b_c\';
NET_NAME
'M_B_CPU1_SB_DQS_DP<0>'
 '@S9S_MB_2U_LIB.S9S_MB_2U(SCH_1):M_B_CPU1_SB_DQS_DP'<0>:
 C_SIGNAL='@s9s_mb_2u_lib.s9s_mb_2u(sch_1):m_b_cpu1_sb_dqs_dp(0)';
NODE_NAME     U1 U27
 '@S9S_MB_2U_LIB.S9S_MB_2U(SCH_1):PAGE52_I91@PURE_QUANTA.SOCKET4677_AZIF0045P001C01CS(CHIPS)':
 'DDR1_SB_DQS_DP0': CDS_PINID='DDR1_SB_DQS_DP0';
NODE_NAME     J19 104
 '@S9S_MB_2U_LIB.S9S_MB_2U(SCH_1):PAGE100_I178@PURE_QUANTA.SCONN288_ADR50017P130CC(CHIPS)':
 'DQS0_B_T': CDS_PINID='DQS0_B_T';
NODE_NAME     J20 104
 '@S9S_MB_2U_LIB.S9S_MB_2U(SCH_1):PAGE101_I178@PURE_QUANTA.SCONN288_ADR50017P087CC(CHIPS)':
 'DQS0_B_T': CDS_PINID='DQS0_B_T';
NET_NAME
'M_B_CPU1_SB_DQS_DP<1>'
 '@S9S_MB_2U_LIB.S9S_MB_2U(SCH_1):M_B_CPU1_SB_DQS_DP'<1>:
 C_SIGNAL='@s9s_mb_2u_lib.s9s_mb_2u(sch_1):m_b_cpu1_sb_dqs_dp(1)';
NODE_NAME     U1 K24
 '@S9S_MB_2U_LIB.S9S_MB_2U(SCH_1):PAGE52_I91@PURE_QUANTA.SOCKET4677_AZIF0045P001C01CS(CHIPS)':
 'DDR1_SB_DQS_DP1': CDS_PINID='DDR1_SB_DQS_DP1';
NODE_NAME     J19 115
 '@S9S_MB_2U_LIB.S9S_MB_2U(SCH_1):PAGE100_I178@PURE_QUANTA.SCONN288_ADR50017P130CC(CHIPS)':
 'DQS1_B_T': CDS_PINID='DQS1_B_T';
NODE_NAME     J20 115
 '@S9S_MB_2U_LIB.S9S_MB_2U(SCH_1):PAGE101_I178@PURE_QUANTA.SCONN288_ADR50017P087CC(CHIPS)':
 'DQS1_B_T': CDS_PINID='DQS1_B_T';
NET_NAME
'M_B_CPU1_SB_DQS_DP<2>'
 '@S9S_MB_2U_LIB.S9S_MB_2U(SCH_1):M_B_CPU1_SB_DQS_DP'<2>:
 C_SIGNAL='@s9s_mb_2u_lib.s9s_mb_2u(sch_1):m_b_cpu1_sb_dqs_dp(2)';
NODE_NAME     U1 K18
 '@S9S_MB_2U_LIB.S9S_MB_2U(SCH_1):PAGE52_I91@PURE_QUANTA.SOCKET4677_AZIF0045P001C01CS(CHIPS)':
 'DDR1_SB_DQS_DP2': CDS_PINID='DDR1_SB_DQS_DP2';
NODE_NAME     J19 126
 '@S9S_MB_2U_LIB.S9S_MB_2U(SCH_1):PAGE100_I178@PURE_QUANTA.SCONN288_ADR50017P130CC(CHIPS)':
 'DQS2_B_T': CDS_PINID='DQS2_B_T';
NODE_NAME     J20 126
 '@S9S_MB_2U_LIB.S9S_MB_2U(SCH_1):PAGE101_I178@PURE_QUANTA.SCONN288_ADR50017P087CC(CHIPS)':
 'DQS2_B_T': CDS_PINID='DQS2_B_T';
NET_NAME
'M_B_CPU1_SB_DQS_DP<3>'
 '@S9S_MB_2U_LIB.S9S_MB_2U(SCH_1):M_B_CPU1_SB_DQS_DP'<3>:
 C_SIGNAL='@s9s_mb_2u_lib.s9s_mb_2u(sch_1):m_b_cpu1_sb_dqs_dp(3)';
NODE_NAME     U1 C15
 '@S9S_MB_2U_LIB.S9S_MB_2U(SCH_1):PAGE52_I91@PURE_QUANTA.SOCKET4677_AZIF0045P001C01CS(CHIPS)':
 'DDR1_SB_DQS_DP3': CDS_PINID='DDR1_SB_DQS_DP3';
NODE_NAME     J19 137
 '@S9S_MB_2U_LIB.S9S_MB_2U(SCH_1):PAGE100_I178@PURE_QUANTA.SCONN288_ADR50017P130CC(CHIPS)':
 'DQS3_B_T': CDS_PINID='DQS3_B_T';
NODE_NAME     J20 137
 '@S9S_MB_2U_LIB.S9S_MB_2U(SCH_1):PAGE101_I178@PURE_QUANTA.SCONN288_ADR50017P087CC(CHIPS)':
 'DQS3_B_T': CDS_PINID='DQS3_B_T';
NET_NAME
'M_B_CPU1_SB_DQS_DP<4>'
 '@S9S_MB_2U_LIB.S9S_MB_2U(SCH_1):M_B_CPU1_SB_DQS_DP'<4>:
 C_SIGNAL='@s9s_mb_2u_lib.s9s_mb_2u(sch_1):m_b_cpu1_sb_dqs_dp(4)';
NODE_NAME     U1 M36
 '@S9S_MB_2U_LIB.S9S_MB_2U(SCH_1):PAGE52_I91@PURE_QUANTA.SOCKET4677_AZIF0045P001C01CS(CHIPS)':
 'DDR1_SB_DQS_DP4': CDS_PINID='DDR1_SB_DQS_DP4';
NODE_NAME     J19 239
 '@S9S_MB_2U_LIB.S9S_MB_2U(SCH_1):PAGE100_I178@PURE_QUANTA.SCONN288_ADR50017P130CC(CHIPS)':
 'DQS4_B_T': CDS_PINID='DQS4_B_T';
NODE_NAME     J20 239
 '@S9S_MB_2U_LIB.S9S_MB_2U(SCH_1):PAGE101_I178@PURE_QUANTA.SCONN288_ADR50017P087CC(CHIPS)':
 'DQS4_B_T': CDS_PINID='DQS4_B_T';
NET_NAME
'M_B_CPU1_SB_DQS_DP<5>'
 '@S9S_MB_2U_LIB.S9S_MB_2U(SCH_1):M_B_CPU1_SB_DQS_DP'<5>:
 C_SIGNAL='@s9s_mb_2u_lib.s9s_mb_2u(sch_1):m_b_cpu1_sb_dqs_dp(5)';
NODE_NAME     U1 AA27
 '@S9S_MB_2U_LIB.S9S_MB_2U(SCH_1):PAGE52_I91@PURE_QUANTA.SOCKET4677_AZIF0045P001C01CS(CHIPS)':
 'DDR1_SB_DQS_DP5': CDS_PINID='DDR1_SB_DQS_DP5';
NODE_NAME     J19 250
 '@S9S_MB_2U_LIB.S9S_MB_2U(SCH_1):PAGE100_I178@PURE_QUANTA.SCONN288_ADR50017P130CC(CHIPS)':
 'DQS5_B_T||TDQS5_B_T': CDS_PINID='\dqs5_b_t||tdqs5_b_t\';
NODE_NAME     J20 250
 '@S9S_MB_2U_LIB.S9S_MB_2U(SCH_1):PAGE101_I178@PURE_QUANTA.SCONN288_ADR50017P087CC(CHIPS)':
 'DQS5_B_T||TDQS5_B_T': CDS_PINID='\dqs5_b_t||tdqs5_b_t\';
NET_NAME
'M_B_CPU1_SB_DQS_DP<6>'
 '@S9S_MB_2U_LIB.S9S_MB_2U(SCH_1):M_B_CPU1_SB_DQS_DP'<6>:
 C_SIGNAL='@s9s_mb_2u_lib.s9s_mb_2u(sch_1):m_b_cpu1_sb_dqs_dp(6)';
NODE_NAME     U1 P24
 '@S9S_MB_2U_LIB.S9S_MB_2U(SCH_1):PAGE52_I91@PURE_QUANTA.SOCKET4677_AZIF0045P001C01CS(CHIPS)':
 'DDR1_SB_DQS_DP6': CDS_PINID='DDR1_SB_DQS_DP6';
NODE_NAME     J19 261
 '@S9S_MB_2U_LIB.S9S_MB_2U(SCH_1):PAGE100_I178@PURE_QUANTA.SCONN288_ADR50017P130CC(CHIPS)':
 'DQS6_B_T||TDQS6_B_T': CDS_PINID='\dqs6_b_t||tdqs6_b_t\';
NODE_NAME     J20 261
 '@S9S_MB_2U_LIB.S9S_MB_2U(SCH_1):PAGE101_I178@PURE_QUANTA.SCONN288_ADR50017P087CC(CHIPS)':
 'DQS6_B_T||TDQS6_B_T': CDS_PINID='\dqs6_b_t||tdqs6_b_t\';
NET_NAME
'M_B_CPU1_SB_DQS_DP<7>'
 '@S9S_MB_2U_LIB.S9S_MB_2U(SCH_1):M_B_CPU1_SB_DQS_DP'<7>:
 C_SIGNAL='@s9s_mb_2u_lib.s9s_mb_2u(sch_1):m_b_cpu1_sb_dqs_dp(7)';
NODE_NAME     U1 P18
 '@S9S_MB_2U_LIB.S9S_MB_2U(SCH_1):PAGE52_I91@PURE_QUANTA.SOCKET4677_AZIF0045P001C01CS(CHIPS)':
 'DDR1_SB_DQS_DP7': CDS_PINID='DDR1_SB_DQS_DP7';
NODE_NAME     J19 272
 '@S9S_MB_2U_LIB.S9S_MB_2U(SCH_1):PAGE100_I178@PURE_QUANTA.SCONN288_ADR50017P130CC(CHIPS)':
 'DQS7_B_T||TDQS7_B_T': CDS_PINID='\dqs7_b_t||tdqs7_b_t\';
NODE_NAME     J20 272
 '@S9S_MB_2U_LIB.S9S_MB_2U(SCH_1):PAGE101_I178@PURE_QUANTA.SCONN288_ADR50017P087CC(CHIPS)':
 'DQS7_B_T||TDQS7_B_T': CDS_PINID='\dqs7_b_t||tdqs7_b_t\';
NET_NAME
'M_B_CPU1_SB_DQS_DP<8>'
 '@S9S_MB_2U_LIB.S9S_MB_2U(SCH_1):M_B_CPU1_SB_DQS_DP'<8>:
 C_SIGNAL='@s9s_mb_2u_lib.s9s_mb_2u(sch_1):m_b_cpu1_sb_dqs_dp(8)';
NODE_NAME     U1 G15
 '@S9S_MB_2U_LIB.S9S_MB_2U(SCH_1):PAGE52_I91@PURE_QUANTA.SOCKET4677_AZIF0045P001C01CS(CHIPS)':
 'DDR1_SB_DQS_DP8': CDS_PINID='DDR1_SB_DQS_DP8';
NODE_NAME     J19 283
 '@S9S_MB_2U_LIB.S9S_MB_2U(SCH_1):PAGE100_I178@PURE_QUANTA.SCONN288_ADR50017P130CC(CHIPS)':
 'DQS8_B_T||TDQS8_B_T': CDS_PINID='\dqs8_b_t||tdqs8_b_t\';
NODE_NAME     J20 283
 '@S9S_MB_2U_LIB.S9S_MB_2U(SCH_1):PAGE101_I178@PURE_QUANTA.SCONN288_ADR50017P087CC(CHIPS)':
 'DQS8_B_T||TDQS8_B_T': CDS_PINID='\dqs8_b_t||tdqs8_b_t\';
NET_NAME
'M_B_CPU1_SB_DQS_DP<9>'
 '@S9S_MB_2U_LIB.S9S_MB_2U(SCH_1):M_B_CPU1_SB_DQS_DP'<9>:
 C_SIGNAL='@s9s_mb_2u_lib.s9s_mb_2u(sch_1):m_b_cpu1_sb_dqs_dp(9)';
NODE_NAME     U1 H36
 '@S9S_MB_2U_LIB.S9S_MB_2U(SCH_1):PAGE52_I91@PURE_QUANTA.SOCKET4677_AZIF0045P001C01CS(CHIPS)':
 'DDR1_SB_DQS_DP9': CDS_PINID='DDR1_SB_DQS_DP9';
NODE_NAME     J19 93
 '@S9S_MB_2U_LIB.S9S_MB_2U(SCH_1):PAGE100_I178@PURE_QUANTA.SCONN288_ADR50017P130CC(CHIPS)':
 'DQS9_B_T||TDQS9_B_T||DBI4_B_N': CDS_PINID='\dqs9_b_t||tdqs9_b_t||dbi4_b_n\';
NODE_NAME     J20 93
 '@S9S_MB_2U_LIB.S9S_MB_2U(SCH_1):PAGE101_I178@PURE_QUANTA.SCONN288_ADR50017P087CC(CHIPS)':
 'DQS9_B_T||TDQS9_B_T||DBI4_B_N': CDS_PINID='\dqs9_b_t||tdqs9_b_t||dbi4_b_n\';
NET_NAME
'M_B_CPU1_SB_PAR'
 '@S9S_MB_2U_LIB.S9S_MB_2U(SCH_1):M_B_CPU1_SB_PAR':
 C_SIGNAL='@s9s_mb_2u_lib.s9s_mb_2u(sch_1):m_b_cpu1_sb_par';
NODE_NAME     U1 P42
 '@S9S_MB_2U_LIB.S9S_MB_2U(SCH_1):PAGE52_I91@PURE_QUANTA.SOCKET4677_AZIF0045P001C01CS(CHIPS)':
 'DDR1_SB_PAR': CDS_PINID='DDR1_SB_PAR';
NODE_NAME     J19 227
 '@S9S_MB_2U_LIB.S9S_MB_2U(SCH_1):PAGE100_I25@PURE_QUANTA.SCONN288_ADR50017P130CC(CHIPS)':
 'PAR_B': CDS_PINID='PAR_B';
NODE_NAME     J20 227
 '@S9S_MB_2U_LIB.S9S_MB_2U(SCH_1):PAGE101_I47@PURE_QUANTA.SCONN288_ADR50017P087CC(CHIPS)':
 'PAR_B': CDS_PINID='PAR_B';
NET_NAME
'M_B_CPU1_SB_RSP<0>'
 '@S9S_MB_2U_LIB.S9S_MB_2U(SCH_1):M_B_CPU1_SB_RSP'<0>:
 C_SIGNAL='@s9s_mb_2u_lib.s9s_mb_2u(sch_1):m_b_cpu1_sb_rsp(0)';
NODE_NAME     U1 AN48
 '@S9S_MB_2U_LIB.S9S_MB_2U(SCH_1):PAGE52_I91@PURE_QUANTA.SOCKET4677_AZIF0045P001C01CS(CHIPS)':
 'DDR1_B_RSP0': CDS_PINID='DDR1_B_RSP0';
NODE_NAME     J19 87
 '@S9S_MB_2U_LIB.S9S_MB_2U(SCH_1):PAGE100_I25@PURE_QUANTA.SCONN288_ADR50017P130CC(CHIPS)':
 'LBS||RSP_B_N': CDS_PINID='\lbs||rsp_b_n\';
NET_NAME
'M_B_CPU1_SB_RSP<1>'
 '@S9S_MB_2U_LIB.S9S_MB_2U(SCH_1):M_B_CPU1_SB_RSP'<1>:
 C_SIGNAL='@s9s_mb_2u_lib.s9s_mb_2u(sch_1):m_b_cpu1_sb_rsp(1)';
NODE_NAME     U1 AP47
 '@S9S_MB_2U_LIB.S9S_MB_2U(SCH_1):PAGE52_I91@PURE_QUANTA.SOCKET4677_AZIF0045P001C01CS(CHIPS)':
 'DDR1_B_RSP1': CDS_PINID='DDR1_B_RSP1';
NODE_NAME     J20 87
 '@S9S_MB_2U_LIB.S9S_MB_2U(SCH_1):PAGE101_I47@PURE_QUANTA.SCONN288_ADR50017P087CC(CHIPS)':
 'LBS||RSP_B_N': CDS_PINID='\lbs||rsp_b_n\';
NET_NAME
'M_C_CPU0_ALERT_N'
 '@S9S_MB_2U_LIB.S9S_MB_2U(SCH_1):M_C_CPU0_ALERT_N':
 C_SIGNAL='@s9s_mb_2u_lib.s9s_mb_2u(sch_1):m_c_cpu0_alert_n';
NODE_NAME     U2 AT47
 '@S9S_MB_2U_LIB.S9S_MB_2U(SCH_1):PAGE22_I169@PURE_QUANTA.SOCKET4677_AZIF0045P001C01CS(CHIPS)':
 'DDR2_ALERT_N': CDS_PINID='DDR2_ALERT_N';
NODE_NAME     J5 62
 '@S9S_MB_2U_LIB.S9S_MB_2U(SCH_1):PAGE86_I24@PURE_QUANTA.SCONN288_ADR50017P130CC(CHIPS)':
 'ALERT_N': CDS_PINID='ALERT_N';
NODE_NAME     J6 62
 '@S9S_MB_2U_LIB.S9S_MB_2U(SCH_1):PAGE87_I46@PURE_QUANTA.SCONN288_ADR50017P087CC(CHIPS)':
 'ALERT_N': CDS_PINID='ALERT_N';
NET_NAME
'M_C_CPU0_CLK_DN<0>'
 '@S9S_MB_2U_LIB.S9S_MB_2U(SCH_1):M_C_CPU0_CLK_DN'<0>:
 C_SIGNAL='@s9s_mb_2u_lib.s9s_mb_2u(sch_1):m_c_cpu0_clk_dn(0)';
NODE_NAME     U2 AB49
 '@S9S_MB_2U_LIB.S9S_MB_2U(SCH_1):PAGE22_I169@PURE_QUANTA.SOCKET4677_AZIF0045P001C01CS(CHIPS)':
 'DDR2_CLK_DN0': CDS_PINID='DDR2_CLK_DN0';
NODE_NAME     J5 218
 '@S9S_MB_2U_LIB.S9S_MB_2U(SCH_1):PAGE86_I24@PURE_QUANTA.SCONN288_ADR50017P130CC(CHIPS)':
 'CK_C': CDS_PINID='CK_C';
NET_NAME
'M_C_CPU0_CLK_DN<1>'
 '@S9S_MB_2U_LIB.S9S_MB_2U(SCH_1):M_C_CPU0_CLK_DN'<1>:
 C_SIGNAL='@s9s_mb_2u_lib.s9s_mb_2u(sch_1):m_c_cpu0_clk_dn(1)';
NODE_NAME     U2 AF49
 '@S9S_MB_2U_LIB.S9S_MB_2U(SCH_1):PAGE22_I169@PURE_QUANTA.SOCKET4677_AZIF0045P001C01CS(CHIPS)':
 'DDR2_CLK_DN1': CDS_PINID='DDR2_CLK_DN1';
NODE_NAME     J6 218
 '@S9S_MB_2U_LIB.S9S_MB_2U(SCH_1):PAGE87_I46@PURE_QUANTA.SCONN288_ADR50017P087CC(CHIPS)':
 'CK_C': CDS_PINID='CK_C';
NET_NAME
'M_C_CPU0_CLK_DP<0>'
 '@S9S_MB_2U_LIB.S9S_MB_2U(SCH_1):M_C_CPU0_CLK_DP'<0>:
 C_SIGNAL='@s9s_mb_2u_lib.s9s_mb_2u(sch_1):m_c_cpu0_clk_dp(0)';
NODE_NAME     U2 AD49
 '@S9S_MB_2U_LIB.S9S_MB_2U(SCH_1):PAGE22_I169@PURE_QUANTA.SOCKET4677_AZIF0045P001C01CS(CHIPS)':
 'DDR2_CLK_DP0': CDS_PINID='DDR2_CLK_DP0';
NODE_NAME     J5 217
 '@S9S_MB_2U_LIB.S9S_MB_2U(SCH_1):PAGE86_I24@PURE_QUANTA.SCONN288_ADR50017P130CC(CHIPS)':
 'CK_T': CDS_PINID='CK_T';
NET_NAME
'M_C_CPU0_CLK_DP<1>'
 '@S9S_MB_2U_LIB.S9S_MB_2U(SCH_1):M_C_CPU0_CLK_DP'<1>:
 C_SIGNAL='@s9s_mb_2u_lib.s9s_mb_2u(sch_1):m_c_cpu0_clk_dp(1)';
NODE_NAME     U2 AH49
 '@S9S_MB_2U_LIB.S9S_MB_2U(SCH_1):PAGE22_I169@PURE_QUANTA.SOCKET4677_AZIF0045P001C01CS(CHIPS)':
 'DDR2_CLK_DP1': CDS_PINID='DDR2_CLK_DP1';
NODE_NAME     J6 217
 '@S9S_MB_2U_LIB.S9S_MB_2U(SCH_1):PAGE87_I46@PURE_QUANTA.SCONN288_ADR50017P087CC(CHIPS)':
 'CK_T': CDS_PINID='CK_T';
NET_NAME
'M_C_CPU0_SA_CA<0>'
 '@S9S_MB_2U_LIB.S9S_MB_2U(SCH_1):M_C_CPU0_SA_CA'<0>:
 C_SIGNAL='@s9s_mb_2u_lib.s9s_mb_2u(sch_1):m_c_cpu0_sa_ca(0)';
NODE_NAME     U2 R52
 '@S9S_MB_2U_LIB.S9S_MB_2U(SCH_1):PAGE22_I169@PURE_QUANTA.SOCKET4677_AZIF0045P001C01CS(CHIPS)':
 'DDR2_SA_CA0': CDS_PINID='DDR2_SA_CA0';
NODE_NAME     J5 66
 '@S9S_MB_2U_LIB.S9S_MB_2U(SCH_1):PAGE86_I24@PURE_QUANTA.SCONN288_ADR50017P130CC(CHIPS)':
 'CA0_A': CDS_PINID='CA0_A';
NODE_NAME     J6 66
 '@S9S_MB_2U_LIB.S9S_MB_2U(SCH_1):PAGE87_I46@PURE_QUANTA.SCONN288_ADR50017P087CC(CHIPS)':
 'CA0_A': CDS_PINID='CA0_A';
NET_NAME
'M_C_CPU0_SA_CA<1>'
 '@S9S_MB_2U_LIB.S9S_MB_2U(SCH_1):M_C_CPU0_SA_CA'<1>:
 C_SIGNAL='@s9s_mb_2u_lib.s9s_mb_2u(sch_1):m_c_cpu0_sa_ca(1)';
NODE_NAME     U2 AA52
 '@S9S_MB_2U_LIB.S9S_MB_2U(SCH_1):PAGE22_I169@PURE_QUANTA.SOCKET4677_AZIF0045P001C01CS(CHIPS)':
 'DDR2_SA_CA1': CDS_PINID='DDR2_SA_CA1';
NODE_NAME     J5 211
 '@S9S_MB_2U_LIB.S9S_MB_2U(SCH_1):PAGE86_I24@PURE_QUANTA.SCONN288_ADR50017P130CC(CHIPS)':
 'CA1_A': CDS_PINID='CA1_A';
NODE_NAME     J6 211
 '@S9S_MB_2U_LIB.S9S_MB_2U(SCH_1):PAGE87_I46@PURE_QUANTA.SCONN288_ADR50017P087CC(CHIPS)':
 'CA1_A': CDS_PINID='CA1_A';
NET_NAME
'M_C_CPU0_SA_CA<2>'
 '@S9S_MB_2U_LIB.S9S_MB_2U(SCH_1):M_C_CPU0_SA_CA'<2>:
 C_SIGNAL='@s9s_mb_2u_lib.s9s_mb_2u(sch_1):m_c_cpu0_sa_ca(2)';
NODE_NAME     U2 T51
 '@S9S_MB_2U_LIB.S9S_MB_2U(SCH_1):PAGE22_I169@PURE_QUANTA.SOCKET4677_AZIF0045P001C01CS(CHIPS)':
 'DDR2_SA_CA2': CDS_PINID='DDR2_SA_CA2';
NODE_NAME     J5 68
 '@S9S_MB_2U_LIB.S9S_MB_2U(SCH_1):PAGE86_I24@PURE_QUANTA.SCONN288_ADR50017P130CC(CHIPS)':
 'CA2_A': CDS_PINID='CA2_A';
NODE_NAME     J6 68
 '@S9S_MB_2U_LIB.S9S_MB_2U(SCH_1):PAGE87_I46@PURE_QUANTA.SCONN288_ADR50017P087CC(CHIPS)':
 'CA2_A': CDS_PINID='CA2_A';
NET_NAME
'M_C_CPU0_SA_CA<3>'
 '@S9S_MB_2U_LIB.S9S_MB_2U(SCH_1):M_C_CPU0_SA_CA'<3>:
 C_SIGNAL='@s9s_mb_2u_lib.s9s_mb_2u(sch_1):m_c_cpu0_sa_ca(3)';
NODE_NAME     U2 Y51
 '@S9S_MB_2U_LIB.S9S_MB_2U(SCH_1):PAGE22_I169@PURE_QUANTA.SOCKET4677_AZIF0045P001C01CS(CHIPS)':
 'DDR2_SA_CA3': CDS_PINID='DDR2_SA_CA3';
NODE_NAME     J5 213
 '@S9S_MB_2U_LIB.S9S_MB_2U(SCH_1):PAGE86_I24@PURE_QUANTA.SCONN288_ADR50017P130CC(CHIPS)':
 'CA3_A': CDS_PINID='CA3_A';
NODE_NAME     J6 213
 '@S9S_MB_2U_LIB.S9S_MB_2U(SCH_1):PAGE87_I46@PURE_QUANTA.SCONN288_ADR50017P087CC(CHIPS)':
 'CA3_A': CDS_PINID='CA3_A';
NET_NAME
'M_C_CPU0_SA_CA<4>'
 '@S9S_MB_2U_LIB.S9S_MB_2U(SCH_1):M_C_CPU0_SA_CA'<4>:
 C_SIGNAL='@s9s_mb_2u_lib.s9s_mb_2u(sch_1):m_c_cpu0_sa_ca(4)';
NODE_NAME     U2 U50
 '@S9S_MB_2U_LIB.S9S_MB_2U(SCH_1):PAGE22_I169@PURE_QUANTA.SOCKET4677_AZIF0045P001C01CS(CHIPS)':
 'DDR2_SA_CA4': CDS_PINID='DDR2_SA_CA4';
NODE_NAME     J5 70
 '@S9S_MB_2U_LIB.S9S_MB_2U(SCH_1):PAGE86_I24@PURE_QUANTA.SCONN288_ADR50017P130CC(CHIPS)':
 'CA4_A': CDS_PINID='CA4_A';
NODE_NAME     J6 70
 '@S9S_MB_2U_LIB.S9S_MB_2U(SCH_1):PAGE87_I46@PURE_QUANTA.SCONN288_ADR50017P087CC(CHIPS)':
 'CA4_A': CDS_PINID='CA4_A';
NET_NAME
'M_C_CPU0_SA_CA<5>'
 '@S9S_MB_2U_LIB.S9S_MB_2U(SCH_1):M_C_CPU0_SA_CA'<5>:
 C_SIGNAL='@s9s_mb_2u_lib.s9s_mb_2u(sch_1):m_c_cpu0_sa_ca(5)';
NODE_NAME     U2 W50
 '@S9S_MB_2U_LIB.S9S_MB_2U(SCH_1):PAGE22_I169@PURE_QUANTA.SOCKET4677_AZIF0045P001C01CS(CHIPS)':
 'DDR2_SA_CA5': CDS_PINID='DDR2_SA_CA5';
NODE_NAME     J5 215
 '@S9S_MB_2U_LIB.S9S_MB_2U(SCH_1):PAGE86_I24@PURE_QUANTA.SCONN288_ADR50017P130CC(CHIPS)':
 'CA5_A': CDS_PINID='CA5_A';
NODE_NAME     J6 215
 '@S9S_MB_2U_LIB.S9S_MB_2U(SCH_1):PAGE87_I46@PURE_QUANTA.SCONN288_ADR50017P087CC(CHIPS)':
 'CA5_A': CDS_PINID='CA5_A';
NET_NAME
'M_C_CPU0_SA_CA<6>'
 '@S9S_MB_2U_LIB.S9S_MB_2U(SCH_1):M_C_CPU0_SA_CA'<6>:
 C_SIGNAL='@s9s_mb_2u_lib.s9s_mb_2u(sch_1):m_c_cpu0_sa_ca(6)';
NODE_NAME     U2 U48
 '@S9S_MB_2U_LIB.S9S_MB_2U(SCH_1):PAGE22_I169@PURE_QUANTA.SOCKET4677_AZIF0045P001C01CS(CHIPS)':
 'DDR2_SA_CA6': CDS_PINID='DDR2_SA_CA6';
NODE_NAME     J5 72
 '@S9S_MB_2U_LIB.S9S_MB_2U(SCH_1):PAGE86_I24@PURE_QUANTA.SCONN288_ADR50017P130CC(CHIPS)':
 'CA6_A': CDS_PINID='CA6_A';
NODE_NAME     J6 72
 '@S9S_MB_2U_LIB.S9S_MB_2U(SCH_1):PAGE87_I46@PURE_QUANTA.SCONN288_ADR50017P087CC(CHIPS)':
 'CA6_A': CDS_PINID='CA6_A';
NET_NAME
'M_C_CPU0_SA_CB<0>'
 '@S9S_MB_2U_LIB.S9S_MB_2U(SCH_1):M_C_CPU0_SA_CB'<0>:
 C_SIGNAL='@s9s_mb_2u_lib.s9s_mb_2u(sch_1):m_c_cpu0_sa_cb(0)';
NODE_NAME     U2 AD57
 '@S9S_MB_2U_LIB.S9S_MB_2U(SCH_1):PAGE22_I169@PURE_QUANTA.SOCKET4677_AZIF0045P001C01CS(CHIPS)':
 'DDR2_SA_ECC0': CDS_PINID='DDR2_SA_ECC0';
NODE_NAME     J5 51
 '@S9S_MB_2U_LIB.S9S_MB_2U(SCH_1):PAGE86_I24@PURE_QUANTA.SCONN288_ADR50017P130CC(CHIPS)':
 'CB0_A': CDS_PINID='CB0_A';
NODE_NAME     J6 51
 '@S9S_MB_2U_LIB.S9S_MB_2U(SCH_1):PAGE87_I46@PURE_QUANTA.SCONN288_ADR50017P087CC(CHIPS)':
 'CB0_A': CDS_PINID='CB0_A';
NET_NAME
'M_C_CPU0_SA_CB<1>'
 '@S9S_MB_2U_LIB.S9S_MB_2U(SCH_1):M_C_CPU0_SA_CB'<1>:
 C_SIGNAL='@s9s_mb_2u_lib.s9s_mb_2u(sch_1):m_c_cpu0_sa_cb(1)';
NODE_NAME     U2 AC56
 '@S9S_MB_2U_LIB.S9S_MB_2U(SCH_1):PAGE22_I169@PURE_QUANTA.SOCKET4677_AZIF0045P001C01CS(CHIPS)':
 'DDR2_SA_ECC1': CDS_PINID='DDR2_SA_ECC1';
NODE_NAME     J5 53
 '@S9S_MB_2U_LIB.S9S_MB_2U(SCH_1):PAGE86_I24@PURE_QUANTA.SCONN288_ADR50017P130CC(CHIPS)':
 'CB1_A': CDS_PINID='CB1_A';
NODE_NAME     J6 53
 '@S9S_MB_2U_LIB.S9S_MB_2U(SCH_1):PAGE87_I46@PURE_QUANTA.SCONN288_ADR50017P087CC(CHIPS)':
 'CB1_A': CDS_PINID='CB1_A';
NET_NAME
'M_C_CPU0_SA_CB<2>'
 '@S9S_MB_2U_LIB.S9S_MB_2U(SCH_1):M_C_CPU0_SA_CB'<2>:
 C_SIGNAL='@s9s_mb_2u_lib.s9s_mb_2u(sch_1):m_c_cpu0_sa_cb(2)';
NODE_NAME     U2 AF57
 '@S9S_MB_2U_LIB.S9S_MB_2U(SCH_1):PAGE22_I169@PURE_QUANTA.SOCKET4677_AZIF0045P001C01CS(CHIPS)':
 'DDR2_SA_ECC2': CDS_PINID='DDR2_SA_ECC2';
NODE_NAME     J5 196
 '@S9S_MB_2U_LIB.S9S_MB_2U(SCH_1):PAGE86_I24@PURE_QUANTA.SCONN288_ADR50017P130CC(CHIPS)':
 'CB2_A': CDS_PINID='CB2_A';
NODE_NAME     J6 196
 '@S9S_MB_2U_LIB.S9S_MB_2U(SCH_1):PAGE87_I46@PURE_QUANTA.SCONN288_ADR50017P087CC(CHIPS)':
 'CB2_A': CDS_PINID='CB2_A';
NET_NAME
'M_C_CPU0_SA_CB<3>'
 '@S9S_MB_2U_LIB.S9S_MB_2U(SCH_1):M_C_CPU0_SA_CB'<3>:
 C_SIGNAL='@s9s_mb_2u_lib.s9s_mb_2u(sch_1):m_c_cpu0_sa_cb(3)';
NODE_NAME     U2 AG56
 '@S9S_MB_2U_LIB.S9S_MB_2U(SCH_1):PAGE22_I169@PURE_QUANTA.SOCKET4677_AZIF0045P001C01CS(CHIPS)':
 'DDR2_SA_ECC3': CDS_PINID='DDR2_SA_ECC3';
NODE_NAME     J5 198
 '@S9S_MB_2U_LIB.S9S_MB_2U(SCH_1):PAGE86_I24@PURE_QUANTA.SCONN288_ADR50017P130CC(CHIPS)':
 'CB3_A': CDS_PINID='CB3_A';
NODE_NAME     J6 198
 '@S9S_MB_2U_LIB.S9S_MB_2U(SCH_1):PAGE87_I46@PURE_QUANTA.SCONN288_ADR50017P087CC(CHIPS)':
 'CB3_A': CDS_PINID='CB3_A';
NET_NAME
'M_C_CPU0_SA_CB<4>'
 '@S9S_MB_2U_LIB.S9S_MB_2U(SCH_1):M_C_CPU0_SA_CB'<4>:
 C_SIGNAL='@s9s_mb_2u_lib.s9s_mb_2u(sch_1):m_c_cpu0_sa_cb(4)';
NODE_NAME     U2 AC54
 '@S9S_MB_2U_LIB.S9S_MB_2U(SCH_1):PAGE22_I169@PURE_QUANTA.SOCKET4677_AZIF0045P001C01CS(CHIPS)':
 'DDR2_SA_ECC4': CDS_PINID='DDR2_SA_ECC4';
NODE_NAME     J5 58
 '@S9S_MB_2U_LIB.S9S_MB_2U(SCH_1):PAGE86_I24@PURE_QUANTA.SCONN288_ADR50017P130CC(CHIPS)':
 'CB4_A': CDS_PINID='CB4_A';
NODE_NAME     J6 58
 '@S9S_MB_2U_LIB.S9S_MB_2U(SCH_1):PAGE87_I46@PURE_QUANTA.SCONN288_ADR50017P087CC(CHIPS)':
 'CB4_A': CDS_PINID='CB4_A';
NET_NAME
'M_C_CPU0_SA_CB<5>'
 '@S9S_MB_2U_LIB.S9S_MB_2U(SCH_1):M_C_CPU0_SA_CB'<5>:
 C_SIGNAL='@s9s_mb_2u_lib.s9s_mb_2u(sch_1):m_c_cpu0_sa_cb(5)';
NODE_NAME     U2 AD53
 '@S9S_MB_2U_LIB.S9S_MB_2U(SCH_1):PAGE22_I169@PURE_QUANTA.SOCKET4677_AZIF0045P001C01CS(CHIPS)':
 'DDR2_SA_ECC5': CDS_PINID='DDR2_SA_ECC5';
NODE_NAME     J5 60
 '@S9S_MB_2U_LIB.S9S_MB_2U(SCH_1):PAGE86_I24@PURE_QUANTA.SCONN288_ADR50017P130CC(CHIPS)':
 'CB5_A': CDS_PINID='CB5_A';
NODE_NAME     J6 60
 '@S9S_MB_2U_LIB.S9S_MB_2U(SCH_1):PAGE87_I46@PURE_QUANTA.SCONN288_ADR50017P087CC(CHIPS)':
 'CB5_A': CDS_PINID='CB5_A';
NET_NAME
'M_C_CPU0_SA_CB<6>'
 '@S9S_MB_2U_LIB.S9S_MB_2U(SCH_1):M_C_CPU0_SA_CB'<6>:
 C_SIGNAL='@s9s_mb_2u_lib.s9s_mb_2u(sch_1):m_c_cpu0_sa_cb(6)';
NODE_NAME     U2 AG54
 '@S9S_MB_2U_LIB.S9S_MB_2U(SCH_1):PAGE22_I169@PURE_QUANTA.SOCKET4677_AZIF0045P001C01CS(CHIPS)':
 'DDR2_SA_ECC6': CDS_PINID='DDR2_SA_ECC6';
NODE_NAME     J5 203
 '@S9S_MB_2U_LIB.S9S_MB_2U(SCH_1):PAGE86_I24@PURE_QUANTA.SCONN288_ADR50017P130CC(CHIPS)':
 'CB6_A': CDS_PINID='CB6_A';
NODE_NAME     J6 203
 '@S9S_MB_2U_LIB.S9S_MB_2U(SCH_1):PAGE87_I46@PURE_QUANTA.SCONN288_ADR50017P087CC(CHIPS)':
 'CB6_A': CDS_PINID='CB6_A';
NET_NAME
'M_C_CPU0_SA_CB<7>'
 '@S9S_MB_2U_LIB.S9S_MB_2U(SCH_1):M_C_CPU0_SA_CB'<7>:
 C_SIGNAL='@s9s_mb_2u_lib.s9s_mb_2u(sch_1):m_c_cpu0_sa_cb(7)';
NODE_NAME     U2 AF53
 '@S9S_MB_2U_LIB.S9S_MB_2U(SCH_1):PAGE22_I169@PURE_QUANTA.SOCKET4677_AZIF0045P001C01CS(CHIPS)':
 'DDR2_SA_ECC7': CDS_PINID='DDR2_SA_ECC7';
NODE_NAME     J5 205
 '@S9S_MB_2U_LIB.S9S_MB_2U(SCH_1):PAGE86_I24@PURE_QUANTA.SCONN288_ADR50017P130CC(CHIPS)':
 'CB7_A': CDS_PINID='CB7_A';
NODE_NAME     J6 205
 '@S9S_MB_2U_LIB.S9S_MB_2U(SCH_1):PAGE87_I46@PURE_QUANTA.SCONN288_ADR50017P087CC(CHIPS)':
 'CB7_A': CDS_PINID='CB7_A';
NET_NAME
'M_C_CPU0_SA_CS_N<0>'
 '@S9S_MB_2U_LIB.S9S_MB_2U(SCH_1):M_C_CPU0_SA_CS_N'<0>:
 C_SIGNAL='@s9s_mb_2u_lib.s9s_mb_2u(sch_1):m_c_cpu0_sa_cs_n(0)';
NODE_NAME     U2 U54
 '@S9S_MB_2U_LIB.S9S_MB_2U(SCH_1):PAGE22_I169@PURE_QUANTA.SOCKET4677_AZIF0045P001C01CS(CHIPS)':
 'DDR2_SA_CS_N0': CDS_PINID='DDR2_SA_CS_N0';
NODE_NAME     J5 64
 '@S9S_MB_2U_LIB.S9S_MB_2U(SCH_1):PAGE86_I24@PURE_QUANTA.SCONN288_ADR50017P130CC(CHIPS)':
 'CS0_A_N': CDS_PINID='CS0_A_N';
NET_NAME
'M_C_CPU0_SA_CS_N<1>'
 '@S9S_MB_2U_LIB.S9S_MB_2U(SCH_1):M_C_CPU0_SA_CS_N'<1>:
 C_SIGNAL='@s9s_mb_2u_lib.s9s_mb_2u(sch_1):m_c_cpu0_sa_cs_n(1)';
NODE_NAME     U2 T53
 '@S9S_MB_2U_LIB.S9S_MB_2U(SCH_1):PAGE22_I169@PURE_QUANTA.SOCKET4677_AZIF0045P001C01CS(CHIPS)':
 'DDR2_SA_CS_N1': CDS_PINID='DDR2_SA_CS_N1';
NODE_NAME     J5 209
 '@S9S_MB_2U_LIB.S9S_MB_2U(SCH_1):PAGE86_I24@PURE_QUANTA.SCONN288_ADR50017P130CC(CHIPS)':
 'CS1_A_N': CDS_PINID='CS1_A_N';
NET_NAME
'M_C_CPU0_SA_CS_N<2>'
 '@S9S_MB_2U_LIB.S9S_MB_2U(SCH_1):M_C_CPU0_SA_CS_N'<2>:
 C_SIGNAL='@s9s_mb_2u_lib.s9s_mb_2u(sch_1):m_c_cpu0_sa_cs_n(2)';
NODE_NAME     U2 W54
 '@S9S_MB_2U_LIB.S9S_MB_2U(SCH_1):PAGE22_I169@PURE_QUANTA.SOCKET4677_AZIF0045P001C01CS(CHIPS)':
 'DDR2_SA_CS_N2': CDS_PINID='DDR2_SA_CS_N2';
NODE_NAME     J6 64
 '@S9S_MB_2U_LIB.S9S_MB_2U(SCH_1):PAGE87_I46@PURE_QUANTA.SCONN288_ADR50017P087CC(CHIPS)':
 'CS0_A_N': CDS_PINID='CS0_A_N';
NET_NAME
'M_C_CPU0_SA_CS_N<3>'
 '@S9S_MB_2U_LIB.S9S_MB_2U(SCH_1):M_C_CPU0_SA_CS_N'<3>:
 C_SIGNAL='@s9s_mb_2u_lib.s9s_mb_2u(sch_1):m_c_cpu0_sa_cs_n(3)';
NODE_NAME     U2 Y53
 '@S9S_MB_2U_LIB.S9S_MB_2U(SCH_1):PAGE22_I169@PURE_QUANTA.SOCKET4677_AZIF0045P001C01CS(CHIPS)':
 'DDR2_SA_CS_N3': CDS_PINID='DDR2_SA_CS_N3';
NODE_NAME     J6 209
 '@S9S_MB_2U_LIB.S9S_MB_2U(SCH_1):PAGE87_I46@PURE_QUANTA.SCONN288_ADR50017P087CC(CHIPS)':
 'CS1_A_N': CDS_PINID='CS1_A_N';
NET_NAME
'M_C_CPU0_SA_DQ<0>'
 '@S9S_MB_2U_LIB.S9S_MB_2U(SCH_1):M_C_CPU0_SA_DQ'<0>:
 C_SIGNAL='@s9s_mb_2u_lib.s9s_mb_2u(sch_1):m_c_cpu0_sa_dq(0)';
NODE_NAME     U2 U78
 '@S9S_MB_2U_LIB.S9S_MB_2U(SCH_1):PAGE22_I169@PURE_QUANTA.SOCKET4677_AZIF0045P001C01CS(CHIPS)':
 'DDR2_SA_DQ0': CDS_PINID='DDR2_SA_DQ0';
NODE_NAME     J5 7
 '@S9S_MB_2U_LIB.S9S_MB_2U(SCH_1):PAGE86_I24@PURE_QUANTA.SCONN288_ADR50017P130CC(CHIPS)':
 'DQ0_A': CDS_PINID='DQ0_A';
NODE_NAME     J6 7
 '@S9S_MB_2U_LIB.S9S_MB_2U(SCH_1):PAGE87_I46@PURE_QUANTA.SCONN288_ADR50017P087CC(CHIPS)':
 'DQ0_A': CDS_PINID='DQ0_A';
NET_NAME
'M_C_CPU0_SA_DQ<10>'
 '@S9S_MB_2U_LIB.S9S_MB_2U(SCH_1):M_C_CPU0_SA_DQ'<10>:
 C_SIGNAL='@s9s_mb_2u_lib.s9s_mb_2u(sch_1):m_c_cpu0_sa_dq(10)';
NODE_NAME     U2 AF69
 '@S9S_MB_2U_LIB.S9S_MB_2U(SCH_1):PAGE22_I169@PURE_QUANTA.SOCKET4677_AZIF0045P001C01CS(CHIPS)':
 'DDR2_SA_DQ10': CDS_PINID='DDR2_SA_DQ10';
NODE_NAME     J5 163
 '@S9S_MB_2U_LIB.S9S_MB_2U(SCH_1):PAGE86_I24@PURE_QUANTA.SCONN288_ADR50017P130CC(CHIPS)':
 'DQ10_A': CDS_PINID='DQ10_A';
NODE_NAME     J6 163
 '@S9S_MB_2U_LIB.S9S_MB_2U(SCH_1):PAGE87_I46@PURE_QUANTA.SCONN288_ADR50017P087CC(CHIPS)':
 'DQ10_A': CDS_PINID='DQ10_A';
NET_NAME
'M_C_CPU0_SA_DQ<11>'
 '@S9S_MB_2U_LIB.S9S_MB_2U(SCH_1):M_C_CPU0_SA_DQ'<11>:
 C_SIGNAL='@s9s_mb_2u_lib.s9s_mb_2u(sch_1):m_c_cpu0_sa_dq(11)';
NODE_NAME     U2 AG68
 '@S9S_MB_2U_LIB.S9S_MB_2U(SCH_1):PAGE22_I169@PURE_QUANTA.SOCKET4677_AZIF0045P001C01CS(CHIPS)':
 'DDR2_SA_DQ11': CDS_PINID='DDR2_SA_DQ11';
NODE_NAME     J5 165
 '@S9S_MB_2U_LIB.S9S_MB_2U(SCH_1):PAGE86_I24@PURE_QUANTA.SCONN288_ADR50017P130CC(CHIPS)':
 'DQ11_A': CDS_PINID='DQ11_A';
NODE_NAME     J6 165
 '@S9S_MB_2U_LIB.S9S_MB_2U(SCH_1):PAGE87_I46@PURE_QUANTA.SCONN288_ADR50017P087CC(CHIPS)':
 'DQ11_A': CDS_PINID='DQ11_A';
NET_NAME
'M_C_CPU0_SA_DQ<12>'
 '@S9S_MB_2U_LIB.S9S_MB_2U(SCH_1):M_C_CPU0_SA_DQ'<12>:
 C_SIGNAL='@s9s_mb_2u_lib.s9s_mb_2u(sch_1):m_c_cpu0_sa_dq(12)';
NODE_NAME     U2 AC66
 '@S9S_MB_2U_LIB.S9S_MB_2U(SCH_1):PAGE22_I169@PURE_QUANTA.SOCKET4677_AZIF0045P001C01CS(CHIPS)':
 'DDR2_SA_DQ12': CDS_PINID='DDR2_SA_DQ12';
NODE_NAME     J5 25
 '@S9S_MB_2U_LIB.S9S_MB_2U(SCH_1):PAGE86_I24@PURE_QUANTA.SCONN288_ADR50017P130CC(CHIPS)':
 'DQ12_A': CDS_PINID='DQ12_A';
NODE_NAME     J6 25
 '@S9S_MB_2U_LIB.S9S_MB_2U(SCH_1):PAGE87_I46@PURE_QUANTA.SCONN288_ADR50017P087CC(CHIPS)':
 'DQ12_A': CDS_PINID='DQ12_A';
NET_NAME
'M_C_CPU0_SA_DQ<13>'
 '@S9S_MB_2U_LIB.S9S_MB_2U(SCH_1):M_C_CPU0_SA_DQ'<13>:
 C_SIGNAL='@s9s_mb_2u_lib.s9s_mb_2u(sch_1):m_c_cpu0_sa_dq(13)';
NODE_NAME     U2 AD65
 '@S9S_MB_2U_LIB.S9S_MB_2U(SCH_1):PAGE22_I169@PURE_QUANTA.SOCKET4677_AZIF0045P001C01CS(CHIPS)':
 'DDR2_SA_DQ13': CDS_PINID='DDR2_SA_DQ13';
NODE_NAME     J5 27
 '@S9S_MB_2U_LIB.S9S_MB_2U(SCH_1):PAGE86_I24@PURE_QUANTA.SCONN288_ADR50017P130CC(CHIPS)':
 'DQ13_A': CDS_PINID='DQ13_A';
NODE_NAME     J6 27
 '@S9S_MB_2U_LIB.S9S_MB_2U(SCH_1):PAGE87_I46@PURE_QUANTA.SCONN288_ADR50017P087CC(CHIPS)':
 'DQ13_A': CDS_PINID='DQ13_A';
NET_NAME
'M_C_CPU0_SA_DQ<14>'
 '@S9S_MB_2U_LIB.S9S_MB_2U(SCH_1):M_C_CPU0_SA_DQ'<14>:
 C_SIGNAL='@s9s_mb_2u_lib.s9s_mb_2u(sch_1):m_c_cpu0_sa_dq(14)';
NODE_NAME     U2 AG66
 '@S9S_MB_2U_LIB.S9S_MB_2U(SCH_1):PAGE22_I169@PURE_QUANTA.SOCKET4677_AZIF0045P001C01CS(CHIPS)':
 'DDR2_SA_DQ14': CDS_PINID='DDR2_SA_DQ14';
NODE_NAME     J5 170
 '@S9S_MB_2U_LIB.S9S_MB_2U(SCH_1):PAGE86_I24@PURE_QUANTA.SCONN288_ADR50017P130CC(CHIPS)':
 'DQ14_A': CDS_PINID='DQ14_A';
NODE_NAME     J6 170
 '@S9S_MB_2U_LIB.S9S_MB_2U(SCH_1):PAGE87_I46@PURE_QUANTA.SCONN288_ADR50017P087CC(CHIPS)':
 'DQ14_A': CDS_PINID='DQ14_A';
NET_NAME
'M_C_CPU0_SA_DQ<15>'
 '@S9S_MB_2U_LIB.S9S_MB_2U(SCH_1):M_C_CPU0_SA_DQ'<15>:
 C_SIGNAL='@s9s_mb_2u_lib.s9s_mb_2u(sch_1):m_c_cpu0_sa_dq(15)';
NODE_NAME     U2 AF65
 '@S9S_MB_2U_LIB.S9S_MB_2U(SCH_1):PAGE22_I169@PURE_QUANTA.SOCKET4677_AZIF0045P001C01CS(CHIPS)':
 'DDR2_SA_DQ15': CDS_PINID='DDR2_SA_DQ15';
NODE_NAME     J5 172
 '@S9S_MB_2U_LIB.S9S_MB_2U(SCH_1):PAGE86_I24@PURE_QUANTA.SCONN288_ADR50017P130CC(CHIPS)':
 'DQ15_A': CDS_PINID='DQ15_A';
NODE_NAME     J6 172
 '@S9S_MB_2U_LIB.S9S_MB_2U(SCH_1):PAGE87_I46@PURE_QUANTA.SCONN288_ADR50017P087CC(CHIPS)':
 'DQ15_A': CDS_PINID='DQ15_A';
NET_NAME
'M_C_CPU0_SA_DQ<16>'
 '@S9S_MB_2U_LIB.S9S_MB_2U(SCH_1):M_C_CPU0_SA_DQ'<16>:
 C_SIGNAL='@s9s_mb_2u_lib.s9s_mb_2u(sch_1):m_c_cpu0_sa_dq(16)';
NODE_NAME     U2 U66
 '@S9S_MB_2U_LIB.S9S_MB_2U(SCH_1):PAGE22_I169@PURE_QUANTA.SOCKET4677_AZIF0045P001C01CS(CHIPS)':
 'DDR2_SA_DQ16': CDS_PINID='DDR2_SA_DQ16';
NODE_NAME     J5 29
 '@S9S_MB_2U_LIB.S9S_MB_2U(SCH_1):PAGE86_I24@PURE_QUANTA.SCONN288_ADR50017P130CC(CHIPS)':
 'DQ16_A': CDS_PINID='DQ16_A';
NODE_NAME     J6 29
 '@S9S_MB_2U_LIB.S9S_MB_2U(SCH_1):PAGE87_I46@PURE_QUANTA.SCONN288_ADR50017P087CC(CHIPS)':
 'DQ16_A': CDS_PINID='DQ16_A';
NET_NAME
'M_C_CPU0_SA_DQ<17>'
 '@S9S_MB_2U_LIB.S9S_MB_2U(SCH_1):M_C_CPU0_SA_DQ'<17>:
 C_SIGNAL='@s9s_mb_2u_lib.s9s_mb_2u(sch_1):m_c_cpu0_sa_dq(17)';
NODE_NAME     U2 T65
 '@S9S_MB_2U_LIB.S9S_MB_2U(SCH_1):PAGE22_I169@PURE_QUANTA.SOCKET4677_AZIF0045P001C01CS(CHIPS)':
 'DDR2_SA_DQ17': CDS_PINID='DDR2_SA_DQ17';
NODE_NAME     J5 31
 '@S9S_MB_2U_LIB.S9S_MB_2U(SCH_1):PAGE86_I24@PURE_QUANTA.SCONN288_ADR50017P130CC(CHIPS)':
 'DQ17_A': CDS_PINID='DQ17_A';
NODE_NAME     J6 31
 '@S9S_MB_2U_LIB.S9S_MB_2U(SCH_1):PAGE87_I46@PURE_QUANTA.SCONN288_ADR50017P087CC(CHIPS)':
 'DQ17_A': CDS_PINID='DQ17_A';
NET_NAME
'M_C_CPU0_SA_DQ<18>'
 '@S9S_MB_2U_LIB.S9S_MB_2U(SCH_1):M_C_CPU0_SA_DQ'<18>:
 C_SIGNAL='@s9s_mb_2u_lib.s9s_mb_2u(sch_1):m_c_cpu0_sa_dq(18)';
NODE_NAME     U2 W66
 '@S9S_MB_2U_LIB.S9S_MB_2U(SCH_1):PAGE22_I169@PURE_QUANTA.SOCKET4677_AZIF0045P001C01CS(CHIPS)':
 'DDR2_SA_DQ18': CDS_PINID='DDR2_SA_DQ18';
NODE_NAME     J5 174
 '@S9S_MB_2U_LIB.S9S_MB_2U(SCH_1):PAGE86_I24@PURE_QUANTA.SCONN288_ADR50017P130CC(CHIPS)':
 'DQ18_A': CDS_PINID='DQ18_A';
NODE_NAME     J6 174
 '@S9S_MB_2U_LIB.S9S_MB_2U(SCH_1):PAGE87_I46@PURE_QUANTA.SCONN288_ADR50017P087CC(CHIPS)':
 'DQ18_A': CDS_PINID='DQ18_A';
NET_NAME
'M_C_CPU0_SA_DQ<19>'
 '@S9S_MB_2U_LIB.S9S_MB_2U(SCH_1):M_C_CPU0_SA_DQ'<19>:
 C_SIGNAL='@s9s_mb_2u_lib.s9s_mb_2u(sch_1):m_c_cpu0_sa_dq(19)';
NODE_NAME     U2 Y65
 '@S9S_MB_2U_LIB.S9S_MB_2U(SCH_1):PAGE22_I169@PURE_QUANTA.SOCKET4677_AZIF0045P001C01CS(CHIPS)':
 'DDR2_SA_DQ19': CDS_PINID='DDR2_SA_DQ19';
NODE_NAME     J5 176
 '@S9S_MB_2U_LIB.S9S_MB_2U(SCH_1):PAGE86_I24@PURE_QUANTA.SCONN288_ADR50017P130CC(CHIPS)':
 'DQ19_A': CDS_PINID='DQ19_A';
NODE_NAME     J6 176
 '@S9S_MB_2U_LIB.S9S_MB_2U(SCH_1):PAGE87_I46@PURE_QUANTA.SCONN288_ADR50017P087CC(CHIPS)':
 'DQ19_A': CDS_PINID='DQ19_A';
NET_NAME
'M_C_CPU0_SA_DQ<1>'
 '@S9S_MB_2U_LIB.S9S_MB_2U(SCH_1):M_C_CPU0_SA_DQ'<1>:
 C_SIGNAL='@s9s_mb_2u_lib.s9s_mb_2u(sch_1):m_c_cpu0_sa_dq(1)';
NODE_NAME     U2 T77
 '@S9S_MB_2U_LIB.S9S_MB_2U(SCH_1):PAGE22_I169@PURE_QUANTA.SOCKET4677_AZIF0045P001C01CS(CHIPS)':
 'DDR2_SA_DQ1': CDS_PINID='DDR2_SA_DQ1';
NODE_NAME     J5 9
 '@S9S_MB_2U_LIB.S9S_MB_2U(SCH_1):PAGE86_I24@PURE_QUANTA.SCONN288_ADR50017P130CC(CHIPS)':
 'DQ1_A': CDS_PINID='DQ1_A';
NODE_NAME     J6 9
 '@S9S_MB_2U_LIB.S9S_MB_2U(SCH_1):PAGE87_I46@PURE_QUANTA.SCONN288_ADR50017P087CC(CHIPS)':
 'DQ1_A': CDS_PINID='DQ1_A';
NET_NAME
'M_C_CPU0_SA_DQ<20>'
 '@S9S_MB_2U_LIB.S9S_MB_2U(SCH_1):M_C_CPU0_SA_DQ'<20>:
 C_SIGNAL='@s9s_mb_2u_lib.s9s_mb_2u(sch_1):m_c_cpu0_sa_dq(20)';
NODE_NAME     U2 T63
 '@S9S_MB_2U_LIB.S9S_MB_2U(SCH_1):PAGE22_I169@PURE_QUANTA.SOCKET4677_AZIF0045P001C01CS(CHIPS)':
 'DDR2_SA_DQ20': CDS_PINID='DDR2_SA_DQ20';
NODE_NAME     J5 36
 '@S9S_MB_2U_LIB.S9S_MB_2U(SCH_1):PAGE86_I24@PURE_QUANTA.SCONN288_ADR50017P130CC(CHIPS)':
 'DQ20_A': CDS_PINID='DQ20_A';
NODE_NAME     J6 36
 '@S9S_MB_2U_LIB.S9S_MB_2U(SCH_1):PAGE87_I46@PURE_QUANTA.SCONN288_ADR50017P087CC(CHIPS)':
 'DQ20_A': CDS_PINID='DQ20_A';
NET_NAME
'M_C_CPU0_SA_DQ<21>'
 '@S9S_MB_2U_LIB.S9S_MB_2U(SCH_1):M_C_CPU0_SA_DQ'<21>:
 C_SIGNAL='@s9s_mb_2u_lib.s9s_mb_2u(sch_1):m_c_cpu0_sa_dq(21)';
NODE_NAME     U2 U62
 '@S9S_MB_2U_LIB.S9S_MB_2U(SCH_1):PAGE22_I169@PURE_QUANTA.SOCKET4677_AZIF0045P001C01CS(CHIPS)':
 'DDR2_SA_DQ21': CDS_PINID='DDR2_SA_DQ21';
NODE_NAME     J5 38
 '@S9S_MB_2U_LIB.S9S_MB_2U(SCH_1):PAGE86_I24@PURE_QUANTA.SCONN288_ADR50017P130CC(CHIPS)':
 'DQ21_A': CDS_PINID='DQ21_A';
NODE_NAME     J6 38
 '@S9S_MB_2U_LIB.S9S_MB_2U(SCH_1):PAGE87_I46@PURE_QUANTA.SCONN288_ADR50017P087CC(CHIPS)':
 'DQ21_A': CDS_PINID='DQ21_A';
NET_NAME
'M_C_CPU0_SA_DQ<22>'
 '@S9S_MB_2U_LIB.S9S_MB_2U(SCH_1):M_C_CPU0_SA_DQ'<22>:
 C_SIGNAL='@s9s_mb_2u_lib.s9s_mb_2u(sch_1):m_c_cpu0_sa_dq(22)';
NODE_NAME     U2 Y63
 '@S9S_MB_2U_LIB.S9S_MB_2U(SCH_1):PAGE22_I169@PURE_QUANTA.SOCKET4677_AZIF0045P001C01CS(CHIPS)':
 'DDR2_SA_DQ22': CDS_PINID='DDR2_SA_DQ22';
NODE_NAME     J5 181
 '@S9S_MB_2U_LIB.S9S_MB_2U(SCH_1):PAGE86_I24@PURE_QUANTA.SCONN288_ADR50017P130CC(CHIPS)':
 'DQ22_A': CDS_PINID='DQ22_A';
NODE_NAME     J6 181
 '@S9S_MB_2U_LIB.S9S_MB_2U(SCH_1):PAGE87_I46@PURE_QUANTA.SCONN288_ADR50017P087CC(CHIPS)':
 'DQ22_A': CDS_PINID='DQ22_A';
NET_NAME
'M_C_CPU0_SA_DQ<23>'
 '@S9S_MB_2U_LIB.S9S_MB_2U(SCH_1):M_C_CPU0_SA_DQ'<23>:
 C_SIGNAL='@s9s_mb_2u_lib.s9s_mb_2u(sch_1):m_c_cpu0_sa_dq(23)';
NODE_NAME     U2 W62
 '@S9S_MB_2U_LIB.S9S_MB_2U(SCH_1):PAGE22_I169@PURE_QUANTA.SOCKET4677_AZIF0045P001C01CS(CHIPS)':
 'DDR2_SA_DQ23': CDS_PINID='DDR2_SA_DQ23';
NODE_NAME     J5 183
 '@S9S_MB_2U_LIB.S9S_MB_2U(SCH_1):PAGE86_I24@PURE_QUANTA.SCONN288_ADR50017P130CC(CHIPS)':
 'DQ23_A': CDS_PINID='DQ23_A';
NODE_NAME     J6 183
 '@S9S_MB_2U_LIB.S9S_MB_2U(SCH_1):PAGE87_I46@PURE_QUANTA.SCONN288_ADR50017P087CC(CHIPS)':
 'DQ23_A': CDS_PINID='DQ23_A';
NET_NAME
'M_C_CPU0_SA_DQ<24>'
 '@S9S_MB_2U_LIB.S9S_MB_2U(SCH_1):M_C_CPU0_SA_DQ'<24>:
 C_SIGNAL='@s9s_mb_2u_lib.s9s_mb_2u(sch_1):m_c_cpu0_sa_dq(24)';
NODE_NAME     U2 AD63
 '@S9S_MB_2U_LIB.S9S_MB_2U(SCH_1):PAGE22_I169@PURE_QUANTA.SOCKET4677_AZIF0045P001C01CS(CHIPS)':
 'DDR2_SA_DQ24': CDS_PINID='DDR2_SA_DQ24';
NODE_NAME     J5 40
 '@S9S_MB_2U_LIB.S9S_MB_2U(SCH_1):PAGE86_I24@PURE_QUANTA.SCONN288_ADR50017P130CC(CHIPS)':
 'DQ24_A': CDS_PINID='DQ24_A';
NODE_NAME     J6 40
 '@S9S_MB_2U_LIB.S9S_MB_2U(SCH_1):PAGE87_I46@PURE_QUANTA.SCONN288_ADR50017P087CC(CHIPS)':
 'DQ24_A': CDS_PINID='DQ24_A';
NET_NAME
'M_C_CPU0_SA_DQ<25>'
 '@S9S_MB_2U_LIB.S9S_MB_2U(SCH_1):M_C_CPU0_SA_DQ'<25>:
 C_SIGNAL='@s9s_mb_2u_lib.s9s_mb_2u(sch_1):m_c_cpu0_sa_dq(25)';
NODE_NAME     U2 AC62
 '@S9S_MB_2U_LIB.S9S_MB_2U(SCH_1):PAGE22_I169@PURE_QUANTA.SOCKET4677_AZIF0045P001C01CS(CHIPS)':
 'DDR2_SA_DQ25': CDS_PINID='DDR2_SA_DQ25';
NODE_NAME     J5 42
 '@S9S_MB_2U_LIB.S9S_MB_2U(SCH_1):PAGE86_I24@PURE_QUANTA.SCONN288_ADR50017P130CC(CHIPS)':
 'DQ25_A': CDS_PINID='DQ25_A';
NODE_NAME     J6 42
 '@S9S_MB_2U_LIB.S9S_MB_2U(SCH_1):PAGE87_I46@PURE_QUANTA.SCONN288_ADR50017P087CC(CHIPS)':
 'DQ25_A': CDS_PINID='DQ25_A';
NET_NAME
'M_C_CPU0_SA_DQ<26>'
 '@S9S_MB_2U_LIB.S9S_MB_2U(SCH_1):M_C_CPU0_SA_DQ'<26>:
 C_SIGNAL='@s9s_mb_2u_lib.s9s_mb_2u(sch_1):m_c_cpu0_sa_dq(26)';
NODE_NAME     U2 AF63
 '@S9S_MB_2U_LIB.S9S_MB_2U(SCH_1):PAGE22_I169@PURE_QUANTA.SOCKET4677_AZIF0045P001C01CS(CHIPS)':
 'DDR2_SA_DQ26': CDS_PINID='DDR2_SA_DQ26';
NODE_NAME     J5 185
 '@S9S_MB_2U_LIB.S9S_MB_2U(SCH_1):PAGE86_I24@PURE_QUANTA.SCONN288_ADR50017P130CC(CHIPS)':
 'DQ26_A': CDS_PINID='DQ26_A';
NODE_NAME     J6 185
 '@S9S_MB_2U_LIB.S9S_MB_2U(SCH_1):PAGE87_I46@PURE_QUANTA.SCONN288_ADR50017P087CC(CHIPS)':
 'DQ26_A': CDS_PINID='DQ26_A';
NET_NAME
'M_C_CPU0_SA_DQ<27>'
 '@S9S_MB_2U_LIB.S9S_MB_2U(SCH_1):M_C_CPU0_SA_DQ'<27>:
 C_SIGNAL='@s9s_mb_2u_lib.s9s_mb_2u(sch_1):m_c_cpu0_sa_dq(27)';
NODE_NAME     U2 AG62
 '@S9S_MB_2U_LIB.S9S_MB_2U(SCH_1):PAGE22_I169@PURE_QUANTA.SOCKET4677_AZIF0045P001C01CS(CHIPS)':
 'DDR2_SA_DQ27': CDS_PINID='DDR2_SA_DQ27';
NODE_NAME     J5 187
 '@S9S_MB_2U_LIB.S9S_MB_2U(SCH_1):PAGE86_I24@PURE_QUANTA.SCONN288_ADR50017P130CC(CHIPS)':
 'DQ27_A': CDS_PINID='DQ27_A';
NODE_NAME     J6 187
 '@S9S_MB_2U_LIB.S9S_MB_2U(SCH_1):PAGE87_I46@PURE_QUANTA.SCONN288_ADR50017P087CC(CHIPS)':
 'DQ27_A': CDS_PINID='DQ27_A';
NET_NAME
'M_C_CPU0_SA_DQ<28>'
 '@S9S_MB_2U_LIB.S9S_MB_2U(SCH_1):M_C_CPU0_SA_DQ'<28>:
 C_SIGNAL='@s9s_mb_2u_lib.s9s_mb_2u(sch_1):m_c_cpu0_sa_dq(28)';
NODE_NAME     U2 AC60
 '@S9S_MB_2U_LIB.S9S_MB_2U(SCH_1):PAGE22_I169@PURE_QUANTA.SOCKET4677_AZIF0045P001C01CS(CHIPS)':
 'DDR2_SA_DQ28': CDS_PINID='DDR2_SA_DQ28';
NODE_NAME     J5 47
 '@S9S_MB_2U_LIB.S9S_MB_2U(SCH_1):PAGE86_I24@PURE_QUANTA.SCONN288_ADR50017P130CC(CHIPS)':
 'DQ28_A': CDS_PINID='DQ28_A';
NODE_NAME     J6 47
 '@S9S_MB_2U_LIB.S9S_MB_2U(SCH_1):PAGE87_I46@PURE_QUANTA.SCONN288_ADR50017P087CC(CHIPS)':
 'DQ28_A': CDS_PINID='DQ28_A';
NET_NAME
'M_C_CPU0_SA_DQ<29>'
 '@S9S_MB_2U_LIB.S9S_MB_2U(SCH_1):M_C_CPU0_SA_DQ'<29>:
 C_SIGNAL='@s9s_mb_2u_lib.s9s_mb_2u(sch_1):m_c_cpu0_sa_dq(29)';
NODE_NAME     U2 AD59
 '@S9S_MB_2U_LIB.S9S_MB_2U(SCH_1):PAGE22_I169@PURE_QUANTA.SOCKET4677_AZIF0045P001C01CS(CHIPS)':
 'DDR2_SA_DQ29': CDS_PINID='DDR2_SA_DQ29';
NODE_NAME     J5 49
 '@S9S_MB_2U_LIB.S9S_MB_2U(SCH_1):PAGE86_I24@PURE_QUANTA.SCONN288_ADR50017P130CC(CHIPS)':
 'DQ29_A': CDS_PINID='DQ29_A';
NODE_NAME     J6 49
 '@S9S_MB_2U_LIB.S9S_MB_2U(SCH_1):PAGE87_I46@PURE_QUANTA.SCONN288_ADR50017P087CC(CHIPS)':
 'DQ29_A': CDS_PINID='DQ29_A';
NET_NAME
'M_C_CPU0_SA_DQ<2>'
 '@S9S_MB_2U_LIB.S9S_MB_2U(SCH_1):M_C_CPU0_SA_DQ'<2>:
 C_SIGNAL='@s9s_mb_2u_lib.s9s_mb_2u(sch_1):m_c_cpu0_sa_dq(2)';
NODE_NAME     U2 W78
 '@S9S_MB_2U_LIB.S9S_MB_2U(SCH_1):PAGE22_I169@PURE_QUANTA.SOCKET4677_AZIF0045P001C01CS(CHIPS)':
 'DDR2_SA_DQ2': CDS_PINID='DDR2_SA_DQ2';
NODE_NAME     J5 152
 '@S9S_MB_2U_LIB.S9S_MB_2U(SCH_1):PAGE86_I24@PURE_QUANTA.SCONN288_ADR50017P130CC(CHIPS)':
 'DQ2_A': CDS_PINID='DQ2_A';
NODE_NAME     J6 152
 '@S9S_MB_2U_LIB.S9S_MB_2U(SCH_1):PAGE87_I46@PURE_QUANTA.SCONN288_ADR50017P087CC(CHIPS)':
 'DQ2_A': CDS_PINID='DQ2_A';
NET_NAME
'M_C_CPU0_SA_DQ<30>'
 '@S9S_MB_2U_LIB.S9S_MB_2U(SCH_1):M_C_CPU0_SA_DQ'<30>:
 C_SIGNAL='@s9s_mb_2u_lib.s9s_mb_2u(sch_1):m_c_cpu0_sa_dq(30)';
NODE_NAME     U2 AG60
 '@S9S_MB_2U_LIB.S9S_MB_2U(SCH_1):PAGE22_I169@PURE_QUANTA.SOCKET4677_AZIF0045P001C01CS(CHIPS)':
 'DDR2_SA_DQ30': CDS_PINID='DDR2_SA_DQ30';
NODE_NAME     J5 192
 '@S9S_MB_2U_LIB.S9S_MB_2U(SCH_1):PAGE86_I24@PURE_QUANTA.SCONN288_ADR50017P130CC(CHIPS)':
 'DQ30_A': CDS_PINID='DQ30_A';
NODE_NAME     J6 192
 '@S9S_MB_2U_LIB.S9S_MB_2U(SCH_1):PAGE87_I46@PURE_QUANTA.SCONN288_ADR50017P087CC(CHIPS)':
 'DQ30_A': CDS_PINID='DQ30_A';
NET_NAME
'M_C_CPU0_SA_DQ<31>'
 '@S9S_MB_2U_LIB.S9S_MB_2U(SCH_1):M_C_CPU0_SA_DQ'<31>:
 C_SIGNAL='@s9s_mb_2u_lib.s9s_mb_2u(sch_1):m_c_cpu0_sa_dq(31)';
NODE_NAME     U2 AF59
 '@S9S_MB_2U_LIB.S9S_MB_2U(SCH_1):PAGE22_I169@PURE_QUANTA.SOCKET4677_AZIF0045P001C01CS(CHIPS)':
 'DDR2_SA_DQ31': CDS_PINID='DDR2_SA_DQ31';
NODE_NAME     J5 194
 '@S9S_MB_2U_LIB.S9S_MB_2U(SCH_1):PAGE86_I24@PURE_QUANTA.SCONN288_ADR50017P130CC(CHIPS)':
 'DQ31_A': CDS_PINID='DQ31_A';
NODE_NAME     J6 194
 '@S9S_MB_2U_LIB.S9S_MB_2U(SCH_1):PAGE87_I46@PURE_QUANTA.SCONN288_ADR50017P087CC(CHIPS)':
 'DQ31_A': CDS_PINID='DQ31_A';
NET_NAME
'M_C_CPU0_SA_DQ<3>'
 '@S9S_MB_2U_LIB.S9S_MB_2U(SCH_1):M_C_CPU0_SA_DQ'<3>:
 C_SIGNAL='@s9s_mb_2u_lib.s9s_mb_2u(sch_1):m_c_cpu0_sa_dq(3)';
NODE_NAME     U2 Y77
 '@S9S_MB_2U_LIB.S9S_MB_2U(SCH_1):PAGE22_I169@PURE_QUANTA.SOCKET4677_AZIF0045P001C01CS(CHIPS)':
 'DDR2_SA_DQ3': CDS_PINID='DDR2_SA_DQ3';
NODE_NAME     J5 154
 '@S9S_MB_2U_LIB.S9S_MB_2U(SCH_1):PAGE86_I24@PURE_QUANTA.SCONN288_ADR50017P130CC(CHIPS)':
 'DQ3_A': CDS_PINID='DQ3_A';
NODE_NAME     J6 154
 '@S9S_MB_2U_LIB.S9S_MB_2U(SCH_1):PAGE87_I46@PURE_QUANTA.SCONN288_ADR50017P087CC(CHIPS)':
 'DQ3_A': CDS_PINID='DQ3_A';
NET_NAME
'M_C_CPU0_SA_DQ<4>'
 '@S9S_MB_2U_LIB.S9S_MB_2U(SCH_1):M_C_CPU0_SA_DQ'<4>:
 C_SIGNAL='@s9s_mb_2u_lib.s9s_mb_2u(sch_1):m_c_cpu0_sa_dq(4)';
NODE_NAME     U2 T75
 '@S9S_MB_2U_LIB.S9S_MB_2U(SCH_1):PAGE22_I169@PURE_QUANTA.SOCKET4677_AZIF0045P001C01CS(CHIPS)':
 'DDR2_SA_DQ4': CDS_PINID='DDR2_SA_DQ4';
NODE_NAME     J5 14
 '@S9S_MB_2U_LIB.S9S_MB_2U(SCH_1):PAGE86_I24@PURE_QUANTA.SCONN288_ADR50017P130CC(CHIPS)':
 'DQ4_A': CDS_PINID='DQ4_A';
NODE_NAME     J6 14
 '@S9S_MB_2U_LIB.S9S_MB_2U(SCH_1):PAGE87_I46@PURE_QUANTA.SCONN288_ADR50017P087CC(CHIPS)':
 'DQ4_A': CDS_PINID='DQ4_A';
NET_NAME
'M_C_CPU0_SA_DQ<5>'
 '@S9S_MB_2U_LIB.S9S_MB_2U(SCH_1):M_C_CPU0_SA_DQ'<5>:
 C_SIGNAL='@s9s_mb_2u_lib.s9s_mb_2u(sch_1):m_c_cpu0_sa_dq(5)';
NODE_NAME     U2 U74
 '@S9S_MB_2U_LIB.S9S_MB_2U(SCH_1):PAGE22_I169@PURE_QUANTA.SOCKET4677_AZIF0045P001C01CS(CHIPS)':
 'DDR2_SA_DQ5': CDS_PINID='DDR2_SA_DQ5';
NODE_NAME     J5 16
 '@S9S_MB_2U_LIB.S9S_MB_2U(SCH_1):PAGE86_I24@PURE_QUANTA.SCONN288_ADR50017P130CC(CHIPS)':
 'DQ5_A': CDS_PINID='DQ5_A';
NODE_NAME     J6 16
 '@S9S_MB_2U_LIB.S9S_MB_2U(SCH_1):PAGE87_I46@PURE_QUANTA.SCONN288_ADR50017P087CC(CHIPS)':
 'DQ5_A': CDS_PINID='DQ5_A';
NET_NAME
'M_C_CPU0_SA_DQ<6>'
 '@S9S_MB_2U_LIB.S9S_MB_2U(SCH_1):M_C_CPU0_SA_DQ'<6>:
 C_SIGNAL='@s9s_mb_2u_lib.s9s_mb_2u(sch_1):m_c_cpu0_sa_dq(6)';
NODE_NAME     U2 Y75
 '@S9S_MB_2U_LIB.S9S_MB_2U(SCH_1):PAGE22_I169@PURE_QUANTA.SOCKET4677_AZIF0045P001C01CS(CHIPS)':
 'DDR2_SA_DQ6': CDS_PINID='DDR2_SA_DQ6';
NODE_NAME     J5 159
 '@S9S_MB_2U_LIB.S9S_MB_2U(SCH_1):PAGE86_I24@PURE_QUANTA.SCONN288_ADR50017P130CC(CHIPS)':
 'DQ6_A': CDS_PINID='DQ6_A';
NODE_NAME     J6 159
 '@S9S_MB_2U_LIB.S9S_MB_2U(SCH_1):PAGE87_I46@PURE_QUANTA.SCONN288_ADR50017P087CC(CHIPS)':
 'DQ6_A': CDS_PINID='DQ6_A';
NET_NAME
'M_C_CPU0_SA_DQ<7>'
 '@S9S_MB_2U_LIB.S9S_MB_2U(SCH_1):M_C_CPU0_SA_DQ'<7>:
 C_SIGNAL='@s9s_mb_2u_lib.s9s_mb_2u(sch_1):m_c_cpu0_sa_dq(7)';
NODE_NAME     U2 W74
 '@S9S_MB_2U_LIB.S9S_MB_2U(SCH_1):PAGE22_I169@PURE_QUANTA.SOCKET4677_AZIF0045P001C01CS(CHIPS)':
 'DDR2_SA_DQ7': CDS_PINID='DDR2_SA_DQ7';
NODE_NAME     J5 161
 '@S9S_MB_2U_LIB.S9S_MB_2U(SCH_1):PAGE86_I24@PURE_QUANTA.SCONN288_ADR50017P130CC(CHIPS)':
 'DQ7_A': CDS_PINID='DQ7_A';
NODE_NAME     J6 161
 '@S9S_MB_2U_LIB.S9S_MB_2U(SCH_1):PAGE87_I46@PURE_QUANTA.SCONN288_ADR50017P087CC(CHIPS)':
 'DQ7_A': CDS_PINID='DQ7_A';
NET_NAME
'M_C_CPU0_SA_DQ<8>'
 '@S9S_MB_2U_LIB.S9S_MB_2U(SCH_1):M_C_CPU0_SA_DQ'<8>:
 C_SIGNAL='@s9s_mb_2u_lib.s9s_mb_2u(sch_1):m_c_cpu0_sa_dq(8)';
NODE_NAME     U2 AD69
 '@S9S_MB_2U_LIB.S9S_MB_2U(SCH_1):PAGE22_I169@PURE_QUANTA.SOCKET4677_AZIF0045P001C01CS(CHIPS)':
 'DDR2_SA_DQ8': CDS_PINID='DDR2_SA_DQ8';
NODE_NAME     J5 18
 '@S9S_MB_2U_LIB.S9S_MB_2U(SCH_1):PAGE86_I24@PURE_QUANTA.SCONN288_ADR50017P130CC(CHIPS)':
 'DQ8_A': CDS_PINID='DQ8_A';
NODE_NAME     J6 18
 '@S9S_MB_2U_LIB.S9S_MB_2U(SCH_1):PAGE87_I46@PURE_QUANTA.SCONN288_ADR50017P087CC(CHIPS)':
 'DQ8_A': CDS_PINID='DQ8_A';
NET_NAME
'M_C_CPU0_SA_DQ<9>'
 '@S9S_MB_2U_LIB.S9S_MB_2U(SCH_1):M_C_CPU0_SA_DQ'<9>:
 C_SIGNAL='@s9s_mb_2u_lib.s9s_mb_2u(sch_1):m_c_cpu0_sa_dq(9)';
NODE_NAME     U2 AC68
 '@S9S_MB_2U_LIB.S9S_MB_2U(SCH_1):PAGE22_I169@PURE_QUANTA.SOCKET4677_AZIF0045P001C01CS(CHIPS)':
 'DDR2_SA_DQ9': CDS_PINID='DDR2_SA_DQ9';
NODE_NAME     J5 20
 '@S9S_MB_2U_LIB.S9S_MB_2U(SCH_1):PAGE86_I24@PURE_QUANTA.SCONN288_ADR50017P130CC(CHIPS)':
 'DQ9_A': CDS_PINID='DQ9_A';
NODE_NAME     J6 20
 '@S9S_MB_2U_LIB.S9S_MB_2U(SCH_1):PAGE87_I46@PURE_QUANTA.SCONN288_ADR50017P087CC(CHIPS)':
 'DQ9_A': CDS_PINID='DQ9_A';
NET_NAME
'M_C_CPU0_SA_DQS_DN<0>'
 '@S9S_MB_2U_LIB.S9S_MB_2U(SCH_1):M_C_CPU0_SA_DQS_DN'<0>:
 C_SIGNAL='@s9s_mb_2u_lib.s9s_mb_2u(sch_1):m_c_cpu0_sa_dqs_dn(0)';
NODE_NAME     U2 R76
 '@S9S_MB_2U_LIB.S9S_MB_2U(SCH_1):PAGE22_I169@PURE_QUANTA.SOCKET4677_AZIF0045P001C01CS(CHIPS)':
 'DDR2_SA_DQS_DN0': CDS_PINID='DDR2_SA_DQS_DN0';
NODE_NAME     J5 12
 '@S9S_MB_2U_LIB.S9S_MB_2U(SCH_1):PAGE86_I178@PURE_QUANTA.SCONN288_ADR50017P130CC(CHIPS)':
 'DQS0_A_C': CDS_PINID='DQS0_A_C';
NODE_NAME     J6 12
 '@S9S_MB_2U_LIB.S9S_MB_2U(SCH_1):PAGE87_I178@PURE_QUANTA.SCONN288_ADR50017P087CC(CHIPS)':
 'DQS0_A_C': CDS_PINID='DQS0_A_C';
NET_NAME
'M_C_CPU0_SA_DQS_DN<1>'
 '@S9S_MB_2U_LIB.S9S_MB_2U(SCH_1):M_C_CPU0_SA_DQS_DN'<1>:
 C_SIGNAL='@s9s_mb_2u_lib.s9s_mb_2u(sch_1):m_c_cpu0_sa_dqs_dn(1)';
NODE_NAME     U2 AB67
 '@S9S_MB_2U_LIB.S9S_MB_2U(SCH_1):PAGE22_I169@PURE_QUANTA.SOCKET4677_AZIF0045P001C01CS(CHIPS)':
 'DDR2_SA_DQS_DN1': CDS_PINID='DDR2_SA_DQS_DN1';
NODE_NAME     J5 23
 '@S9S_MB_2U_LIB.S9S_MB_2U(SCH_1):PAGE86_I178@PURE_QUANTA.SCONN288_ADR50017P130CC(CHIPS)':
 'DQS1_A_C': CDS_PINID='DQS1_A_C';
NODE_NAME     J6 23
 '@S9S_MB_2U_LIB.S9S_MB_2U(SCH_1):PAGE87_I178@PURE_QUANTA.SCONN288_ADR50017P087CC(CHIPS)':
 'DQS1_A_C': CDS_PINID='DQS1_A_C';
NET_NAME
'M_C_CPU0_SA_DQS_DN<2>'
 '@S9S_MB_2U_LIB.S9S_MB_2U(SCH_1):M_C_CPU0_SA_DQS_DN'<2>:
 C_SIGNAL='@s9s_mb_2u_lib.s9s_mb_2u(sch_1):m_c_cpu0_sa_dqs_dn(2)';
NODE_NAME     U2 R64
 '@S9S_MB_2U_LIB.S9S_MB_2U(SCH_1):PAGE22_I169@PURE_QUANTA.SOCKET4677_AZIF0045P001C01CS(CHIPS)':
 'DDR2_SA_DQS_DN2': CDS_PINID='DDR2_SA_DQS_DN2';
NODE_NAME     J5 34
 '@S9S_MB_2U_LIB.S9S_MB_2U(SCH_1):PAGE86_I178@PURE_QUANTA.SCONN288_ADR50017P130CC(CHIPS)':
 'DQS2_A_C': CDS_PINID='DQS2_A_C';
NODE_NAME     J6 34
 '@S9S_MB_2U_LIB.S9S_MB_2U(SCH_1):PAGE87_I178@PURE_QUANTA.SCONN288_ADR50017P087CC(CHIPS)':
 'DQS2_A_C': CDS_PINID='DQS2_A_C';
NET_NAME
'M_C_CPU0_SA_DQS_DN<3>'
 '@S9S_MB_2U_LIB.S9S_MB_2U(SCH_1):M_C_CPU0_SA_DQS_DN'<3>:
 C_SIGNAL='@s9s_mb_2u_lib.s9s_mb_2u(sch_1):m_c_cpu0_sa_dqs_dn(3)';
NODE_NAME     U2 AB61
 '@S9S_MB_2U_LIB.S9S_MB_2U(SCH_1):PAGE22_I169@PURE_QUANTA.SOCKET4677_AZIF0045P001C01CS(CHIPS)':
 'DDR2_SA_DQS_DN3': CDS_PINID='DDR2_SA_DQS_DN3';
NODE_NAME     J5 45
 '@S9S_MB_2U_LIB.S9S_MB_2U(SCH_1):PAGE86_I178@PURE_QUANTA.SCONN288_ADR50017P130CC(CHIPS)':
 'DQS3_A_C': CDS_PINID='DQS3_A_C';
NODE_NAME     J6 45
 '@S9S_MB_2U_LIB.S9S_MB_2U(SCH_1):PAGE87_I178@PURE_QUANTA.SCONN288_ADR50017P087CC(CHIPS)':
 'DQS3_A_C': CDS_PINID='DQS3_A_C';
NET_NAME
'M_C_CPU0_SA_DQS_DN<4>'
 '@S9S_MB_2U_LIB.S9S_MB_2U(SCH_1):M_C_CPU0_SA_DQS_DN'<4>:
 C_SIGNAL='@s9s_mb_2u_lib.s9s_mb_2u(sch_1):m_c_cpu0_sa_dqs_dn(4)';
NODE_NAME     U2 AD55
 '@S9S_MB_2U_LIB.S9S_MB_2U(SCH_1):PAGE22_I169@PURE_QUANTA.SOCKET4677_AZIF0045P001C01CS(CHIPS)':
 'DDR2_SA_DQS_DN4': CDS_PINID='DDR2_SA_DQS_DN4';
NODE_NAME     J5 56
 '@S9S_MB_2U_LIB.S9S_MB_2U(SCH_1):PAGE86_I178@PURE_QUANTA.SCONN288_ADR50017P130CC(CHIPS)':
 'DQS4_A_C': CDS_PINID='DQS4_A_C';
NODE_NAME     J6 56
 '@S9S_MB_2U_LIB.S9S_MB_2U(SCH_1):PAGE87_I178@PURE_QUANTA.SCONN288_ADR50017P087CC(CHIPS)':
 'DQS4_A_C': CDS_PINID='DQS4_A_C';
NET_NAME
'M_C_CPU0_SA_DQS_DN<5>'
 '@S9S_MB_2U_LIB.S9S_MB_2U(SCH_1):M_C_CPU0_SA_DQS_DN'<5>:
 C_SIGNAL='@s9s_mb_2u_lib.s9s_mb_2u(sch_1):m_c_cpu0_sa_dqs_dn(5)';
NODE_NAME     U2 W76
 '@S9S_MB_2U_LIB.S9S_MB_2U(SCH_1):PAGE22_I169@PURE_QUANTA.SOCKET4677_AZIF0045P001C01CS(CHIPS)':
 'DDR2_SA_DQS_DN5': CDS_PINID='DDR2_SA_DQS_DN5';
NODE_NAME     J5 156
 '@S9S_MB_2U_LIB.S9S_MB_2U(SCH_1):PAGE86_I178@PURE_QUANTA.SCONN288_ADR50017P130CC(CHIPS)':
 'DQS5_A_C||TDQS5_A_C||DQS5_A_T||TDQS5_A_T': CDS_PINID='\dqs5_a_c||tdqs5_a_c||dqs5_a_t||tdqs5_a_t\';
NODE_NAME     J6 156
 '@S9S_MB_2U_LIB.S9S_MB_2U(SCH_1):PAGE87_I178@PURE_QUANTA.SCONN288_ADR50017P087CC(CHIPS)':
 'DQS5_A_C||TDQS5_A_C||DQS5_A_T||TDQS5_A_T': CDS_PINID='\dqs5_a_c||tdqs5_a_c||dqs5_a_t||tdqs5_a_t\';
NET_NAME
'M_C_CPU0_SA_DQS_DN<6>'
 '@S9S_MB_2U_LIB.S9S_MB_2U(SCH_1):M_C_CPU0_SA_DQS_DN'<6>:
 C_SIGNAL='@s9s_mb_2u_lib.s9s_mb_2u(sch_1):m_c_cpu0_sa_dqs_dn(6)';
NODE_NAME     U2 AH67
 '@S9S_MB_2U_LIB.S9S_MB_2U(SCH_1):PAGE22_I169@PURE_QUANTA.SOCKET4677_AZIF0045P001C01CS(CHIPS)':
 'DDR2_SA_DQS_DN6': CDS_PINID='DDR2_SA_DQS_DN6';
NODE_NAME     J5 167
 '@S9S_MB_2U_LIB.S9S_MB_2U(SCH_1):PAGE86_I178@PURE_QUANTA.SCONN288_ADR50017P130CC(CHIPS)':
 'DQS6_A_C||TDQS6_A_C||DQS6_A_T||TDQS6_A_T': CDS_PINID='\dqs6_a_c||tdqs6_a_c||dqs6_a_t||tdqs6_a_t\';
NODE_NAME     J6 167
 '@S9S_MB_2U_LIB.S9S_MB_2U(SCH_1):PAGE87_I178@PURE_QUANTA.SCONN288_ADR50017P087CC(CHIPS)':
 'DQS6_A_C||TDQS6_A_C||DQS6_A_T||TDQS6_A_T': CDS_PINID='\dqs6_a_c||tdqs6_a_c||dqs6_a_t||tdqs6_a_t\';
NET_NAME
'M_C_CPU0_SA_DQS_DN<7>'
 '@S9S_MB_2U_LIB.S9S_MB_2U(SCH_1):M_C_CPU0_SA_DQS_DN'<7>:
 C_SIGNAL='@s9s_mb_2u_lib.s9s_mb_2u(sch_1):m_c_cpu0_sa_dqs_dn(7)';
NODE_NAME     U2 AA64
 '@S9S_MB_2U_LIB.S9S_MB_2U(SCH_1):PAGE22_I169@PURE_QUANTA.SOCKET4677_AZIF0045P001C01CS(CHIPS)':
 'DDR2_SA_DQS_DN7': CDS_PINID='DDR2_SA_DQS_DN7';
NODE_NAME     J5 178
 '@S9S_MB_2U_LIB.S9S_MB_2U(SCH_1):PAGE86_I178@PURE_QUANTA.SCONN288_ADR50017P130CC(CHIPS)':
 'DQS7_A_C||TDQS7_A_C': CDS_PINID='\dqs7_a_c||tdqs7_a_c\';
NODE_NAME     J6 178
 '@S9S_MB_2U_LIB.S9S_MB_2U(SCH_1):PAGE87_I178@PURE_QUANTA.SCONN288_ADR50017P087CC(CHIPS)':
 'DQS7_A_C||TDQS7_A_C': CDS_PINID='\dqs7_a_c||tdqs7_a_c\';
NET_NAME
'M_C_CPU0_SA_DQS_DN<8>'
 '@S9S_MB_2U_LIB.S9S_MB_2U(SCH_1):M_C_CPU0_SA_DQS_DN'<8>:
 C_SIGNAL='@s9s_mb_2u_lib.s9s_mb_2u(sch_1):m_c_cpu0_sa_dqs_dn(8)';
NODE_NAME     U2 AF61
 '@S9S_MB_2U_LIB.S9S_MB_2U(SCH_1):PAGE22_I169@PURE_QUANTA.SOCKET4677_AZIF0045P001C01CS(CHIPS)':
 'DDR2_SA_DQS_DN8': CDS_PINID='DDR2_SA_DQS_DN8';
NODE_NAME     J5 189
 '@S9S_MB_2U_LIB.S9S_MB_2U(SCH_1):PAGE86_I178@PURE_QUANTA.SCONN288_ADR50017P130CC(CHIPS)':
 'DQS8_A_C||TDQS8_A_C': CDS_PINID='\dqs8_a_c||tdqs8_a_c\';
NODE_NAME     J6 189
 '@S9S_MB_2U_LIB.S9S_MB_2U(SCH_1):PAGE87_I178@PURE_QUANTA.SCONN288_ADR50017P087CC(CHIPS)':
 'DQS8_A_C||TDQS8_A_C': CDS_PINID='\dqs8_a_c||tdqs8_a_c\';
NET_NAME
'M_C_CPU0_SA_DQS_DN<9>'
 '@S9S_MB_2U_LIB.S9S_MB_2U(SCH_1):M_C_CPU0_SA_DQS_DN'<9>:
 C_SIGNAL='@s9s_mb_2u_lib.s9s_mb_2u(sch_1):m_c_cpu0_sa_dqs_dn(9)';
NODE_NAME     U2 AH55
 '@S9S_MB_2U_LIB.S9S_MB_2U(SCH_1):PAGE22_I169@PURE_QUANTA.SOCKET4677_AZIF0045P001C01CS(CHIPS)':
 'DDR2_SA_DQS_DN9': CDS_PINID='DDR2_SA_DQS_DN9';
NODE_NAME     J5 200
 '@S9S_MB_2U_LIB.S9S_MB_2U(SCH_1):PAGE86_I178@PURE_QUANTA.SCONN288_ADR50017P130CC(CHIPS)':
 'DQS9_A_C||TDQS9_A_C': CDS_PINID='\dqs9_a_c||tdqs9_a_c\';
NODE_NAME     J6 200
 '@S9S_MB_2U_LIB.S9S_MB_2U(SCH_1):PAGE87_I178@PURE_QUANTA.SCONN288_ADR50017P087CC(CHIPS)':
 'DQS9_A_C||TDQS9_A_C': CDS_PINID='\dqs9_a_c||tdqs9_a_c\';
NET_NAME
'M_C_CPU0_SA_DQS_DP<0>'
 '@S9S_MB_2U_LIB.S9S_MB_2U(SCH_1):M_C_CPU0_SA_DQS_DP'<0>:
 C_SIGNAL='@s9s_mb_2u_lib.s9s_mb_2u(sch_1):m_c_cpu0_sa_dqs_dp(0)';
NODE_NAME     U2 U76
 '@S9S_MB_2U_LIB.S9S_MB_2U(SCH_1):PAGE22_I169@PURE_QUANTA.SOCKET4677_AZIF0045P001C01CS(CHIPS)':
 'DDR2_SA_DQS_DP0': CDS_PINID='DDR2_SA_DQS_DP0';
NODE_NAME     J5 11
 '@S9S_MB_2U_LIB.S9S_MB_2U(SCH_1):PAGE86_I178@PURE_QUANTA.SCONN288_ADR50017P130CC(CHIPS)':
 'DQS0_A_T': CDS_PINID='DQS0_A_T';
NODE_NAME     J6 11
 '@S9S_MB_2U_LIB.S9S_MB_2U(SCH_1):PAGE87_I178@PURE_QUANTA.SCONN288_ADR50017P087CC(CHIPS)':
 'DQS0_A_T': CDS_PINID='DQS0_A_T';
NET_NAME
'M_C_CPU0_SA_DQS_DP<1>'
 '@S9S_MB_2U_LIB.S9S_MB_2U(SCH_1):M_C_CPU0_SA_DQS_DP'<1>:
 C_SIGNAL='@s9s_mb_2u_lib.s9s_mb_2u(sch_1):m_c_cpu0_sa_dqs_dp(1)';
NODE_NAME     U2 AD67
 '@S9S_MB_2U_LIB.S9S_MB_2U(SCH_1):PAGE22_I169@PURE_QUANTA.SOCKET4677_AZIF0045P001C01CS(CHIPS)':
 'DDR2_SA_DQS_DP1': CDS_PINID='DDR2_SA_DQS_DP1';
NODE_NAME     J5 22
 '@S9S_MB_2U_LIB.S9S_MB_2U(SCH_1):PAGE86_I178@PURE_QUANTA.SCONN288_ADR50017P130CC(CHIPS)':
 'DQS1_A_T': CDS_PINID='DQS1_A_T';
NODE_NAME     J6 22
 '@S9S_MB_2U_LIB.S9S_MB_2U(SCH_1):PAGE87_I178@PURE_QUANTA.SCONN288_ADR50017P087CC(CHIPS)':
 'DQS1_A_T': CDS_PINID='DQS1_A_T';
NET_NAME
'M_C_CPU0_SA_DQS_DP<2>'
 '@S9S_MB_2U_LIB.S9S_MB_2U(SCH_1):M_C_CPU0_SA_DQS_DP'<2>:
 C_SIGNAL='@s9s_mb_2u_lib.s9s_mb_2u(sch_1):m_c_cpu0_sa_dqs_dp(2)';
NODE_NAME     U2 U64
 '@S9S_MB_2U_LIB.S9S_MB_2U(SCH_1):PAGE22_I169@PURE_QUANTA.SOCKET4677_AZIF0045P001C01CS(CHIPS)':
 'DDR2_SA_DQS_DP2': CDS_PINID='DDR2_SA_DQS_DP2';
NODE_NAME     J5 33
 '@S9S_MB_2U_LIB.S9S_MB_2U(SCH_1):PAGE86_I178@PURE_QUANTA.SCONN288_ADR50017P130CC(CHIPS)':
 'DQS2_A_T': CDS_PINID='DQS2_A_T';
NODE_NAME     J6 33
 '@S9S_MB_2U_LIB.S9S_MB_2U(SCH_1):PAGE87_I178@PURE_QUANTA.SCONN288_ADR50017P087CC(CHIPS)':
 'DQS2_A_T': CDS_PINID='DQS2_A_T';
NET_NAME
'M_C_CPU0_SA_DQS_DP<3>'
 '@S9S_MB_2U_LIB.S9S_MB_2U(SCH_1):M_C_CPU0_SA_DQS_DP'<3>:
 C_SIGNAL='@s9s_mb_2u_lib.s9s_mb_2u(sch_1):m_c_cpu0_sa_dqs_dp(3)';
NODE_NAME     U2 AD61
 '@S9S_MB_2U_LIB.S9S_MB_2U(SCH_1):PAGE22_I169@PURE_QUANTA.SOCKET4677_AZIF0045P001C01CS(CHIPS)':
 'DDR2_SA_DQS_DP3': CDS_PINID='DDR2_SA_DQS_DP3';
NODE_NAME     J5 44
 '@S9S_MB_2U_LIB.S9S_MB_2U(SCH_1):PAGE86_I178@PURE_QUANTA.SCONN288_ADR50017P130CC(CHIPS)':
 'DQS3_A_T': CDS_PINID='DQS3_A_T';
NODE_NAME     J6 44
 '@S9S_MB_2U_LIB.S9S_MB_2U(SCH_1):PAGE87_I178@PURE_QUANTA.SCONN288_ADR50017P087CC(CHIPS)':
 'DQS3_A_T': CDS_PINID='DQS3_A_T';
NET_NAME
'M_C_CPU0_SA_DQS_DP<4>'
 '@S9S_MB_2U_LIB.S9S_MB_2U(SCH_1):M_C_CPU0_SA_DQS_DP'<4>:
 C_SIGNAL='@s9s_mb_2u_lib.s9s_mb_2u(sch_1):m_c_cpu0_sa_dqs_dp(4)';
NODE_NAME     U2 AB55
 '@S9S_MB_2U_LIB.S9S_MB_2U(SCH_1):PAGE22_I169@PURE_QUANTA.SOCKET4677_AZIF0045P001C01CS(CHIPS)':
 'DDR2_SA_DQS_DP4': CDS_PINID='DDR2_SA_DQS_DP4';
NODE_NAME     J5 55
 '@S9S_MB_2U_LIB.S9S_MB_2U(SCH_1):PAGE86_I178@PURE_QUANTA.SCONN288_ADR50017P130CC(CHIPS)':
 'DQS4_A_T': CDS_PINID='DQS4_A_T';
NODE_NAME     J6 55
 '@S9S_MB_2U_LIB.S9S_MB_2U(SCH_1):PAGE87_I178@PURE_QUANTA.SCONN288_ADR50017P087CC(CHIPS)':
 'DQS4_A_T': CDS_PINID='DQS4_A_T';
NET_NAME
'M_C_CPU0_SA_DQS_DP<5>'
 '@S9S_MB_2U_LIB.S9S_MB_2U(SCH_1):M_C_CPU0_SA_DQS_DP'<5>:
 C_SIGNAL='@s9s_mb_2u_lib.s9s_mb_2u(sch_1):m_c_cpu0_sa_dqs_dp(5)';
NODE_NAME     U2 AA76
 '@S9S_MB_2U_LIB.S9S_MB_2U(SCH_1):PAGE22_I169@PURE_QUANTA.SOCKET4677_AZIF0045P001C01CS(CHIPS)':
 'DDR2_SA_DQS_DP5': CDS_PINID='DDR2_SA_DQS_DP5';
NODE_NAME     J5 157
 '@S9S_MB_2U_LIB.S9S_MB_2U(SCH_1):PAGE86_I178@PURE_QUANTA.SCONN288_ADR50017P130CC(CHIPS)':
 'DQS5_A_T||TDQS5_A_T': CDS_PINID='\dqs5_a_t||tdqs5_a_t\';
NODE_NAME     J6 157
 '@S9S_MB_2U_LIB.S9S_MB_2U(SCH_1):PAGE87_I178@PURE_QUANTA.SCONN288_ADR50017P087CC(CHIPS)':
 'DQS5_A_T||TDQS5_A_T': CDS_PINID='\dqs5_a_t||tdqs5_a_t\';
NET_NAME
'M_C_CPU0_SA_DQS_DP<6>'
 '@S9S_MB_2U_LIB.S9S_MB_2U(SCH_1):M_C_CPU0_SA_DQS_DP'<6>:
 C_SIGNAL='@s9s_mb_2u_lib.s9s_mb_2u(sch_1):m_c_cpu0_sa_dqs_dp(6)';
NODE_NAME     U2 AF67
 '@S9S_MB_2U_LIB.S9S_MB_2U(SCH_1):PAGE22_I169@PURE_QUANTA.SOCKET4677_AZIF0045P001C01CS(CHIPS)':
 'DDR2_SA_DQS_DP6': CDS_PINID='DDR2_SA_DQS_DP6';
NODE_NAME     J5 168
 '@S9S_MB_2U_LIB.S9S_MB_2U(SCH_1):PAGE86_I178@PURE_QUANTA.SCONN288_ADR50017P130CC(CHIPS)':
 'DQS6_A_T||TDQS6_A_T': CDS_PINID='\dqs6_a_t||tdqs6_a_t\';
NODE_NAME     J6 168
 '@S9S_MB_2U_LIB.S9S_MB_2U(SCH_1):PAGE87_I178@PURE_QUANTA.SCONN288_ADR50017P087CC(CHIPS)':
 'DQS6_A_T||TDQS6_A_T': CDS_PINID='\dqs6_a_t||tdqs6_a_t\';
NET_NAME
'M_C_CPU0_SA_DQS_DP<7>'
 '@S9S_MB_2U_LIB.S9S_MB_2U(SCH_1):M_C_CPU0_SA_DQS_DP'<7>:
 C_SIGNAL='@s9s_mb_2u_lib.s9s_mb_2u(sch_1):m_c_cpu0_sa_dqs_dp(7)';
NODE_NAME     U2 W64
 '@S9S_MB_2U_LIB.S9S_MB_2U(SCH_1):PAGE22_I169@PURE_QUANTA.SOCKET4677_AZIF0045P001C01CS(CHIPS)':
 'DDR2_SA_DQS_DP7': CDS_PINID='DDR2_SA_DQS_DP7';
NODE_NAME     J5 179
 '@S9S_MB_2U_LIB.S9S_MB_2U(SCH_1):PAGE86_I178@PURE_QUANTA.SCONN288_ADR50017P130CC(CHIPS)':
 'DQS7_A_T||TDQS7_A_T': CDS_PINID='\dqs7_a_t||tdqs7_a_t\';
NODE_NAME     J6 179
 '@S9S_MB_2U_LIB.S9S_MB_2U(SCH_1):PAGE87_I178@PURE_QUANTA.SCONN288_ADR50017P087CC(CHIPS)':
 'DQS7_A_T||TDQS7_A_T': CDS_PINID='\dqs7_a_t||tdqs7_a_t\';
NET_NAME
'M_C_CPU0_SA_DQS_DP<8>'
 '@S9S_MB_2U_LIB.S9S_MB_2U(SCH_1):M_C_CPU0_SA_DQS_DP'<8>:
 C_SIGNAL='@s9s_mb_2u_lib.s9s_mb_2u(sch_1):m_c_cpu0_sa_dqs_dp(8)';
NODE_NAME     U2 AH61
 '@S9S_MB_2U_LIB.S9S_MB_2U(SCH_1):PAGE22_I169@PURE_QUANTA.SOCKET4677_AZIF0045P001C01CS(CHIPS)':
 'DDR2_SA_DQS_DP8': CDS_PINID='DDR2_SA_DQS_DP8';
NODE_NAME     J5 190
 '@S9S_MB_2U_LIB.S9S_MB_2U(SCH_1):PAGE86_I178@PURE_QUANTA.SCONN288_ADR50017P130CC(CHIPS)':
 'DQS8_A_T||TDQS8_A_T': CDS_PINID='\dqs8_a_t||tdqs8_a_t\';
NODE_NAME     J6 190
 '@S9S_MB_2U_LIB.S9S_MB_2U(SCH_1):PAGE87_I178@PURE_QUANTA.SCONN288_ADR50017P087CC(CHIPS)':
 'DQS8_A_T||TDQS8_A_T': CDS_PINID='\dqs8_a_t||tdqs8_a_t\';
NET_NAME
'M_C_CPU0_SA_DQS_DP<9>'
 '@S9S_MB_2U_LIB.S9S_MB_2U(SCH_1):M_C_CPU0_SA_DQS_DP'<9>:
 C_SIGNAL='@s9s_mb_2u_lib.s9s_mb_2u(sch_1):m_c_cpu0_sa_dqs_dp(9)';
NODE_NAME     U2 AF55
 '@S9S_MB_2U_LIB.S9S_MB_2U(SCH_1):PAGE22_I169@PURE_QUANTA.SOCKET4677_AZIF0045P001C01CS(CHIPS)':
 'DDR2_SA_DQS_DP9': CDS_PINID='DDR2_SA_DQS_DP9';
NODE_NAME     J5 201
 '@S9S_MB_2U_LIB.S9S_MB_2U(SCH_1):PAGE86_I178@PURE_QUANTA.SCONN288_ADR50017P130CC(CHIPS)':
 'DQS9_A_T||TDQS9_A_T': CDS_PINID='\dqs9_a_t||tdqs9_a_t\';
NODE_NAME     J6 201
 '@S9S_MB_2U_LIB.S9S_MB_2U(SCH_1):PAGE87_I178@PURE_QUANTA.SCONN288_ADR50017P087CC(CHIPS)':
 'DQS9_A_T||TDQS9_A_T': CDS_PINID='\dqs9_a_t||tdqs9_a_t\';
NET_NAME
'M_C_CPU0_SA_PAR'
 '@S9S_MB_2U_LIB.S9S_MB_2U(SCH_1):M_C_CPU0_SA_PAR':
 C_SIGNAL='@s9s_mb_2u_lib.s9s_mb_2u(sch_1):m_c_cpu0_sa_par';
NODE_NAME     U2 T47
 '@S9S_MB_2U_LIB.S9S_MB_2U(SCH_1):PAGE22_I169@PURE_QUANTA.SOCKET4677_AZIF0045P001C01CS(CHIPS)':
 'DDR2_SA_PAR': CDS_PINID='DDR2_SA_PAR';
NODE_NAME     J5 74
 '@S9S_MB_2U_LIB.S9S_MB_2U(SCH_1):PAGE86_I24@PURE_QUANTA.SCONN288_ADR50017P130CC(CHIPS)':
 'PAR_A': CDS_PINID='PAR_A';
NODE_NAME     J6 74
 '@S9S_MB_2U_LIB.S9S_MB_2U(SCH_1):PAGE87_I46@PURE_QUANTA.SCONN288_ADR50017P087CC(CHIPS)':
 'PAR_A': CDS_PINID='PAR_A';
NET_NAME
'M_C_CPU0_SA_RSP<0>'
 '@S9S_MB_2U_LIB.S9S_MB_2U(SCH_1):M_C_CPU0_SA_RSP'<0>:
 C_SIGNAL='@s9s_mb_2u_lib.s9s_mb_2u(sch_1):m_c_cpu0_sa_rsp(0)';
NODE_NAME     U2 AC48
 '@S9S_MB_2U_LIB.S9S_MB_2U(SCH_1):PAGE22_I169@PURE_QUANTA.SOCKET4677_AZIF0045P001C01CS(CHIPS)':
 'DDR2_A_RSP0': CDS_PINID='DDR2_A_RSP0';
NODE_NAME     J5 86
 '@S9S_MB_2U_LIB.S9S_MB_2U(SCH_1):PAGE86_I24@PURE_QUANTA.SCONN288_ADR50017P130CC(CHIPS)':
 'LBD||RSP_A_N': CDS_PINID='\lbd||rsp_a_n\';
NET_NAME
'M_C_CPU0_SA_RSP<1>'
 '@S9S_MB_2U_LIB.S9S_MB_2U(SCH_1):M_C_CPU0_SA_RSP'<1>:
 C_SIGNAL='@s9s_mb_2u_lib.s9s_mb_2u(sch_1):m_c_cpu0_sa_rsp(1)';
NODE_NAME     U2 AD47
 '@S9S_MB_2U_LIB.S9S_MB_2U(SCH_1):PAGE22_I169@PURE_QUANTA.SOCKET4677_AZIF0045P001C01CS(CHIPS)':
 'DDR2_A_RSP1': CDS_PINID='DDR2_A_RSP1';
NODE_NAME     J6 86
 '@S9S_MB_2U_LIB.S9S_MB_2U(SCH_1):PAGE87_I46@PURE_QUANTA.SCONN288_ADR50017P087CC(CHIPS)':
 'LBD||RSP_A_N': CDS_PINID='\lbd||rsp_a_n\';
NET_NAME
'M_C_CPU0_SB_CA<0>'
 '@S9S_MB_2U_LIB.S9S_MB_2U(SCH_1):M_C_CPU0_SB_CA'<0>:
 C_SIGNAL='@s9s_mb_2u_lib.s9s_mb_2u(sch_1):m_c_cpu0_sb_ca(0)';
NODE_NAME     U2 W48
 '@S9S_MB_2U_LIB.S9S_MB_2U(SCH_1):PAGE22_I169@PURE_QUANTA.SOCKET4677_AZIF0045P001C01CS(CHIPS)':
 'DDR2_SB_CA0': CDS_PINID='DDR2_SB_CA0';
NODE_NAME     J5 76
 '@S9S_MB_2U_LIB.S9S_MB_2U(SCH_1):PAGE86_I24@PURE_QUANTA.SCONN288_ADR50017P130CC(CHIPS)':
 'CA0_B': CDS_PINID='CA0_B';
NODE_NAME     J6 76
 '@S9S_MB_2U_LIB.S9S_MB_2U(SCH_1):PAGE87_I46@PURE_QUANTA.SCONN288_ADR50017P087CC(CHIPS)':
 'CA0_B': CDS_PINID='CA0_B';
NET_NAME
'M_C_CPU0_SB_CA<1>'
 '@S9S_MB_2U_LIB.S9S_MB_2U(SCH_1):M_C_CPU0_SB_CA'<1>:
 C_SIGNAL='@s9s_mb_2u_lib.s9s_mb_2u(sch_1):m_c_cpu0_sb_ca(1)';
NODE_NAME     U2 Y47
 '@S9S_MB_2U_LIB.S9S_MB_2U(SCH_1):PAGE22_I169@PURE_QUANTA.SOCKET4677_AZIF0045P001C01CS(CHIPS)':
 'DDR2_SB_CA1': CDS_PINID='DDR2_SB_CA1';
NODE_NAME     J5 221
 '@S9S_MB_2U_LIB.S9S_MB_2U(SCH_1):PAGE86_I24@PURE_QUANTA.SCONN288_ADR50017P130CC(CHIPS)':
 'CA1_B': CDS_PINID='CA1_B';
NODE_NAME     J6 221
 '@S9S_MB_2U_LIB.S9S_MB_2U(SCH_1):PAGE87_I46@PURE_QUANTA.SCONN288_ADR50017P087CC(CHIPS)':
 'CA1_B': CDS_PINID='CA1_B';
NET_NAME
'M_C_CPU0_SB_CA<2>'
 '@S9S_MB_2U_LIB.S9S_MB_2U(SCH_1):M_C_CPU0_SB_CA'<2>:
 C_SIGNAL='@s9s_mb_2u_lib.s9s_mb_2u(sch_1):m_c_cpu0_sb_ca(2)';
NODE_NAME     U2 U41
 '@S9S_MB_2U_LIB.S9S_MB_2U(SCH_1):PAGE22_I169@PURE_QUANTA.SOCKET4677_AZIF0045P001C01CS(CHIPS)':
 'DDR2_SB_CA2': CDS_PINID='DDR2_SB_CA2';
NODE_NAME     J5 78
 '@S9S_MB_2U_LIB.S9S_MB_2U(SCH_1):PAGE86_I24@PURE_QUANTA.SCONN288_ADR50017P130CC(CHIPS)':
 'CA2_B': CDS_PINID='CA2_B';
NODE_NAME     J6 78
 '@S9S_MB_2U_LIB.S9S_MB_2U(SCH_1):PAGE87_I46@PURE_QUANTA.SCONN288_ADR50017P087CC(CHIPS)':
 'CA2_B': CDS_PINID='CA2_B';
NET_NAME
'M_C_CPU0_SB_CA<3>'
 '@S9S_MB_2U_LIB.S9S_MB_2U(SCH_1):M_C_CPU0_SB_CA'<3>:
 C_SIGNAL='@s9s_mb_2u_lib.s9s_mb_2u(sch_1):m_c_cpu0_sb_ca(3)';
NODE_NAME     U2 W41
 '@S9S_MB_2U_LIB.S9S_MB_2U(SCH_1):PAGE22_I169@PURE_QUANTA.SOCKET4677_AZIF0045P001C01CS(CHIPS)':
 'DDR2_SB_CA3': CDS_PINID='DDR2_SB_CA3';
NODE_NAME     J5 223
 '@S9S_MB_2U_LIB.S9S_MB_2U(SCH_1):PAGE86_I24@PURE_QUANTA.SCONN288_ADR50017P130CC(CHIPS)':
 'CA3_B': CDS_PINID='CA3_B';
NODE_NAME     J6 223
 '@S9S_MB_2U_LIB.S9S_MB_2U(SCH_1):PAGE87_I46@PURE_QUANTA.SCONN288_ADR50017P087CC(CHIPS)':
 'CA3_B': CDS_PINID='CA3_B';
NET_NAME
'M_C_CPU0_SB_CA<4>'
 '@S9S_MB_2U_LIB.S9S_MB_2U(SCH_1):M_C_CPU0_SB_CA'<4>:
 C_SIGNAL='@s9s_mb_2u_lib.s9s_mb_2u(sch_1):m_c_cpu0_sb_ca(4)';
NODE_NAME     U2 T40
 '@S9S_MB_2U_LIB.S9S_MB_2U(SCH_1):PAGE22_I169@PURE_QUANTA.SOCKET4677_AZIF0045P001C01CS(CHIPS)':
 'DDR2_SB_CA4': CDS_PINID='DDR2_SB_CA4';
NODE_NAME     J5 80
 '@S9S_MB_2U_LIB.S9S_MB_2U(SCH_1):PAGE86_I24@PURE_QUANTA.SCONN288_ADR50017P130CC(CHIPS)':
 'CA4_B': CDS_PINID='CA4_B';
NODE_NAME     J6 80
 '@S9S_MB_2U_LIB.S9S_MB_2U(SCH_1):PAGE87_I46@PURE_QUANTA.SCONN288_ADR50017P087CC(CHIPS)':
 'CA4_B': CDS_PINID='CA4_B';
NET_NAME
'M_C_CPU0_SB_CA<5>'
 '@S9S_MB_2U_LIB.S9S_MB_2U(SCH_1):M_C_CPU0_SB_CA'<5>:
 C_SIGNAL='@s9s_mb_2u_lib.s9s_mb_2u(sch_1):m_c_cpu0_sb_ca(5)';
NODE_NAME     U2 Y40
 '@S9S_MB_2U_LIB.S9S_MB_2U(SCH_1):PAGE22_I169@PURE_QUANTA.SOCKET4677_AZIF0045P001C01CS(CHIPS)':
 'DDR2_SB_CA5': CDS_PINID='DDR2_SB_CA5';
NODE_NAME     J5 225
 '@S9S_MB_2U_LIB.S9S_MB_2U(SCH_1):PAGE86_I24@PURE_QUANTA.SCONN288_ADR50017P130CC(CHIPS)':
 'CA5_B': CDS_PINID='CA5_B';
NODE_NAME     J6 225
 '@S9S_MB_2U_LIB.S9S_MB_2U(SCH_1):PAGE87_I46@PURE_QUANTA.SCONN288_ADR50017P087CC(CHIPS)':
 'CA5_B': CDS_PINID='CA5_B';
NET_NAME
'M_C_CPU0_SB_CA<6>'
 '@S9S_MB_2U_LIB.S9S_MB_2U(SCH_1):M_C_CPU0_SB_CA'<6>:
 C_SIGNAL='@s9s_mb_2u_lib.s9s_mb_2u(sch_1):m_c_cpu0_sb_ca(6)';
NODE_NAME     U2 R39
 '@S9S_MB_2U_LIB.S9S_MB_2U(SCH_1):PAGE22_I169@PURE_QUANTA.SOCKET4677_AZIF0045P001C01CS(CHIPS)':
 'DDR2_SB_CA6': CDS_PINID='DDR2_SB_CA6';
NODE_NAME     J5 82
 '@S9S_MB_2U_LIB.S9S_MB_2U(SCH_1):PAGE86_I24@PURE_QUANTA.SCONN288_ADR50017P130CC(CHIPS)':
 'CA6_B': CDS_PINID='CA6_B';
NODE_NAME     J6 82
 '@S9S_MB_2U_LIB.S9S_MB_2U(SCH_1):PAGE87_I46@PURE_QUANTA.SCONN288_ADR50017P087CC(CHIPS)':
 'CA6_B': CDS_PINID='CA6_B';
NET_NAME
'M_C_CPU0_SB_CB<0>'
 '@S9S_MB_2U_LIB.S9S_MB_2U(SCH_1):M_C_CPU0_SB_CB'<0>:
 C_SIGNAL='@s9s_mb_2u_lib.s9s_mb_2u(sch_1):m_c_cpu0_sb_cb(0)';
NODE_NAME     U2 T32
 '@S9S_MB_2U_LIB.S9S_MB_2U(SCH_1):PAGE22_I169@PURE_QUANTA.SOCKET4677_AZIF0045P001C01CS(CHIPS)':
 'DDR2_SB_ECC0': CDS_PINID='DDR2_SB_ECC0';
NODE_NAME     J5 96
 '@S9S_MB_2U_LIB.S9S_MB_2U(SCH_1):PAGE86_I24@PURE_QUANTA.SCONN288_ADR50017P130CC(CHIPS)':
 'CB0_B': CDS_PINID='CB0_B';
NODE_NAME     J6 96
 '@S9S_MB_2U_LIB.S9S_MB_2U(SCH_1):PAGE87_I46@PURE_QUANTA.SCONN288_ADR50017P087CC(CHIPS)':
 'CB0_B': CDS_PINID='CB0_B';
NET_NAME
'M_C_CPU0_SB_CB<1>'
 '@S9S_MB_2U_LIB.S9S_MB_2U(SCH_1):M_C_CPU0_SB_CB'<1>:
 C_SIGNAL='@s9s_mb_2u_lib.s9s_mb_2u(sch_1):m_c_cpu0_sb_cb(1)';
NODE_NAME     U2 U31
 '@S9S_MB_2U_LIB.S9S_MB_2U(SCH_1):PAGE22_I169@PURE_QUANTA.SOCKET4677_AZIF0045P001C01CS(CHIPS)':
 'DDR2_SB_ECC1': CDS_PINID='DDR2_SB_ECC1';
NODE_NAME     J5 98
 '@S9S_MB_2U_LIB.S9S_MB_2U(SCH_1):PAGE86_I24@PURE_QUANTA.SCONN288_ADR50017P130CC(CHIPS)':
 'CB1_B': CDS_PINID='CB1_B';
NODE_NAME     J6 98
 '@S9S_MB_2U_LIB.S9S_MB_2U(SCH_1):PAGE87_I46@PURE_QUANTA.SCONN288_ADR50017P087CC(CHIPS)':
 'CB1_B': CDS_PINID='CB1_B';
NET_NAME
'M_C_CPU0_SB_CB<2>'
 '@S9S_MB_2U_LIB.S9S_MB_2U(SCH_1):M_C_CPU0_SB_CB'<2>:
 C_SIGNAL='@s9s_mb_2u_lib.s9s_mb_2u(sch_1):m_c_cpu0_sb_cb(2)';
NODE_NAME     U2 Y32
 '@S9S_MB_2U_LIB.S9S_MB_2U(SCH_1):PAGE22_I169@PURE_QUANTA.SOCKET4677_AZIF0045P001C01CS(CHIPS)':
 'DDR2_SB_ECC2': CDS_PINID='DDR2_SB_ECC2';
NODE_NAME     J5 241
 '@S9S_MB_2U_LIB.S9S_MB_2U(SCH_1):PAGE86_I24@PURE_QUANTA.SCONN288_ADR50017P130CC(CHIPS)':
 'CB2_B': CDS_PINID='CB2_B';
NODE_NAME     J6 241
 '@S9S_MB_2U_LIB.S9S_MB_2U(SCH_1):PAGE87_I46@PURE_QUANTA.SCONN288_ADR50017P087CC(CHIPS)':
 'CB2_B': CDS_PINID='CB2_B';
NET_NAME
'M_C_CPU0_SB_CB<3>'
 '@S9S_MB_2U_LIB.S9S_MB_2U(SCH_1):M_C_CPU0_SB_CB'<3>:
 C_SIGNAL='@s9s_mb_2u_lib.s9s_mb_2u(sch_1):m_c_cpu0_sb_cb(3)';
NODE_NAME     U2 W31
 '@S9S_MB_2U_LIB.S9S_MB_2U(SCH_1):PAGE22_I169@PURE_QUANTA.SOCKET4677_AZIF0045P001C01CS(CHIPS)':
 'DDR2_SB_ECC3': CDS_PINID='DDR2_SB_ECC3';
NODE_NAME     J5 243
 '@S9S_MB_2U_LIB.S9S_MB_2U(SCH_1):PAGE86_I24@PURE_QUANTA.SCONN288_ADR50017P130CC(CHIPS)':
 'CB3_B': CDS_PINID='CB3_B';
NODE_NAME     J6 243
 '@S9S_MB_2U_LIB.S9S_MB_2U(SCH_1):PAGE87_I46@PURE_QUANTA.SCONN288_ADR50017P087CC(CHIPS)':
 'CB3_B': CDS_PINID='CB3_B';
NET_NAME
'M_C_CPU0_SB_CB<4>'
 '@S9S_MB_2U_LIB.S9S_MB_2U(SCH_1):M_C_CPU0_SB_CB'<4>:
 C_SIGNAL='@s9s_mb_2u_lib.s9s_mb_2u(sch_1):m_c_cpu0_sb_cb(4)';
NODE_NAME     U2 U35
 '@S9S_MB_2U_LIB.S9S_MB_2U(SCH_1):PAGE22_I169@PURE_QUANTA.SOCKET4677_AZIF0045P001C01CS(CHIPS)':
 'DDR2_SB_ECC4': CDS_PINID='DDR2_SB_ECC4';
NODE_NAME     J5 89
 '@S9S_MB_2U_LIB.S9S_MB_2U(SCH_1):PAGE86_I24@PURE_QUANTA.SCONN288_ADR50017P130CC(CHIPS)':
 'CB4_B': CDS_PINID='CB4_B';
NODE_NAME     J6 89
 '@S9S_MB_2U_LIB.S9S_MB_2U(SCH_1):PAGE87_I46@PURE_QUANTA.SCONN288_ADR50017P087CC(CHIPS)':
 'CB4_B': CDS_PINID='CB4_B';
NET_NAME
'M_C_CPU0_SB_CB<5>'
 '@S9S_MB_2U_LIB.S9S_MB_2U(SCH_1):M_C_CPU0_SB_CB'<5>:
 C_SIGNAL='@s9s_mb_2u_lib.s9s_mb_2u(sch_1):m_c_cpu0_sb_cb(5)';
NODE_NAME     U2 T34
 '@S9S_MB_2U_LIB.S9S_MB_2U(SCH_1):PAGE22_I169@PURE_QUANTA.SOCKET4677_AZIF0045P001C01CS(CHIPS)':
 'DDR2_SB_ECC5': CDS_PINID='DDR2_SB_ECC5';
NODE_NAME     J5 91
 '@S9S_MB_2U_LIB.S9S_MB_2U(SCH_1):PAGE86_I24@PURE_QUANTA.SCONN288_ADR50017P130CC(CHIPS)':
 'CB5_B': CDS_PINID='CB5_B';
NODE_NAME     J6 91
 '@S9S_MB_2U_LIB.S9S_MB_2U(SCH_1):PAGE87_I46@PURE_QUANTA.SCONN288_ADR50017P087CC(CHIPS)':
 'CB5_B': CDS_PINID='CB5_B';
NET_NAME
'M_C_CPU0_SB_CB<6>'
 '@S9S_MB_2U_LIB.S9S_MB_2U(SCH_1):M_C_CPU0_SB_CB'<6>:
 C_SIGNAL='@s9s_mb_2u_lib.s9s_mb_2u(sch_1):m_c_cpu0_sb_cb(6)';
NODE_NAME     U2 W35
 '@S9S_MB_2U_LIB.S9S_MB_2U(SCH_1):PAGE22_I169@PURE_QUANTA.SOCKET4677_AZIF0045P001C01CS(CHIPS)':
 'DDR2_SB_ECC6': CDS_PINID='DDR2_SB_ECC6';
NODE_NAME     J5 234
 '@S9S_MB_2U_LIB.S9S_MB_2U(SCH_1):PAGE86_I24@PURE_QUANTA.SCONN288_ADR50017P130CC(CHIPS)':
 'CB6_B': CDS_PINID='CB6_B';
NODE_NAME     J6 234
 '@S9S_MB_2U_LIB.S9S_MB_2U(SCH_1):PAGE87_I46@PURE_QUANTA.SCONN288_ADR50017P087CC(CHIPS)':
 'CB6_B': CDS_PINID='CB6_B';
NET_NAME
'M_C_CPU0_SB_CB<7>'
 '@S9S_MB_2U_LIB.S9S_MB_2U(SCH_1):M_C_CPU0_SB_CB'<7>:
 C_SIGNAL='@s9s_mb_2u_lib.s9s_mb_2u(sch_1):m_c_cpu0_sb_cb(7)';
NODE_NAME     U2 Y34
 '@S9S_MB_2U_LIB.S9S_MB_2U(SCH_1):PAGE22_I169@PURE_QUANTA.SOCKET4677_AZIF0045P001C01CS(CHIPS)':
 'DDR2_SB_ECC7': CDS_PINID='DDR2_SB_ECC7';
NODE_NAME     J5 236
 '@S9S_MB_2U_LIB.S9S_MB_2U(SCH_1):PAGE86_I24@PURE_QUANTA.SCONN288_ADR50017P130CC(CHIPS)':
 'CB7_B': CDS_PINID='CB7_B';
NODE_NAME     J6 236
 '@S9S_MB_2U_LIB.S9S_MB_2U(SCH_1):PAGE87_I46@PURE_QUANTA.SCONN288_ADR50017P087CC(CHIPS)':
 'CB7_B': CDS_PINID='CB7_B';
NET_NAME
'M_C_CPU0_SB_CS_N<0>'
 '@S9S_MB_2U_LIB.S9S_MB_2U(SCH_1):M_C_CPU0_SB_CS_N'<0>:
 C_SIGNAL='@s9s_mb_2u_lib.s9s_mb_2u(sch_1):m_c_cpu0_sb_cs_n(0)';
NODE_NAME     U2 T38
 '@S9S_MB_2U_LIB.S9S_MB_2U(SCH_1):PAGE22_I169@PURE_QUANTA.SOCKET4677_AZIF0045P001C01CS(CHIPS)':
 'DDR2_SB_CS_N0': CDS_PINID='DDR2_SB_CS_N0';
NODE_NAME     J5 84
 '@S9S_MB_2U_LIB.S9S_MB_2U(SCH_1):PAGE86_I24@PURE_QUANTA.SCONN288_ADR50017P130CC(CHIPS)':
 'CS0_B_N': CDS_PINID='CS0_B_N';
NET_NAME
'M_C_CPU0_SB_CS_N<1>'
 '@S9S_MB_2U_LIB.S9S_MB_2U(SCH_1):M_C_CPU0_SB_CS_N'<1>:
 C_SIGNAL='@s9s_mb_2u_lib.s9s_mb_2u(sch_1):m_c_cpu0_sb_cs_n(1)';
NODE_NAME     U2 U37
 '@S9S_MB_2U_LIB.S9S_MB_2U(SCH_1):PAGE22_I169@PURE_QUANTA.SOCKET4677_AZIF0045P001C01CS(CHIPS)':
 'DDR2_SB_CS_N1': CDS_PINID='DDR2_SB_CS_N1';
NODE_NAME     J5 229
 '@S9S_MB_2U_LIB.S9S_MB_2U(SCH_1):PAGE86_I24@PURE_QUANTA.SCONN288_ADR50017P130CC(CHIPS)':
 'CS1_B_N': CDS_PINID='CS1_B_N';
NET_NAME
'M_C_CPU0_SB_CS_N<2>'
 '@S9S_MB_2U_LIB.S9S_MB_2U(SCH_1):M_C_CPU0_SB_CS_N'<2>:
 C_SIGNAL='@s9s_mb_2u_lib.s9s_mb_2u(sch_1):m_c_cpu0_sb_cs_n(2)';
NODE_NAME     U2 Y38
 '@S9S_MB_2U_LIB.S9S_MB_2U(SCH_1):PAGE22_I169@PURE_QUANTA.SOCKET4677_AZIF0045P001C01CS(CHIPS)':
 'DDR2_SB_CS_N2': CDS_PINID='DDR2_SB_CS_N2';
NODE_NAME     J6 84
 '@S9S_MB_2U_LIB.S9S_MB_2U(SCH_1):PAGE87_I46@PURE_QUANTA.SCONN288_ADR50017P087CC(CHIPS)':
 'CS0_B_N': CDS_PINID='CS0_B_N';
NET_NAME
'M_C_CPU0_SB_CS_N<3>'
 '@S9S_MB_2U_LIB.S9S_MB_2U(SCH_1):M_C_CPU0_SB_CS_N'<3>:
 C_SIGNAL='@s9s_mb_2u_lib.s9s_mb_2u(sch_1):m_c_cpu0_sb_cs_n(3)';
NODE_NAME     U2 W37
 '@S9S_MB_2U_LIB.S9S_MB_2U(SCH_1):PAGE22_I169@PURE_QUANTA.SOCKET4677_AZIF0045P001C01CS(CHIPS)':
 'DDR2_SB_CS_N3': CDS_PINID='DDR2_SB_CS_N3';
NODE_NAME     J6 229
 '@S9S_MB_2U_LIB.S9S_MB_2U(SCH_1):PAGE87_I46@PURE_QUANTA.SCONN288_ADR50017P087CC(CHIPS)':
 'CS1_B_N': CDS_PINID='CS1_B_N';
NET_NAME
'M_C_CPU0_SB_DQ<0>'
 '@S9S_MB_2U_LIB.S9S_MB_2U(SCH_1):M_C_CPU0_SB_DQ'<0>:
 C_SIGNAL='@s9s_mb_2u_lib.s9s_mb_2u(sch_1):m_c_cpu0_sb_dq(0)';
NODE_NAME     U2 AD38
 '@S9S_MB_2U_LIB.S9S_MB_2U(SCH_1):PAGE22_I169@PURE_QUANTA.SOCKET4677_AZIF0045P001C01CS(CHIPS)':
 'DDR2_SB_DQ0': CDS_PINID='DDR2_SB_DQ0';
NODE_NAME     J5 100
 '@S9S_MB_2U_LIB.S9S_MB_2U(SCH_1):PAGE86_I24@PURE_QUANTA.SCONN288_ADR50017P130CC(CHIPS)':
 'DQ0_B': CDS_PINID='DQ0_B';
NODE_NAME     J6 100
 '@S9S_MB_2U_LIB.S9S_MB_2U(SCH_1):PAGE87_I46@PURE_QUANTA.SCONN288_ADR50017P087CC(CHIPS)':
 'DQ0_B': CDS_PINID='DQ0_B';
NET_NAME
'M_C_CPU0_SB_DQ<10>'
 '@S9S_MB_2U_LIB.S9S_MB_2U(SCH_1):M_C_CPU0_SB_DQ'<10>:
 C_SIGNAL='@s9s_mb_2u_lib.s9s_mb_2u(sch_1):m_c_cpu0_sb_dq(10)';
NODE_NAME     U2 AF32
 '@S9S_MB_2U_LIB.S9S_MB_2U(SCH_1):PAGE22_I169@PURE_QUANTA.SOCKET4677_AZIF0045P001C01CS(CHIPS)':
 'DDR2_SB_DQ10': CDS_PINID='DDR2_SB_DQ10';
NODE_NAME     J5 256
 '@S9S_MB_2U_LIB.S9S_MB_2U(SCH_1):PAGE86_I24@PURE_QUANTA.SCONN288_ADR50017P130CC(CHIPS)':
 'DQ10_B': CDS_PINID='DQ10_B';
NODE_NAME     J6 256
 '@S9S_MB_2U_LIB.S9S_MB_2U(SCH_1):PAGE87_I46@PURE_QUANTA.SCONN288_ADR50017P087CC(CHIPS)':
 'DQ10_B': CDS_PINID='DQ10_B';
NET_NAME
'M_C_CPU0_SB_DQ<11>'
 '@S9S_MB_2U_LIB.S9S_MB_2U(SCH_1):M_C_CPU0_SB_DQ'<11>:
 C_SIGNAL='@s9s_mb_2u_lib.s9s_mb_2u(sch_1):m_c_cpu0_sb_dq(11)';
NODE_NAME     U2 AG31
 '@S9S_MB_2U_LIB.S9S_MB_2U(SCH_1):PAGE22_I169@PURE_QUANTA.SOCKET4677_AZIF0045P001C01CS(CHIPS)':
 'DDR2_SB_DQ11': CDS_PINID='DDR2_SB_DQ11';
NODE_NAME     J5 258
 '@S9S_MB_2U_LIB.S9S_MB_2U(SCH_1):PAGE86_I24@PURE_QUANTA.SCONN288_ADR50017P130CC(CHIPS)':
 'DQ11_B': CDS_PINID='DQ11_B';
NODE_NAME     J6 258
 '@S9S_MB_2U_LIB.S9S_MB_2U(SCH_1):PAGE87_I46@PURE_QUANTA.SCONN288_ADR50017P087CC(CHIPS)':
 'DQ11_B': CDS_PINID='DQ11_B';
NET_NAME
'M_C_CPU0_SB_DQ<12>'
 '@S9S_MB_2U_LIB.S9S_MB_2U(SCH_1):M_C_CPU0_SB_DQ'<12>:
 C_SIGNAL='@s9s_mb_2u_lib.s9s_mb_2u(sch_1):m_c_cpu0_sb_dq(12)';
NODE_NAME     U2 AC29
 '@S9S_MB_2U_LIB.S9S_MB_2U(SCH_1):PAGE22_I169@PURE_QUANTA.SOCKET4677_AZIF0045P001C01CS(CHIPS)':
 'DDR2_SB_DQ12': CDS_PINID='DDR2_SB_DQ12';
NODE_NAME     J5 118
 '@S9S_MB_2U_LIB.S9S_MB_2U(SCH_1):PAGE86_I24@PURE_QUANTA.SCONN288_ADR50017P130CC(CHIPS)':
 'DQ12_B': CDS_PINID='DQ12_B';
NODE_NAME     J6 118
 '@S9S_MB_2U_LIB.S9S_MB_2U(SCH_1):PAGE87_I46@PURE_QUANTA.SCONN288_ADR50017P087CC(CHIPS)':
 'DQ12_B': CDS_PINID='DQ12_B';
NET_NAME
'M_C_CPU0_SB_DQ<13>'
 '@S9S_MB_2U_LIB.S9S_MB_2U(SCH_1):M_C_CPU0_SB_DQ'<13>:
 C_SIGNAL='@s9s_mb_2u_lib.s9s_mb_2u(sch_1):m_c_cpu0_sb_dq(13)';
NODE_NAME     U2 AD28
 '@S9S_MB_2U_LIB.S9S_MB_2U(SCH_1):PAGE22_I169@PURE_QUANTA.SOCKET4677_AZIF0045P001C01CS(CHIPS)':
 'DDR2_SB_DQ13': CDS_PINID='DDR2_SB_DQ13';
NODE_NAME     J5 120
 '@S9S_MB_2U_LIB.S9S_MB_2U(SCH_1):PAGE86_I24@PURE_QUANTA.SCONN288_ADR50017P130CC(CHIPS)':
 'DQ13_B': CDS_PINID='DQ13_B';
NODE_NAME     J6 120
 '@S9S_MB_2U_LIB.S9S_MB_2U(SCH_1):PAGE87_I46@PURE_QUANTA.SCONN288_ADR50017P087CC(CHIPS)':
 'DQ13_B': CDS_PINID='DQ13_B';
NET_NAME
'M_C_CPU0_SB_DQ<14>'
 '@S9S_MB_2U_LIB.S9S_MB_2U(SCH_1):M_C_CPU0_SB_DQ'<14>:
 C_SIGNAL='@s9s_mb_2u_lib.s9s_mb_2u(sch_1):m_c_cpu0_sb_dq(14)';
NODE_NAME     U2 AG29
 '@S9S_MB_2U_LIB.S9S_MB_2U(SCH_1):PAGE22_I169@PURE_QUANTA.SOCKET4677_AZIF0045P001C01CS(CHIPS)':
 'DDR2_SB_DQ14': CDS_PINID='DDR2_SB_DQ14';
NODE_NAME     J5 263
 '@S9S_MB_2U_LIB.S9S_MB_2U(SCH_1):PAGE86_I24@PURE_QUANTA.SCONN288_ADR50017P130CC(CHIPS)':
 'DQ14_B': CDS_PINID='DQ14_B';
NODE_NAME     J6 263
 '@S9S_MB_2U_LIB.S9S_MB_2U(SCH_1):PAGE87_I46@PURE_QUANTA.SCONN288_ADR50017P087CC(CHIPS)':
 'DQ14_B': CDS_PINID='DQ14_B';
NET_NAME
'M_C_CPU0_SB_DQ<15>'
 '@S9S_MB_2U_LIB.S9S_MB_2U(SCH_1):M_C_CPU0_SB_DQ'<15>:
 C_SIGNAL='@s9s_mb_2u_lib.s9s_mb_2u(sch_1):m_c_cpu0_sb_dq(15)';
NODE_NAME     U2 AF28
 '@S9S_MB_2U_LIB.S9S_MB_2U(SCH_1):PAGE22_I169@PURE_QUANTA.SOCKET4677_AZIF0045P001C01CS(CHIPS)':
 'DDR2_SB_DQ15': CDS_PINID='DDR2_SB_DQ15';
NODE_NAME     J5 265
 '@S9S_MB_2U_LIB.S9S_MB_2U(SCH_1):PAGE86_I24@PURE_QUANTA.SCONN288_ADR50017P130CC(CHIPS)':
 'DQ15_B': CDS_PINID='DQ15_B';
NODE_NAME     J6 265
 '@S9S_MB_2U_LIB.S9S_MB_2U(SCH_1):PAGE87_I46@PURE_QUANTA.SCONN288_ADR50017P087CC(CHIPS)':
 'DQ15_B': CDS_PINID='DQ15_B';
NET_NAME
'M_C_CPU0_SB_DQ<16>'
 '@S9S_MB_2U_LIB.S9S_MB_2U(SCH_1):M_C_CPU0_SB_DQ'<16>:
 C_SIGNAL='@s9s_mb_2u_lib.s9s_mb_2u(sch_1):m_c_cpu0_sb_dq(16)';
NODE_NAME     U2 U23
 '@S9S_MB_2U_LIB.S9S_MB_2U(SCH_1):PAGE22_I169@PURE_QUANTA.SOCKET4677_AZIF0045P001C01CS(CHIPS)':
 'DDR2_SB_DQ16': CDS_PINID='DDR2_SB_DQ16';
NODE_NAME     J5 122
 '@S9S_MB_2U_LIB.S9S_MB_2U(SCH_1):PAGE86_I24@PURE_QUANTA.SCONN288_ADR50017P130CC(CHIPS)':
 'DQ16_B': CDS_PINID='DQ16_B';
NODE_NAME     J6 122
 '@S9S_MB_2U_LIB.S9S_MB_2U(SCH_1):PAGE87_I46@PURE_QUANTA.SCONN288_ADR50017P087CC(CHIPS)':
 'DQ16_B': CDS_PINID='DQ16_B';
NET_NAME
'M_C_CPU0_SB_DQ<17>'
 '@S9S_MB_2U_LIB.S9S_MB_2U(SCH_1):M_C_CPU0_SB_DQ'<17>:
 C_SIGNAL='@s9s_mb_2u_lib.s9s_mb_2u(sch_1):m_c_cpu0_sb_dq(17)';
NODE_NAME     U2 T22
 '@S9S_MB_2U_LIB.S9S_MB_2U(SCH_1):PAGE22_I169@PURE_QUANTA.SOCKET4677_AZIF0045P001C01CS(CHIPS)':
 'DDR2_SB_DQ17': CDS_PINID='DDR2_SB_DQ17';
NODE_NAME     J5 124
 '@S9S_MB_2U_LIB.S9S_MB_2U(SCH_1):PAGE86_I24@PURE_QUANTA.SCONN288_ADR50017P130CC(CHIPS)':
 'DQ17_B': CDS_PINID='DQ17_B';
NODE_NAME     J6 124
 '@S9S_MB_2U_LIB.S9S_MB_2U(SCH_1):PAGE87_I46@PURE_QUANTA.SCONN288_ADR50017P087CC(CHIPS)':
 'DQ17_B': CDS_PINID='DQ17_B';
NET_NAME
'M_C_CPU0_SB_DQ<18>'
 '@S9S_MB_2U_LIB.S9S_MB_2U(SCH_1):M_C_CPU0_SB_DQ'<18>:
 C_SIGNAL='@s9s_mb_2u_lib.s9s_mb_2u(sch_1):m_c_cpu0_sb_dq(18)';
NODE_NAME     U2 W23
 '@S9S_MB_2U_LIB.S9S_MB_2U(SCH_1):PAGE22_I169@PURE_QUANTA.SOCKET4677_AZIF0045P001C01CS(CHIPS)':
 'DDR2_SB_DQ18': CDS_PINID='DDR2_SB_DQ18';
NODE_NAME     J5 267
 '@S9S_MB_2U_LIB.S9S_MB_2U(SCH_1):PAGE86_I24@PURE_QUANTA.SCONN288_ADR50017P130CC(CHIPS)':
 'DQ18_B': CDS_PINID='DQ18_B';
NODE_NAME     J6 267
 '@S9S_MB_2U_LIB.S9S_MB_2U(SCH_1):PAGE87_I46@PURE_QUANTA.SCONN288_ADR50017P087CC(CHIPS)':
 'DQ18_B': CDS_PINID='DQ18_B';
NET_NAME
'M_C_CPU0_SB_DQ<19>'
 '@S9S_MB_2U_LIB.S9S_MB_2U(SCH_1):M_C_CPU0_SB_DQ'<19>:
 C_SIGNAL='@s9s_mb_2u_lib.s9s_mb_2u(sch_1):m_c_cpu0_sb_dq(19)';
NODE_NAME     U2 Y22
 '@S9S_MB_2U_LIB.S9S_MB_2U(SCH_1):PAGE22_I169@PURE_QUANTA.SOCKET4677_AZIF0045P001C01CS(CHIPS)':
 'DDR2_SB_DQ19': CDS_PINID='DDR2_SB_DQ19';
NODE_NAME     J5 269
 '@S9S_MB_2U_LIB.S9S_MB_2U(SCH_1):PAGE86_I24@PURE_QUANTA.SCONN288_ADR50017P130CC(CHIPS)':
 'DQ19_B': CDS_PINID='DQ19_B';
NODE_NAME     J6 269
 '@S9S_MB_2U_LIB.S9S_MB_2U(SCH_1):PAGE87_I46@PURE_QUANTA.SCONN288_ADR50017P087CC(CHIPS)':
 'DQ19_B': CDS_PINID='DQ19_B';
NET_NAME
'M_C_CPU0_SB_DQ<1>'
 '@S9S_MB_2U_LIB.S9S_MB_2U(SCH_1):M_C_CPU0_SB_DQ'<1>:
 C_SIGNAL='@s9s_mb_2u_lib.s9s_mb_2u(sch_1):m_c_cpu0_sb_dq(1)';
NODE_NAME     U2 AC37
 '@S9S_MB_2U_LIB.S9S_MB_2U(SCH_1):PAGE22_I169@PURE_QUANTA.SOCKET4677_AZIF0045P001C01CS(CHIPS)':
 'DDR2_SB_DQ1': CDS_PINID='DDR2_SB_DQ1';
NODE_NAME     J5 102
 '@S9S_MB_2U_LIB.S9S_MB_2U(SCH_1):PAGE86_I24@PURE_QUANTA.SCONN288_ADR50017P130CC(CHIPS)':
 'DQ1_B': CDS_PINID='DQ1_B';
NODE_NAME     J6 102
 '@S9S_MB_2U_LIB.S9S_MB_2U(SCH_1):PAGE87_I46@PURE_QUANTA.SCONN288_ADR50017P087CC(CHIPS)':
 'DQ1_B': CDS_PINID='DQ1_B';
NET_NAME
'M_C_CPU0_SB_DQ<20>'
 '@S9S_MB_2U_LIB.S9S_MB_2U(SCH_1):M_C_CPU0_SB_DQ'<20>:
 C_SIGNAL='@s9s_mb_2u_lib.s9s_mb_2u(sch_1):m_c_cpu0_sb_dq(20)';
NODE_NAME     U2 T20
 '@S9S_MB_2U_LIB.S9S_MB_2U(SCH_1):PAGE22_I169@PURE_QUANTA.SOCKET4677_AZIF0045P001C01CS(CHIPS)':
 'DDR2_SB_DQ20': CDS_PINID='DDR2_SB_DQ20';
NODE_NAME     J5 129
 '@S9S_MB_2U_LIB.S9S_MB_2U(SCH_1):PAGE86_I24@PURE_QUANTA.SCONN288_ADR50017P130CC(CHIPS)':
 'DQ20_B': CDS_PINID='DQ20_B';
NODE_NAME     J6 129
 '@S9S_MB_2U_LIB.S9S_MB_2U(SCH_1):PAGE87_I46@PURE_QUANTA.SCONN288_ADR50017P087CC(CHIPS)':
 'DQ20_B': CDS_PINID='DQ20_B';
NET_NAME
'M_C_CPU0_SB_DQ<21>'
 '@S9S_MB_2U_LIB.S9S_MB_2U(SCH_1):M_C_CPU0_SB_DQ'<21>:
 C_SIGNAL='@s9s_mb_2u_lib.s9s_mb_2u(sch_1):m_c_cpu0_sb_dq(21)';
NODE_NAME     U2 U19
 '@S9S_MB_2U_LIB.S9S_MB_2U(SCH_1):PAGE22_I169@PURE_QUANTA.SOCKET4677_AZIF0045P001C01CS(CHIPS)':
 'DDR2_SB_DQ21': CDS_PINID='DDR2_SB_DQ21';
NODE_NAME     J5 131
 '@S9S_MB_2U_LIB.S9S_MB_2U(SCH_1):PAGE86_I24@PURE_QUANTA.SCONN288_ADR50017P130CC(CHIPS)':
 'DQ21_B': CDS_PINID='DQ21_B';
NODE_NAME     J6 131
 '@S9S_MB_2U_LIB.S9S_MB_2U(SCH_1):PAGE87_I46@PURE_QUANTA.SCONN288_ADR50017P087CC(CHIPS)':
 'DQ21_B': CDS_PINID='DQ21_B';
NET_NAME
'M_C_CPU0_SB_DQ<22>'
 '@S9S_MB_2U_LIB.S9S_MB_2U(SCH_1):M_C_CPU0_SB_DQ'<22>:
 C_SIGNAL='@s9s_mb_2u_lib.s9s_mb_2u(sch_1):m_c_cpu0_sb_dq(22)';
NODE_NAME     U2 Y20
 '@S9S_MB_2U_LIB.S9S_MB_2U(SCH_1):PAGE22_I169@PURE_QUANTA.SOCKET4677_AZIF0045P001C01CS(CHIPS)':
 'DDR2_SB_DQ22': CDS_PINID='DDR2_SB_DQ22';
NODE_NAME     J5 274
 '@S9S_MB_2U_LIB.S9S_MB_2U(SCH_1):PAGE86_I24@PURE_QUANTA.SCONN288_ADR50017P130CC(CHIPS)':
 'DQ22_B': CDS_PINID='DQ22_B';
NODE_NAME     J6 274
 '@S9S_MB_2U_LIB.S9S_MB_2U(SCH_1):PAGE87_I46@PURE_QUANTA.SCONN288_ADR50017P087CC(CHIPS)':
 'DQ22_B': CDS_PINID='DQ22_B';
NET_NAME
'M_C_CPU0_SB_DQ<23>'
 '@S9S_MB_2U_LIB.S9S_MB_2U(SCH_1):M_C_CPU0_SB_DQ'<23>:
 C_SIGNAL='@s9s_mb_2u_lib.s9s_mb_2u(sch_1):m_c_cpu0_sb_dq(23)';
NODE_NAME     U2 W19
 '@S9S_MB_2U_LIB.S9S_MB_2U(SCH_1):PAGE22_I169@PURE_QUANTA.SOCKET4677_AZIF0045P001C01CS(CHIPS)':
 'DDR2_SB_DQ23': CDS_PINID='DDR2_SB_DQ23';
NODE_NAME     J5 276
 '@S9S_MB_2U_LIB.S9S_MB_2U(SCH_1):PAGE86_I24@PURE_QUANTA.SCONN288_ADR50017P130CC(CHIPS)':
 'DQ23_B': CDS_PINID='DQ23_B';
NODE_NAME     J6 276
 '@S9S_MB_2U_LIB.S9S_MB_2U(SCH_1):PAGE87_I46@PURE_QUANTA.SCONN288_ADR50017P087CC(CHIPS)':
 'DQ23_B': CDS_PINID='DQ23_B';
NET_NAME
'M_C_CPU0_SB_DQ<24>'
 '@S9S_MB_2U_LIB.S9S_MB_2U(SCH_1):M_C_CPU0_SB_DQ'<24>:
 C_SIGNAL='@s9s_mb_2u_lib.s9s_mb_2u(sch_1):m_c_cpu0_sb_dq(24)';
NODE_NAME     U2 AD20
 '@S9S_MB_2U_LIB.S9S_MB_2U(SCH_1):PAGE22_I169@PURE_QUANTA.SOCKET4677_AZIF0045P001C01CS(CHIPS)':
 'DDR2_SB_DQ24': CDS_PINID='DDR2_SB_DQ24';
NODE_NAME     J5 133
 '@S9S_MB_2U_LIB.S9S_MB_2U(SCH_1):PAGE86_I24@PURE_QUANTA.SCONN288_ADR50017P130CC(CHIPS)':
 'DQ24_B': CDS_PINID='DQ24_B';
NODE_NAME     J6 133
 '@S9S_MB_2U_LIB.S9S_MB_2U(SCH_1):PAGE87_I46@PURE_QUANTA.SCONN288_ADR50017P087CC(CHIPS)':
 'DQ24_B': CDS_PINID='DQ24_B';
NET_NAME
'M_C_CPU0_SB_DQ<25>'
 '@S9S_MB_2U_LIB.S9S_MB_2U(SCH_1):M_C_CPU0_SB_DQ'<25>:
 C_SIGNAL='@s9s_mb_2u_lib.s9s_mb_2u(sch_1):m_c_cpu0_sb_dq(25)';
NODE_NAME     U2 AC19
 '@S9S_MB_2U_LIB.S9S_MB_2U(SCH_1):PAGE22_I169@PURE_QUANTA.SOCKET4677_AZIF0045P001C01CS(CHIPS)':
 'DDR2_SB_DQ25': CDS_PINID='DDR2_SB_DQ25';
NODE_NAME     J5 135
 '@S9S_MB_2U_LIB.S9S_MB_2U(SCH_1):PAGE86_I24@PURE_QUANTA.SCONN288_ADR50017P130CC(CHIPS)':
 'DQ25_B': CDS_PINID='DQ25_B';
NODE_NAME     J6 135
 '@S9S_MB_2U_LIB.S9S_MB_2U(SCH_1):PAGE87_I46@PURE_QUANTA.SCONN288_ADR50017P087CC(CHIPS)':
 'DQ25_B': CDS_PINID='DQ25_B';
NET_NAME
'M_C_CPU0_SB_DQ<26>'
 '@S9S_MB_2U_LIB.S9S_MB_2U(SCH_1):M_C_CPU0_SB_DQ'<26>:
 C_SIGNAL='@s9s_mb_2u_lib.s9s_mb_2u(sch_1):m_c_cpu0_sb_dq(26)';
NODE_NAME     U2 AF20
 '@S9S_MB_2U_LIB.S9S_MB_2U(SCH_1):PAGE22_I169@PURE_QUANTA.SOCKET4677_AZIF0045P001C01CS(CHIPS)':
 'DDR2_SB_DQ26': CDS_PINID='DDR2_SB_DQ26';
NODE_NAME     J5 278
 '@S9S_MB_2U_LIB.S9S_MB_2U(SCH_1):PAGE86_I24@PURE_QUANTA.SCONN288_ADR50017P130CC(CHIPS)':
 'DQ26_B': CDS_PINID='DQ26_B';
NODE_NAME     J6 278
 '@S9S_MB_2U_LIB.S9S_MB_2U(SCH_1):PAGE87_I46@PURE_QUANTA.SCONN288_ADR50017P087CC(CHIPS)':
 'DQ26_B': CDS_PINID='DQ26_B';
NET_NAME
'M_C_CPU0_SB_DQ<27>'
 '@S9S_MB_2U_LIB.S9S_MB_2U(SCH_1):M_C_CPU0_SB_DQ'<27>:
 C_SIGNAL='@s9s_mb_2u_lib.s9s_mb_2u(sch_1):m_c_cpu0_sb_dq(27)';
NODE_NAME     U2 AG19
 '@S9S_MB_2U_LIB.S9S_MB_2U(SCH_1):PAGE22_I169@PURE_QUANTA.SOCKET4677_AZIF0045P001C01CS(CHIPS)':
 'DDR2_SB_DQ27': CDS_PINID='DDR2_SB_DQ27';
NODE_NAME     J5 280
 '@S9S_MB_2U_LIB.S9S_MB_2U(SCH_1):PAGE86_I24@PURE_QUANTA.SCONN288_ADR50017P130CC(CHIPS)':
 'DQ27_B': CDS_PINID='DQ27_B';
NODE_NAME     J6 280
 '@S9S_MB_2U_LIB.S9S_MB_2U(SCH_1):PAGE87_I46@PURE_QUANTA.SCONN288_ADR50017P087CC(CHIPS)':
 'DQ27_B': CDS_PINID='DQ27_B';
NET_NAME
'M_C_CPU0_SB_DQ<28>'
 '@S9S_MB_2U_LIB.S9S_MB_2U(SCH_1):M_C_CPU0_SB_DQ'<28>:
 C_SIGNAL='@s9s_mb_2u_lib.s9s_mb_2u(sch_1):m_c_cpu0_sb_dq(28)';
NODE_NAME     U2 AA17
 '@S9S_MB_2U_LIB.S9S_MB_2U(SCH_1):PAGE22_I169@PURE_QUANTA.SOCKET4677_AZIF0045P001C01CS(CHIPS)':
 'DDR2_SB_DQ28': CDS_PINID='DDR2_SB_DQ28';
NODE_NAME     J5 140
 '@S9S_MB_2U_LIB.S9S_MB_2U(SCH_1):PAGE86_I24@PURE_QUANTA.SCONN288_ADR50017P130CC(CHIPS)':
 'DQ28_B': CDS_PINID='DQ28_B';
NODE_NAME     J6 140
 '@S9S_MB_2U_LIB.S9S_MB_2U(SCH_1):PAGE87_I46@PURE_QUANTA.SCONN288_ADR50017P087CC(CHIPS)':
 'DQ28_B': CDS_PINID='DQ28_B';
NET_NAME
'M_C_CPU0_SB_DQ<29>'
 '@S9S_MB_2U_LIB.S9S_MB_2U(SCH_1):M_C_CPU0_SB_DQ'<29>:
 C_SIGNAL='@s9s_mb_2u_lib.s9s_mb_2u(sch_1):m_c_cpu0_sb_dq(29)';
NODE_NAME     U2 AG17
 '@S9S_MB_2U_LIB.S9S_MB_2U(SCH_1):PAGE22_I169@PURE_QUANTA.SOCKET4677_AZIF0045P001C01CS(CHIPS)':
 'DDR2_SB_DQ29': CDS_PINID='DDR2_SB_DQ29';
NODE_NAME     J5 142
 '@S9S_MB_2U_LIB.S9S_MB_2U(SCH_1):PAGE86_I24@PURE_QUANTA.SCONN288_ADR50017P130CC(CHIPS)':
 'DQ29_B': CDS_PINID='DQ29_B';
NODE_NAME     J6 142
 '@S9S_MB_2U_LIB.S9S_MB_2U(SCH_1):PAGE87_I46@PURE_QUANTA.SCONN288_ADR50017P087CC(CHIPS)':
 'DQ29_B': CDS_PINID='DQ29_B';
NET_NAME
'M_C_CPU0_SB_DQ<2>'
 '@S9S_MB_2U_LIB.S9S_MB_2U(SCH_1):M_C_CPU0_SB_DQ'<2>:
 C_SIGNAL='@s9s_mb_2u_lib.s9s_mb_2u(sch_1):m_c_cpu0_sb_dq(2)';
NODE_NAME     U2 AF38
 '@S9S_MB_2U_LIB.S9S_MB_2U(SCH_1):PAGE22_I169@PURE_QUANTA.SOCKET4677_AZIF0045P001C01CS(CHIPS)':
 'DDR2_SB_DQ2': CDS_PINID='DDR2_SB_DQ2';
NODE_NAME     J5 245
 '@S9S_MB_2U_LIB.S9S_MB_2U(SCH_1):PAGE86_I24@PURE_QUANTA.SCONN288_ADR50017P130CC(CHIPS)':
 'DQ2_B': CDS_PINID='DQ2_B';
NODE_NAME     J6 245
 '@S9S_MB_2U_LIB.S9S_MB_2U(SCH_1):PAGE87_I46@PURE_QUANTA.SCONN288_ADR50017P087CC(CHIPS)':
 'DQ2_B': CDS_PINID='DQ2_B';
NET_NAME
'M_C_CPU0_SB_DQ<30>'
 '@S9S_MB_2U_LIB.S9S_MB_2U(SCH_1):M_C_CPU0_SB_DQ'<30>:
 C_SIGNAL='@s9s_mb_2u_lib.s9s_mb_2u(sch_1):m_c_cpu0_sb_dq(30)';
NODE_NAME     U2 AC17
 '@S9S_MB_2U_LIB.S9S_MB_2U(SCH_1):PAGE22_I169@PURE_QUANTA.SOCKET4677_AZIF0045P001C01CS(CHIPS)':
 'DDR2_SB_DQ30': CDS_PINID='DDR2_SB_DQ30';
NODE_NAME     J5 285
 '@S9S_MB_2U_LIB.S9S_MB_2U(SCH_1):PAGE86_I24@PURE_QUANTA.SCONN288_ADR50017P130CC(CHIPS)':
 'DQ30_B': CDS_PINID='DQ30_B';
NODE_NAME     J6 285
 '@S9S_MB_2U_LIB.S9S_MB_2U(SCH_1):PAGE87_I46@PURE_QUANTA.SCONN288_ADR50017P087CC(CHIPS)':
 'DQ30_B': CDS_PINID='DQ30_B';
NET_NAME
'M_C_CPU0_SB_DQ<31>'
 '@S9S_MB_2U_LIB.S9S_MB_2U(SCH_1):M_C_CPU0_SB_DQ'<31>:
 C_SIGNAL='@s9s_mb_2u_lib.s9s_mb_2u(sch_1):m_c_cpu0_sb_dq(31)';
NODE_NAME     U2 AJ17
 '@S9S_MB_2U_LIB.S9S_MB_2U(SCH_1):PAGE22_I169@PURE_QUANTA.SOCKET4677_AZIF0045P001C01CS(CHIPS)':
 'DDR2_SB_DQ31': CDS_PINID='DDR2_SB_DQ31';
NODE_NAME     J5 287
 '@S9S_MB_2U_LIB.S9S_MB_2U(SCH_1):PAGE86_I24@PURE_QUANTA.SCONN288_ADR50017P130CC(CHIPS)':
 'DQ31_B': CDS_PINID='DQ31_B';
NODE_NAME     J6 287
 '@S9S_MB_2U_LIB.S9S_MB_2U(SCH_1):PAGE87_I46@PURE_QUANTA.SCONN288_ADR50017P087CC(CHIPS)':
 'DQ31_B': CDS_PINID='DQ31_B';
NET_NAME
'M_C_CPU0_SB_DQ<3>'
 '@S9S_MB_2U_LIB.S9S_MB_2U(SCH_1):M_C_CPU0_SB_DQ'<3>:
 C_SIGNAL='@s9s_mb_2u_lib.s9s_mb_2u(sch_1):m_c_cpu0_sb_dq(3)';
NODE_NAME     U2 AG37
 '@S9S_MB_2U_LIB.S9S_MB_2U(SCH_1):PAGE22_I169@PURE_QUANTA.SOCKET4677_AZIF0045P001C01CS(CHIPS)':
 'DDR2_SB_DQ3': CDS_PINID='DDR2_SB_DQ3';
NODE_NAME     J5 247
 '@S9S_MB_2U_LIB.S9S_MB_2U(SCH_1):PAGE86_I24@PURE_QUANTA.SCONN288_ADR50017P130CC(CHIPS)':
 'DQ3_B': CDS_PINID='DQ3_B';
NODE_NAME     J6 247
 '@S9S_MB_2U_LIB.S9S_MB_2U(SCH_1):PAGE87_I46@PURE_QUANTA.SCONN288_ADR50017P087CC(CHIPS)':
 'DQ3_B': CDS_PINID='DQ3_B';
NET_NAME
'M_C_CPU0_SB_DQ<4>'
 '@S9S_MB_2U_LIB.S9S_MB_2U(SCH_1):M_C_CPU0_SB_DQ'<4>:
 C_SIGNAL='@s9s_mb_2u_lib.s9s_mb_2u(sch_1):m_c_cpu0_sb_dq(4)';
NODE_NAME     U2 AC35
 '@S9S_MB_2U_LIB.S9S_MB_2U(SCH_1):PAGE22_I169@PURE_QUANTA.SOCKET4677_AZIF0045P001C01CS(CHIPS)':
 'DDR2_SB_DQ4': CDS_PINID='DDR2_SB_DQ4';
NODE_NAME     J5 107
 '@S9S_MB_2U_LIB.S9S_MB_2U(SCH_1):PAGE86_I24@PURE_QUANTA.SCONN288_ADR50017P130CC(CHIPS)':
 'DQ4_B': CDS_PINID='DQ4_B';
NODE_NAME     J6 107
 '@S9S_MB_2U_LIB.S9S_MB_2U(SCH_1):PAGE87_I46@PURE_QUANTA.SCONN288_ADR50017P087CC(CHIPS)':
 'DQ4_B': CDS_PINID='DQ4_B';
NET_NAME
'M_C_CPU0_SB_DQ<5>'
 '@S9S_MB_2U_LIB.S9S_MB_2U(SCH_1):M_C_CPU0_SB_DQ'<5>:
 C_SIGNAL='@s9s_mb_2u_lib.s9s_mb_2u(sch_1):m_c_cpu0_sb_dq(5)';
NODE_NAME     U2 AD34
 '@S9S_MB_2U_LIB.S9S_MB_2U(SCH_1):PAGE22_I169@PURE_QUANTA.SOCKET4677_AZIF0045P001C01CS(CHIPS)':
 'DDR2_SB_DQ5': CDS_PINID='DDR2_SB_DQ5';
NODE_NAME     J5 109
 '@S9S_MB_2U_LIB.S9S_MB_2U(SCH_1):PAGE86_I24@PURE_QUANTA.SCONN288_ADR50017P130CC(CHIPS)':
 'DQ5_B': CDS_PINID='DQ5_B';
NODE_NAME     J6 109
 '@S9S_MB_2U_LIB.S9S_MB_2U(SCH_1):PAGE87_I46@PURE_QUANTA.SCONN288_ADR50017P087CC(CHIPS)':
 'DQ5_B': CDS_PINID='DQ5_B';
NET_NAME
'M_C_CPU0_SB_DQ<6>'
 '@S9S_MB_2U_LIB.S9S_MB_2U(SCH_1):M_C_CPU0_SB_DQ'<6>:
 C_SIGNAL='@s9s_mb_2u_lib.s9s_mb_2u(sch_1):m_c_cpu0_sb_dq(6)';
NODE_NAME     U2 AG35
 '@S9S_MB_2U_LIB.S9S_MB_2U(SCH_1):PAGE22_I169@PURE_QUANTA.SOCKET4677_AZIF0045P001C01CS(CHIPS)':
 'DDR2_SB_DQ6': CDS_PINID='DDR2_SB_DQ6';
NODE_NAME     J5 252
 '@S9S_MB_2U_LIB.S9S_MB_2U(SCH_1):PAGE86_I24@PURE_QUANTA.SCONN288_ADR50017P130CC(CHIPS)':
 'DQ6_B': CDS_PINID='DQ6_B';
NODE_NAME     J6 252
 '@S9S_MB_2U_LIB.S9S_MB_2U(SCH_1):PAGE87_I46@PURE_QUANTA.SCONN288_ADR50017P087CC(CHIPS)':
 'DQ6_B': CDS_PINID='DQ6_B';
NET_NAME
'M_C_CPU0_SB_DQ<7>'
 '@S9S_MB_2U_LIB.S9S_MB_2U(SCH_1):M_C_CPU0_SB_DQ'<7>:
 C_SIGNAL='@s9s_mb_2u_lib.s9s_mb_2u(sch_1):m_c_cpu0_sb_dq(7)';
NODE_NAME     U2 AF34
 '@S9S_MB_2U_LIB.S9S_MB_2U(SCH_1):PAGE22_I169@PURE_QUANTA.SOCKET4677_AZIF0045P001C01CS(CHIPS)':
 'DDR2_SB_DQ7': CDS_PINID='DDR2_SB_DQ7';
NODE_NAME     J5 254
 '@S9S_MB_2U_LIB.S9S_MB_2U(SCH_1):PAGE86_I24@PURE_QUANTA.SCONN288_ADR50017P130CC(CHIPS)':
 'DQ7_B': CDS_PINID='DQ7_B';
NODE_NAME     J6 254
 '@S9S_MB_2U_LIB.S9S_MB_2U(SCH_1):PAGE87_I46@PURE_QUANTA.SCONN288_ADR50017P087CC(CHIPS)':
 'DQ7_B': CDS_PINID='DQ7_B';
NET_NAME
'M_C_CPU0_SB_DQ<8>'
 '@S9S_MB_2U_LIB.S9S_MB_2U(SCH_1):M_C_CPU0_SB_DQ'<8>:
 C_SIGNAL='@s9s_mb_2u_lib.s9s_mb_2u(sch_1):m_c_cpu0_sb_dq(8)';
NODE_NAME     U2 AD32
 '@S9S_MB_2U_LIB.S9S_MB_2U(SCH_1):PAGE22_I169@PURE_QUANTA.SOCKET4677_AZIF0045P001C01CS(CHIPS)':
 'DDR2_SB_DQ8': CDS_PINID='DDR2_SB_DQ8';
NODE_NAME     J5 111
 '@S9S_MB_2U_LIB.S9S_MB_2U(SCH_1):PAGE86_I24@PURE_QUANTA.SCONN288_ADR50017P130CC(CHIPS)':
 'DQ8_B': CDS_PINID='DQ8_B';
NODE_NAME     J6 111
 '@S9S_MB_2U_LIB.S9S_MB_2U(SCH_1):PAGE87_I46@PURE_QUANTA.SCONN288_ADR50017P087CC(CHIPS)':
 'DQ8_B': CDS_PINID='DQ8_B';
NET_NAME
'M_C_CPU0_SB_DQ<9>'
 '@S9S_MB_2U_LIB.S9S_MB_2U(SCH_1):M_C_CPU0_SB_DQ'<9>:
 C_SIGNAL='@s9s_mb_2u_lib.s9s_mb_2u(sch_1):m_c_cpu0_sb_dq(9)';
NODE_NAME     U2 AC31
 '@S9S_MB_2U_LIB.S9S_MB_2U(SCH_1):PAGE22_I169@PURE_QUANTA.SOCKET4677_AZIF0045P001C01CS(CHIPS)':
 'DDR2_SB_DQ9': CDS_PINID='DDR2_SB_DQ9';
NODE_NAME     J5 113
 '@S9S_MB_2U_LIB.S9S_MB_2U(SCH_1):PAGE86_I24@PURE_QUANTA.SCONN288_ADR50017P130CC(CHIPS)':
 'DQ9_B': CDS_PINID='DQ9_B';
NODE_NAME     J6 113
 '@S9S_MB_2U_LIB.S9S_MB_2U(SCH_1):PAGE87_I46@PURE_QUANTA.SCONN288_ADR50017P087CC(CHIPS)':
 'DQ9_B': CDS_PINID='DQ9_B';
NET_NAME
'M_C_CPU0_SB_DQS_DN<0>'
 '@S9S_MB_2U_LIB.S9S_MB_2U(SCH_1):M_C_CPU0_SB_DQS_DN'<0>:
 C_SIGNAL='@s9s_mb_2u_lib.s9s_mb_2u(sch_1):m_c_cpu0_sb_dqs_dn(0)';
NODE_NAME     U2 AB36
 '@S9S_MB_2U_LIB.S9S_MB_2U(SCH_1):PAGE22_I169@PURE_QUANTA.SOCKET4677_AZIF0045P001C01CS(CHIPS)':
 'DDR2_SB_DQS_DN0': CDS_PINID='DDR2_SB_DQS_DN0';
NODE_NAME     J5 105
 '@S9S_MB_2U_LIB.S9S_MB_2U(SCH_1):PAGE86_I178@PURE_QUANTA.SCONN288_ADR50017P130CC(CHIPS)':
 'DQS0_B_C': CDS_PINID='DQS0_B_C';
NODE_NAME     J6 105
 '@S9S_MB_2U_LIB.S9S_MB_2U(SCH_1):PAGE87_I178@PURE_QUANTA.SCONN288_ADR50017P087CC(CHIPS)':
 'DQS0_B_C': CDS_PINID='DQS0_B_C';
NET_NAME
'M_C_CPU0_SB_DQS_DN<1>'
 '@S9S_MB_2U_LIB.S9S_MB_2U(SCH_1):M_C_CPU0_SB_DQS_DN'<1>:
 C_SIGNAL='@s9s_mb_2u_lib.s9s_mb_2u(sch_1):m_c_cpu0_sb_dqs_dn(1)';
NODE_NAME     U2 AB30
 '@S9S_MB_2U_LIB.S9S_MB_2U(SCH_1):PAGE22_I169@PURE_QUANTA.SOCKET4677_AZIF0045P001C01CS(CHIPS)':
 'DDR2_SB_DQS_DN1': CDS_PINID='DDR2_SB_DQS_DN1';
NODE_NAME     J5 116
 '@S9S_MB_2U_LIB.S9S_MB_2U(SCH_1):PAGE86_I178@PURE_QUANTA.SCONN288_ADR50017P130CC(CHIPS)':
 'DQS1_B_C': CDS_PINID='DQS1_B_C';
NODE_NAME     J6 116
 '@S9S_MB_2U_LIB.S9S_MB_2U(SCH_1):PAGE87_I178@PURE_QUANTA.SCONN288_ADR50017P087CC(CHIPS)':
 'DQS1_B_C': CDS_PINID='DQS1_B_C';
NET_NAME
'M_C_CPU0_SB_DQS_DN<2>'
 '@S9S_MB_2U_LIB.S9S_MB_2U(SCH_1):M_C_CPU0_SB_DQS_DN'<2>:
 C_SIGNAL='@s9s_mb_2u_lib.s9s_mb_2u(sch_1):m_c_cpu0_sb_dqs_dn(2)';
NODE_NAME     U2 R21
 '@S9S_MB_2U_LIB.S9S_MB_2U(SCH_1):PAGE22_I169@PURE_QUANTA.SOCKET4677_AZIF0045P001C01CS(CHIPS)':
 'DDR2_SB_DQS_DN2': CDS_PINID='DDR2_SB_DQS_DN2';
NODE_NAME     J5 127
 '@S9S_MB_2U_LIB.S9S_MB_2U(SCH_1):PAGE86_I178@PURE_QUANTA.SCONN288_ADR50017P130CC(CHIPS)':
 'DQS2_B_C': CDS_PINID='DQS2_B_C';
NODE_NAME     J6 127
 '@S9S_MB_2U_LIB.S9S_MB_2U(SCH_1):PAGE87_I178@PURE_QUANTA.SCONN288_ADR50017P087CC(CHIPS)':
 'DQS2_B_C': CDS_PINID='DQS2_B_C';
NET_NAME
'M_C_CPU0_SB_DQS_DN<3>'
 '@S9S_MB_2U_LIB.S9S_MB_2U(SCH_1):M_C_CPU0_SB_DQS_DN'<3>:
 C_SIGNAL='@s9s_mb_2u_lib.s9s_mb_2u(sch_1):m_c_cpu0_sb_dqs_dn(3)';
NODE_NAME     U2 AB18
 '@S9S_MB_2U_LIB.S9S_MB_2U(SCH_1):PAGE22_I169@PURE_QUANTA.SOCKET4677_AZIF0045P001C01CS(CHIPS)':
 'DDR2_SB_DQS_DN3': CDS_PINID='DDR2_SB_DQS_DN3';
NODE_NAME     J5 138
 '@S9S_MB_2U_LIB.S9S_MB_2U(SCH_1):PAGE86_I178@PURE_QUANTA.SCONN288_ADR50017P130CC(CHIPS)':
 'DQS3_B_C': CDS_PINID='DQS3_B_C';
NODE_NAME     J6 138
 '@S9S_MB_2U_LIB.S9S_MB_2U(SCH_1):PAGE87_I178@PURE_QUANTA.SCONN288_ADR50017P087CC(CHIPS)':
 'DQS3_B_C': CDS_PINID='DQS3_B_C';
NET_NAME
'M_C_CPU0_SB_DQS_DN<4>'
 '@S9S_MB_2U_LIB.S9S_MB_2U(SCH_1):M_C_CPU0_SB_DQS_DN'<4>:
 C_SIGNAL='@s9s_mb_2u_lib.s9s_mb_2u(sch_1):m_c_cpu0_sb_dqs_dn(4)';
NODE_NAME     U2 W33
 '@S9S_MB_2U_LIB.S9S_MB_2U(SCH_1):PAGE22_I169@PURE_QUANTA.SOCKET4677_AZIF0045P001C01CS(CHIPS)':
 'DDR2_SB_DQS_DN4': CDS_PINID='DDR2_SB_DQS_DN4';
NODE_NAME     J5 238
 '@S9S_MB_2U_LIB.S9S_MB_2U(SCH_1):PAGE86_I178@PURE_QUANTA.SCONN288_ADR50017P130CC(CHIPS)':
 'DQS4_B_C': CDS_PINID='DQS4_B_C';
NODE_NAME     J6 238
 '@S9S_MB_2U_LIB.S9S_MB_2U(SCH_1):PAGE87_I178@PURE_QUANTA.SCONN288_ADR50017P087CC(CHIPS)':
 'DQS4_B_C': CDS_PINID='DQS4_B_C';
NET_NAME
'M_C_CPU0_SB_DQS_DN<5>'
 '@S9S_MB_2U_LIB.S9S_MB_2U(SCH_1):M_C_CPU0_SB_DQS_DN'<5>:
 C_SIGNAL='@s9s_mb_2u_lib.s9s_mb_2u(sch_1):m_c_cpu0_sb_dqs_dn(5)';
NODE_NAME     U2 AF36
 '@S9S_MB_2U_LIB.S9S_MB_2U(SCH_1):PAGE22_I169@PURE_QUANTA.SOCKET4677_AZIF0045P001C01CS(CHIPS)':
 'DDR2_SB_DQS_DN5': CDS_PINID='DDR2_SB_DQS_DN5';
NODE_NAME     J5 249
 '@S9S_MB_2U_LIB.S9S_MB_2U(SCH_1):PAGE86_I178@PURE_QUANTA.SCONN288_ADR50017P130CC(CHIPS)':
 'DQS5_B_C||TDQS5_B_C': CDS_PINID='\dqs5_b_c||tdqs5_b_c\';
NODE_NAME     J6 249
 '@S9S_MB_2U_LIB.S9S_MB_2U(SCH_1):PAGE87_I178@PURE_QUANTA.SCONN288_ADR50017P087CC(CHIPS)':
 'DQS5_B_C||TDQS5_B_C': CDS_PINID='\dqs5_b_c||tdqs5_b_c\';
NET_NAME
'M_C_CPU0_SB_DQS_DN<6>'
 '@S9S_MB_2U_LIB.S9S_MB_2U(SCH_1):M_C_CPU0_SB_DQS_DN'<6>:
 C_SIGNAL='@s9s_mb_2u_lib.s9s_mb_2u(sch_1):m_c_cpu0_sb_dqs_dn(6)';
NODE_NAME     U2 AF30
 '@S9S_MB_2U_LIB.S9S_MB_2U(SCH_1):PAGE22_I169@PURE_QUANTA.SOCKET4677_AZIF0045P001C01CS(CHIPS)':
 'DDR2_SB_DQS_DN6': CDS_PINID='DDR2_SB_DQS_DN6';
NODE_NAME     J5 260
 '@S9S_MB_2U_LIB.S9S_MB_2U(SCH_1):PAGE86_I178@PURE_QUANTA.SCONN288_ADR50017P130CC(CHIPS)':
 'DQS6_B_C||TDQS6_B_C': CDS_PINID='\dqs6_b_c||tdqs6_b_c\';
NODE_NAME     J6 260
 '@S9S_MB_2U_LIB.S9S_MB_2U(SCH_1):PAGE87_I178@PURE_QUANTA.SCONN288_ADR50017P087CC(CHIPS)':
 'DQS6_B_C||TDQS6_B_C': CDS_PINID='\dqs6_b_c||tdqs6_b_c\';
NET_NAME
'M_C_CPU0_SB_DQS_DN<7>'
 '@S9S_MB_2U_LIB.S9S_MB_2U(SCH_1):M_C_CPU0_SB_DQS_DN'<7>:
 C_SIGNAL='@s9s_mb_2u_lib.s9s_mb_2u(sch_1):m_c_cpu0_sb_dqs_dn(7)';
NODE_NAME     U2 W21
 '@S9S_MB_2U_LIB.S9S_MB_2U(SCH_1):PAGE22_I169@PURE_QUANTA.SOCKET4677_AZIF0045P001C01CS(CHIPS)':
 'DDR2_SB_DQS_DN7': CDS_PINID='DDR2_SB_DQS_DN7';
NODE_NAME     J5 271
 '@S9S_MB_2U_LIB.S9S_MB_2U(SCH_1):PAGE86_I178@PURE_QUANTA.SCONN288_ADR50017P130CC(CHIPS)':
 'DQS7_B_C||TDQS7_B_C': CDS_PINID='\dqs7_b_c||tdqs7_b_c\';
NODE_NAME     J6 271
 '@S9S_MB_2U_LIB.S9S_MB_2U(SCH_1):PAGE87_I178@PURE_QUANTA.SCONN288_ADR50017P087CC(CHIPS)':
 'DQS7_B_C||TDQS7_B_C': CDS_PINID='\dqs7_b_c||tdqs7_b_c\';
NET_NAME
'M_C_CPU0_SB_DQS_DN<8>'
 '@S9S_MB_2U_LIB.S9S_MB_2U(SCH_1):M_C_CPU0_SB_DQS_DN'<8>:
 C_SIGNAL='@s9s_mb_2u_lib.s9s_mb_2u(sch_1):m_c_cpu0_sb_dqs_dn(8)';
NODE_NAME     U2 AF18
 '@S9S_MB_2U_LIB.S9S_MB_2U(SCH_1):PAGE22_I169@PURE_QUANTA.SOCKET4677_AZIF0045P001C01CS(CHIPS)':
 'DDR2_SB_DQS_DN8': CDS_PINID='DDR2_SB_DQS_DN8';
NODE_NAME     J5 282
 '@S9S_MB_2U_LIB.S9S_MB_2U(SCH_1):PAGE86_I178@PURE_QUANTA.SCONN288_ADR50017P130CC(CHIPS)':
 'DQS8_B_C||TDQS8_B_C': CDS_PINID='\dqs8_b_c||tdqs8_b_c\';
NODE_NAME     J6 282
 '@S9S_MB_2U_LIB.S9S_MB_2U(SCH_1):PAGE87_I178@PURE_QUANTA.SCONN288_ADR50017P087CC(CHIPS)':
 'DQS8_B_C||TDQS8_B_C': CDS_PINID='\dqs8_b_c||tdqs8_b_c\';
NET_NAME
'M_C_CPU0_SB_DQS_DN<9>'
 '@S9S_MB_2U_LIB.S9S_MB_2U(SCH_1):M_C_CPU0_SB_DQS_DN'<9>:
 C_SIGNAL='@s9s_mb_2u_lib.s9s_mb_2u(sch_1):m_c_cpu0_sb_dqs_dn(9)';
NODE_NAME     U2 R33
 '@S9S_MB_2U_LIB.S9S_MB_2U(SCH_1):PAGE22_I169@PURE_QUANTA.SOCKET4677_AZIF0045P001C01CS(CHIPS)':
 'DDR2_SB_DQS_DN9': CDS_PINID='DDR2_SB_DQS_DN9';
NODE_NAME     J5 94
 '@S9S_MB_2U_LIB.S9S_MB_2U(SCH_1):PAGE86_I178@PURE_QUANTA.SCONN288_ADR50017P130CC(CHIPS)':
 'DQS9_B_C||TDQS9_B_C': CDS_PINID='\dqs9_b_c||tdqs9_b_c\';
NODE_NAME     J6 94
 '@S9S_MB_2U_LIB.S9S_MB_2U(SCH_1):PAGE87_I178@PURE_QUANTA.SCONN288_ADR50017P087CC(CHIPS)':
 'DQS9_B_C||TDQS9_B_C': CDS_PINID='\dqs9_b_c||tdqs9_b_c\';
NET_NAME
'M_C_CPU0_SB_DQS_DP<0>'
 '@S9S_MB_2U_LIB.S9S_MB_2U(SCH_1):M_C_CPU0_SB_DQS_DP'<0>:
 C_SIGNAL='@s9s_mb_2u_lib.s9s_mb_2u(sch_1):m_c_cpu0_sb_dqs_dp(0)';
NODE_NAME     U2 AD36
 '@S9S_MB_2U_LIB.S9S_MB_2U(SCH_1):PAGE22_I169@PURE_QUANTA.SOCKET4677_AZIF0045P001C01CS(CHIPS)':
 'DDR2_SB_DQS_DP0': CDS_PINID='DDR2_SB_DQS_DP0';
NODE_NAME     J5 104
 '@S9S_MB_2U_LIB.S9S_MB_2U(SCH_1):PAGE86_I178@PURE_QUANTA.SCONN288_ADR50017P130CC(CHIPS)':
 'DQS0_B_T': CDS_PINID='DQS0_B_T';
NODE_NAME     J6 104
 '@S9S_MB_2U_LIB.S9S_MB_2U(SCH_1):PAGE87_I178@PURE_QUANTA.SCONN288_ADR50017P087CC(CHIPS)':
 'DQS0_B_T': CDS_PINID='DQS0_B_T';
NET_NAME
'M_C_CPU0_SB_DQS_DP<1>'
 '@S9S_MB_2U_LIB.S9S_MB_2U(SCH_1):M_C_CPU0_SB_DQS_DP'<1>:
 C_SIGNAL='@s9s_mb_2u_lib.s9s_mb_2u(sch_1):m_c_cpu0_sb_dqs_dp(1)';
NODE_NAME     U2 AD30
 '@S9S_MB_2U_LIB.S9S_MB_2U(SCH_1):PAGE22_I169@PURE_QUANTA.SOCKET4677_AZIF0045P001C01CS(CHIPS)':
 'DDR2_SB_DQS_DP1': CDS_PINID='DDR2_SB_DQS_DP1';
NODE_NAME     J5 115
 '@S9S_MB_2U_LIB.S9S_MB_2U(SCH_1):PAGE86_I178@PURE_QUANTA.SCONN288_ADR50017P130CC(CHIPS)':
 'DQS1_B_T': CDS_PINID='DQS1_B_T';
NODE_NAME     J6 115
 '@S9S_MB_2U_LIB.S9S_MB_2U(SCH_1):PAGE87_I178@PURE_QUANTA.SCONN288_ADR50017P087CC(CHIPS)':
 'DQS1_B_T': CDS_PINID='DQS1_B_T';
NET_NAME
'M_C_CPU0_SB_DQS_DP<2>'
 '@S9S_MB_2U_LIB.S9S_MB_2U(SCH_1):M_C_CPU0_SB_DQS_DP'<2>:
 C_SIGNAL='@s9s_mb_2u_lib.s9s_mb_2u(sch_1):m_c_cpu0_sb_dqs_dp(2)';
NODE_NAME     U2 U21
 '@S9S_MB_2U_LIB.S9S_MB_2U(SCH_1):PAGE22_I169@PURE_QUANTA.SOCKET4677_AZIF0045P001C01CS(CHIPS)':
 'DDR2_SB_DQS_DP2': CDS_PINID='DDR2_SB_DQS_DP2';
NODE_NAME     J5 126
 '@S9S_MB_2U_LIB.S9S_MB_2U(SCH_1):PAGE86_I178@PURE_QUANTA.SCONN288_ADR50017P130CC(CHIPS)':
 'DQS2_B_T': CDS_PINID='DQS2_B_T';
NODE_NAME     J6 126
 '@S9S_MB_2U_LIB.S9S_MB_2U(SCH_1):PAGE87_I178@PURE_QUANTA.SCONN288_ADR50017P087CC(CHIPS)':
 'DQS2_B_T': CDS_PINID='DQS2_B_T';
NET_NAME
'M_C_CPU0_SB_DQS_DP<3>'
 '@S9S_MB_2U_LIB.S9S_MB_2U(SCH_1):M_C_CPU0_SB_DQS_DP'<3>:
 C_SIGNAL='@s9s_mb_2u_lib.s9s_mb_2u(sch_1):m_c_cpu0_sb_dqs_dp(3)';
NODE_NAME     U2 AD18
 '@S9S_MB_2U_LIB.S9S_MB_2U(SCH_1):PAGE22_I169@PURE_QUANTA.SOCKET4677_AZIF0045P001C01CS(CHIPS)':
 'DDR2_SB_DQS_DP3': CDS_PINID='DDR2_SB_DQS_DP3';
NODE_NAME     J5 137
 '@S9S_MB_2U_LIB.S9S_MB_2U(SCH_1):PAGE86_I178@PURE_QUANTA.SCONN288_ADR50017P130CC(CHIPS)':
 'DQS3_B_T': CDS_PINID='DQS3_B_T';
NODE_NAME     J6 137
 '@S9S_MB_2U_LIB.S9S_MB_2U(SCH_1):PAGE87_I178@PURE_QUANTA.SCONN288_ADR50017P087CC(CHIPS)':
 'DQS3_B_T': CDS_PINID='DQS3_B_T';
NET_NAME
'M_C_CPU0_SB_DQS_DP<4>'
 '@S9S_MB_2U_LIB.S9S_MB_2U(SCH_1):M_C_CPU0_SB_DQS_DP'<4>:
 C_SIGNAL='@s9s_mb_2u_lib.s9s_mb_2u(sch_1):m_c_cpu0_sb_dqs_dp(4)';
NODE_NAME     U2 AA33
 '@S9S_MB_2U_LIB.S9S_MB_2U(SCH_1):PAGE22_I169@PURE_QUANTA.SOCKET4677_AZIF0045P001C01CS(CHIPS)':
 'DDR2_SB_DQS_DP4': CDS_PINID='DDR2_SB_DQS_DP4';
NODE_NAME     J5 239
 '@S9S_MB_2U_LIB.S9S_MB_2U(SCH_1):PAGE86_I178@PURE_QUANTA.SCONN288_ADR50017P130CC(CHIPS)':
 'DQS4_B_T': CDS_PINID='DQS4_B_T';
NODE_NAME     J6 239
 '@S9S_MB_2U_LIB.S9S_MB_2U(SCH_1):PAGE87_I178@PURE_QUANTA.SCONN288_ADR50017P087CC(CHIPS)':
 'DQS4_B_T': CDS_PINID='DQS4_B_T';
NET_NAME
'M_C_CPU0_SB_DQS_DP<5>'
 '@S9S_MB_2U_LIB.S9S_MB_2U(SCH_1):M_C_CPU0_SB_DQS_DP'<5>:
 C_SIGNAL='@s9s_mb_2u_lib.s9s_mb_2u(sch_1):m_c_cpu0_sb_dqs_dp(5)';
NODE_NAME     U2 AH36
 '@S9S_MB_2U_LIB.S9S_MB_2U(SCH_1):PAGE22_I169@PURE_QUANTA.SOCKET4677_AZIF0045P001C01CS(CHIPS)':
 'DDR2_SB_DQS_DP5': CDS_PINID='DDR2_SB_DQS_DP5';
NODE_NAME     J5 250
 '@S9S_MB_2U_LIB.S9S_MB_2U(SCH_1):PAGE86_I178@PURE_QUANTA.SCONN288_ADR50017P130CC(CHIPS)':
 'DQS5_B_T||TDQS5_B_T': CDS_PINID='\dqs5_b_t||tdqs5_b_t\';
NODE_NAME     J6 250
 '@S9S_MB_2U_LIB.S9S_MB_2U(SCH_1):PAGE87_I178@PURE_QUANTA.SCONN288_ADR50017P087CC(CHIPS)':
 'DQS5_B_T||TDQS5_B_T': CDS_PINID='\dqs5_b_t||tdqs5_b_t\';
NET_NAME
'M_C_CPU0_SB_DQS_DP<6>'
 '@S9S_MB_2U_LIB.S9S_MB_2U(SCH_1):M_C_CPU0_SB_DQS_DP'<6>:
 C_SIGNAL='@s9s_mb_2u_lib.s9s_mb_2u(sch_1):m_c_cpu0_sb_dqs_dp(6)';
NODE_NAME     U2 AH30
 '@S9S_MB_2U_LIB.S9S_MB_2U(SCH_1):PAGE22_I169@PURE_QUANTA.SOCKET4677_AZIF0045P001C01CS(CHIPS)':
 'DDR2_SB_DQS_DP6': CDS_PINID='DDR2_SB_DQS_DP6';
NODE_NAME     J5 261
 '@S9S_MB_2U_LIB.S9S_MB_2U(SCH_1):PAGE86_I178@PURE_QUANTA.SCONN288_ADR50017P130CC(CHIPS)':
 'DQS6_B_T||TDQS6_B_T': CDS_PINID='\dqs6_b_t||tdqs6_b_t\';
NODE_NAME     J6 261
 '@S9S_MB_2U_LIB.S9S_MB_2U(SCH_1):PAGE87_I178@PURE_QUANTA.SCONN288_ADR50017P087CC(CHIPS)':
 'DQS6_B_T||TDQS6_B_T': CDS_PINID='\dqs6_b_t||tdqs6_b_t\';
NET_NAME
'M_C_CPU0_SB_DQS_DP<7>'
 '@S9S_MB_2U_LIB.S9S_MB_2U(SCH_1):M_C_CPU0_SB_DQS_DP'<7>:
 C_SIGNAL='@s9s_mb_2u_lib.s9s_mb_2u(sch_1):m_c_cpu0_sb_dqs_dp(7)';
NODE_NAME     U2 AA21
 '@S9S_MB_2U_LIB.S9S_MB_2U(SCH_1):PAGE22_I169@PURE_QUANTA.SOCKET4677_AZIF0045P001C01CS(CHIPS)':
 'DDR2_SB_DQS_DP7': CDS_PINID='DDR2_SB_DQS_DP7';
NODE_NAME     J5 272
 '@S9S_MB_2U_LIB.S9S_MB_2U(SCH_1):PAGE86_I178@PURE_QUANTA.SCONN288_ADR50017P130CC(CHIPS)':
 'DQS7_B_T||TDQS7_B_T': CDS_PINID='\dqs7_b_t||tdqs7_b_t\';
NODE_NAME     J6 272
 '@S9S_MB_2U_LIB.S9S_MB_2U(SCH_1):PAGE87_I178@PURE_QUANTA.SCONN288_ADR50017P087CC(CHIPS)':
 'DQS7_B_T||TDQS7_B_T': CDS_PINID='\dqs7_b_t||tdqs7_b_t\';
NET_NAME
'M_C_CPU0_SB_DQS_DP<8>'
 '@S9S_MB_2U_LIB.S9S_MB_2U(SCH_1):M_C_CPU0_SB_DQS_DP'<8>:
 C_SIGNAL='@s9s_mb_2u_lib.s9s_mb_2u(sch_1):m_c_cpu0_sb_dqs_dp(8)';
NODE_NAME     U2 AH18
 '@S9S_MB_2U_LIB.S9S_MB_2U(SCH_1):PAGE22_I169@PURE_QUANTA.SOCKET4677_AZIF0045P001C01CS(CHIPS)':
 'DDR2_SB_DQS_DP8': CDS_PINID='DDR2_SB_DQS_DP8';
NODE_NAME     J5 283
 '@S9S_MB_2U_LIB.S9S_MB_2U(SCH_1):PAGE86_I178@PURE_QUANTA.SCONN288_ADR50017P130CC(CHIPS)':
 'DQS8_B_T||TDQS8_B_T': CDS_PINID='\dqs8_b_t||tdqs8_b_t\';
NODE_NAME     J6 283
 '@S9S_MB_2U_LIB.S9S_MB_2U(SCH_1):PAGE87_I178@PURE_QUANTA.SCONN288_ADR50017P087CC(CHIPS)':
 'DQS8_B_T||TDQS8_B_T': CDS_PINID='\dqs8_b_t||tdqs8_b_t\';
NET_NAME
'M_C_CPU0_SB_DQS_DP<9>'
 '@S9S_MB_2U_LIB.S9S_MB_2U(SCH_1):M_C_CPU0_SB_DQS_DP'<9>:
 C_SIGNAL='@s9s_mb_2u_lib.s9s_mb_2u(sch_1):m_c_cpu0_sb_dqs_dp(9)';
NODE_NAME     U2 U33
 '@S9S_MB_2U_LIB.S9S_MB_2U(SCH_1):PAGE22_I169@PURE_QUANTA.SOCKET4677_AZIF0045P001C01CS(CHIPS)':
 'DDR2_SB_DQS_DP9': CDS_PINID='DDR2_SB_DQS_DP9';
NODE_NAME     J5 93
 '@S9S_MB_2U_LIB.S9S_MB_2U(SCH_1):PAGE86_I178@PURE_QUANTA.SCONN288_ADR50017P130CC(CHIPS)':
 'DQS9_B_T||TDQS9_B_T||DBI4_B_N': CDS_PINID='\dqs9_b_t||tdqs9_b_t||dbi4_b_n\';
NODE_NAME     J6 93
 '@S9S_MB_2U_LIB.S9S_MB_2U(SCH_1):PAGE87_I178@PURE_QUANTA.SCONN288_ADR50017P087CC(CHIPS)':
 'DQS9_B_T||TDQS9_B_T||DBI4_B_N': CDS_PINID='\dqs9_b_t||tdqs9_b_t||dbi4_b_n\';
NET_NAME
'M_C_CPU0_SB_PAR'
 '@S9S_MB_2U_LIB.S9S_MB_2U(SCH_1):M_C_CPU0_SB_PAR':
 C_SIGNAL='@s9s_mb_2u_lib.s9s_mb_2u(sch_1):m_c_cpu0_sb_par';
NODE_NAME     U2 AA39
 '@S9S_MB_2U_LIB.S9S_MB_2U(SCH_1):PAGE22_I169@PURE_QUANTA.SOCKET4677_AZIF0045P001C01CS(CHIPS)':
 'DDR2_SB_PAR': CDS_PINID='DDR2_SB_PAR';
NODE_NAME     J5 227
 '@S9S_MB_2U_LIB.S9S_MB_2U(SCH_1):PAGE86_I24@PURE_QUANTA.SCONN288_ADR50017P130CC(CHIPS)':
 'PAR_B': CDS_PINID='PAR_B';
NODE_NAME     J6 227
 '@S9S_MB_2U_LIB.S9S_MB_2U(SCH_1):PAGE87_I46@PURE_QUANTA.SCONN288_ADR50017P087CC(CHIPS)':
 'PAR_B': CDS_PINID='PAR_B';
NET_NAME
'M_C_CPU0_SB_RSP<0>'
 '@S9S_MB_2U_LIB.S9S_MB_2U(SCH_1):M_C_CPU0_SB_RSP'<0>:
 C_SIGNAL='@s9s_mb_2u_lib.s9s_mb_2u(sch_1):m_c_cpu0_sb_rsp(0)';
NODE_NAME     U2 AG48
 '@S9S_MB_2U_LIB.S9S_MB_2U(SCH_1):PAGE22_I169@PURE_QUANTA.SOCKET4677_AZIF0045P001C01CS(CHIPS)':
 'DDR2_B_RSP0': CDS_PINID='DDR2_B_RSP0';
NODE_NAME     J5 87
 '@S9S_MB_2U_LIB.S9S_MB_2U(SCH_1):PAGE86_I24@PURE_QUANTA.SCONN288_ADR50017P130CC(CHIPS)':
 'LBS||RSP_B_N': CDS_PINID='\lbs||rsp_b_n\';
NET_NAME
'M_C_CPU0_SB_RSP<1>'
 '@S9S_MB_2U_LIB.S9S_MB_2U(SCH_1):M_C_CPU0_SB_RSP'<1>:
 C_SIGNAL='@s9s_mb_2u_lib.s9s_mb_2u(sch_1):m_c_cpu0_sb_rsp(1)';
NODE_NAME     U2 AF47
 '@S9S_MB_2U_LIB.S9S_MB_2U(SCH_1):PAGE22_I169@PURE_QUANTA.SOCKET4677_AZIF0045P001C01CS(CHIPS)':
 'DDR2_B_RSP1': CDS_PINID='DDR2_B_RSP1';
NODE_NAME     J6 87
 '@S9S_MB_2U_LIB.S9S_MB_2U(SCH_1):PAGE87_I46@PURE_QUANTA.SCONN288_ADR50017P087CC(CHIPS)':
 'LBS||RSP_B_N': CDS_PINID='\lbs||rsp_b_n\';
NET_NAME
'M_C_CPU1_ALERT_N'
 '@S9S_MB_2U_LIB.S9S_MB_2U(SCH_1):M_C_CPU1_ALERT_N':
 C_SIGNAL='@s9s_mb_2u_lib.s9s_mb_2u(sch_1):m_c_cpu1_alert_n';
NODE_NAME     U1 AT47
 '@S9S_MB_2U_LIB.S9S_MB_2U(SCH_1):PAGE53_I91@PURE_QUANTA.SOCKET4677_AZIF0045P001C01CS(CHIPS)':
 'DDR2_ALERT_N': CDS_PINID='DDR2_ALERT_N';
NODE_NAME     J21 62
 '@S9S_MB_2U_LIB.S9S_MB_2U(SCH_1):PAGE102_I13@PURE_QUANTA.SCONN288_ADR50017P130CC(CHIPS)':
 'ALERT_N': CDS_PINID='ALERT_N';
NODE_NAME     J22 62
 '@S9S_MB_2U_LIB.S9S_MB_2U(SCH_1):PAGE103_I51@PURE_QUANTA.SCONN288_ADR50017P087CC(CHIPS)':
 'ALERT_N': CDS_PINID='ALERT_N';
NET_NAME
'M_C_CPU1_CLK_DN<0>'
 '@S9S_MB_2U_LIB.S9S_MB_2U(SCH_1):M_C_CPU1_CLK_DN'<0>:
 C_SIGNAL='@s9s_mb_2u_lib.s9s_mb_2u(sch_1):m_c_cpu1_clk_dn(0)';
NODE_NAME     U1 AB49
 '@S9S_MB_2U_LIB.S9S_MB_2U(SCH_1):PAGE53_I91@PURE_QUANTA.SOCKET4677_AZIF0045P001C01CS(CHIPS)':
 'DDR2_CLK_DN0': CDS_PINID='DDR2_CLK_DN0';
NODE_NAME     J21 218
 '@S9S_MB_2U_LIB.S9S_MB_2U(SCH_1):PAGE102_I13@PURE_QUANTA.SCONN288_ADR50017P130CC(CHIPS)':
 'CK_C': CDS_PINID='CK_C';
NET_NAME
'M_C_CPU1_CLK_DN<1>'
 '@S9S_MB_2U_LIB.S9S_MB_2U(SCH_1):M_C_CPU1_CLK_DN'<1>:
 C_SIGNAL='@s9s_mb_2u_lib.s9s_mb_2u(sch_1):m_c_cpu1_clk_dn(1)';
NODE_NAME     U1 AF49
 '@S9S_MB_2U_LIB.S9S_MB_2U(SCH_1):PAGE53_I91@PURE_QUANTA.SOCKET4677_AZIF0045P001C01CS(CHIPS)':
 'DDR2_CLK_DN1': CDS_PINID='DDR2_CLK_DN1';
NODE_NAME     J22 218
 '@S9S_MB_2U_LIB.S9S_MB_2U(SCH_1):PAGE103_I51@PURE_QUANTA.SCONN288_ADR50017P087CC(CHIPS)':
 'CK_C': CDS_PINID='CK_C';
NET_NAME
'M_C_CPU1_CLK_DP<0>'
 '@S9S_MB_2U_LIB.S9S_MB_2U(SCH_1):M_C_CPU1_CLK_DP'<0>:
 C_SIGNAL='@s9s_mb_2u_lib.s9s_mb_2u(sch_1):m_c_cpu1_clk_dp(0)';
NODE_NAME     U1 AD49
 '@S9S_MB_2U_LIB.S9S_MB_2U(SCH_1):PAGE53_I91@PURE_QUANTA.SOCKET4677_AZIF0045P001C01CS(CHIPS)':
 'DDR2_CLK_DP0': CDS_PINID='DDR2_CLK_DP0';
NODE_NAME     J21 217
 '@S9S_MB_2U_LIB.S9S_MB_2U(SCH_1):PAGE102_I13@PURE_QUANTA.SCONN288_ADR50017P130CC(CHIPS)':
 'CK_T': CDS_PINID='CK_T';
NET_NAME
'M_C_CPU1_CLK_DP<1>'
 '@S9S_MB_2U_LIB.S9S_MB_2U(SCH_1):M_C_CPU1_CLK_DP'<1>:
 C_SIGNAL='@s9s_mb_2u_lib.s9s_mb_2u(sch_1):m_c_cpu1_clk_dp(1)';
NODE_NAME     U1 AH49
 '@S9S_MB_2U_LIB.S9S_MB_2U(SCH_1):PAGE53_I91@PURE_QUANTA.SOCKET4677_AZIF0045P001C01CS(CHIPS)':
 'DDR2_CLK_DP1': CDS_PINID='DDR2_CLK_DP1';
NODE_NAME     J22 217
 '@S9S_MB_2U_LIB.S9S_MB_2U(SCH_1):PAGE103_I51@PURE_QUANTA.SCONN288_ADR50017P087CC(CHIPS)':
 'CK_T': CDS_PINID='CK_T';
NET_NAME
'M_C_CPU1_SA_CA<0>'
 '@S9S_MB_2U_LIB.S9S_MB_2U(SCH_1):M_C_CPU1_SA_CA'<0>:
 C_SIGNAL='@s9s_mb_2u_lib.s9s_mb_2u(sch_1):m_c_cpu1_sa_ca(0)';
NODE_NAME     U1 R52
 '@S9S_MB_2U_LIB.S9S_MB_2U(SCH_1):PAGE53_I91@PURE_QUANTA.SOCKET4677_AZIF0045P001C01CS(CHIPS)':
 'DDR2_SA_CA0': CDS_PINID='DDR2_SA_CA0';
NODE_NAME     J21 66
 '@S9S_MB_2U_LIB.S9S_MB_2U(SCH_1):PAGE102_I13@PURE_QUANTA.SCONN288_ADR50017P130CC(CHIPS)':
 'CA0_A': CDS_PINID='CA0_A';
NODE_NAME     J22 66
 '@S9S_MB_2U_LIB.S9S_MB_2U(SCH_1):PAGE103_I51@PURE_QUANTA.SCONN288_ADR50017P087CC(CHIPS)':
 'CA0_A': CDS_PINID='CA0_A';
NET_NAME
'M_C_CPU1_SA_CA<1>'
 '@S9S_MB_2U_LIB.S9S_MB_2U(SCH_1):M_C_CPU1_SA_CA'<1>:
 C_SIGNAL='@s9s_mb_2u_lib.s9s_mb_2u(sch_1):m_c_cpu1_sa_ca(1)';
NODE_NAME     U1 AA52
 '@S9S_MB_2U_LIB.S9S_MB_2U(SCH_1):PAGE53_I91@PURE_QUANTA.SOCKET4677_AZIF0045P001C01CS(CHIPS)':
 'DDR2_SA_CA1': CDS_PINID='DDR2_SA_CA1';
NODE_NAME     J21 211
 '@S9S_MB_2U_LIB.S9S_MB_2U(SCH_1):PAGE102_I13@PURE_QUANTA.SCONN288_ADR50017P130CC(CHIPS)':
 'CA1_A': CDS_PINID='CA1_A';
NODE_NAME     J22 211
 '@S9S_MB_2U_LIB.S9S_MB_2U(SCH_1):PAGE103_I51@PURE_QUANTA.SCONN288_ADR50017P087CC(CHIPS)':
 'CA1_A': CDS_PINID='CA1_A';
NET_NAME
'M_C_CPU1_SA_CA<2>'
 '@S9S_MB_2U_LIB.S9S_MB_2U(SCH_1):M_C_CPU1_SA_CA'<2>:
 C_SIGNAL='@s9s_mb_2u_lib.s9s_mb_2u(sch_1):m_c_cpu1_sa_ca(2)';
NODE_NAME     U1 T51
 '@S9S_MB_2U_LIB.S9S_MB_2U(SCH_1):PAGE53_I91@PURE_QUANTA.SOCKET4677_AZIF0045P001C01CS(CHIPS)':
 'DDR2_SA_CA2': CDS_PINID='DDR2_SA_CA2';
NODE_NAME     J21 68
 '@S9S_MB_2U_LIB.S9S_MB_2U(SCH_1):PAGE102_I13@PURE_QUANTA.SCONN288_ADR50017P130CC(CHIPS)':
 'CA2_A': CDS_PINID='CA2_A';
NODE_NAME     J22 68
 '@S9S_MB_2U_LIB.S9S_MB_2U(SCH_1):PAGE103_I51@PURE_QUANTA.SCONN288_ADR50017P087CC(CHIPS)':
 'CA2_A': CDS_PINID='CA2_A';
NET_NAME
'M_C_CPU1_SA_CA<3>'
 '@S9S_MB_2U_LIB.S9S_MB_2U(SCH_1):M_C_CPU1_SA_CA'<3>:
 C_SIGNAL='@s9s_mb_2u_lib.s9s_mb_2u(sch_1):m_c_cpu1_sa_ca(3)';
NODE_NAME     U1 Y51
 '@S9S_MB_2U_LIB.S9S_MB_2U(SCH_1):PAGE53_I91@PURE_QUANTA.SOCKET4677_AZIF0045P001C01CS(CHIPS)':
 'DDR2_SA_CA3': CDS_PINID='DDR2_SA_CA3';
NODE_NAME     J21 213
 '@S9S_MB_2U_LIB.S9S_MB_2U(SCH_1):PAGE102_I13@PURE_QUANTA.SCONN288_ADR50017P130CC(CHIPS)':
 'CA3_A': CDS_PINID='CA3_A';
NODE_NAME     J22 213
 '@S9S_MB_2U_LIB.S9S_MB_2U(SCH_1):PAGE103_I51@PURE_QUANTA.SCONN288_ADR50017P087CC(CHIPS)':
 'CA3_A': CDS_PINID='CA3_A';
NET_NAME
'M_C_CPU1_SA_CA<4>'
 '@S9S_MB_2U_LIB.S9S_MB_2U(SCH_1):M_C_CPU1_SA_CA'<4>:
 C_SIGNAL='@s9s_mb_2u_lib.s9s_mb_2u(sch_1):m_c_cpu1_sa_ca(4)';
NODE_NAME     U1 U50
 '@S9S_MB_2U_LIB.S9S_MB_2U(SCH_1):PAGE53_I91@PURE_QUANTA.SOCKET4677_AZIF0045P001C01CS(CHIPS)':
 'DDR2_SA_CA4': CDS_PINID='DDR2_SA_CA4';
NODE_NAME     J21 70
 '@S9S_MB_2U_LIB.S9S_MB_2U(SCH_1):PAGE102_I13@PURE_QUANTA.SCONN288_ADR50017P130CC(CHIPS)':
 'CA4_A': CDS_PINID='CA4_A';
NODE_NAME     J22 70
 '@S9S_MB_2U_LIB.S9S_MB_2U(SCH_1):PAGE103_I51@PURE_QUANTA.SCONN288_ADR50017P087CC(CHIPS)':
 'CA4_A': CDS_PINID='CA4_A';
NET_NAME
'M_C_CPU1_SA_CA<5>'
 '@S9S_MB_2U_LIB.S9S_MB_2U(SCH_1):M_C_CPU1_SA_CA'<5>:
 C_SIGNAL='@s9s_mb_2u_lib.s9s_mb_2u(sch_1):m_c_cpu1_sa_ca(5)';
NODE_NAME     U1 W50
 '@S9S_MB_2U_LIB.S9S_MB_2U(SCH_1):PAGE53_I91@PURE_QUANTA.SOCKET4677_AZIF0045P001C01CS(CHIPS)':
 'DDR2_SA_CA5': CDS_PINID='DDR2_SA_CA5';
NODE_NAME     J21 215
 '@S9S_MB_2U_LIB.S9S_MB_2U(SCH_1):PAGE102_I13@PURE_QUANTA.SCONN288_ADR50017P130CC(CHIPS)':
 'CA5_A': CDS_PINID='CA5_A';
NODE_NAME     J22 215
 '@S9S_MB_2U_LIB.S9S_MB_2U(SCH_1):PAGE103_I51@PURE_QUANTA.SCONN288_ADR50017P087CC(CHIPS)':
 'CA5_A': CDS_PINID='CA5_A';
NET_NAME
'M_C_CPU1_SA_CA<6>'
 '@S9S_MB_2U_LIB.S9S_MB_2U(SCH_1):M_C_CPU1_SA_CA'<6>:
 C_SIGNAL='@s9s_mb_2u_lib.s9s_mb_2u(sch_1):m_c_cpu1_sa_ca(6)';
NODE_NAME     U1 U48
 '@S9S_MB_2U_LIB.S9S_MB_2U(SCH_1):PAGE53_I91@PURE_QUANTA.SOCKET4677_AZIF0045P001C01CS(CHIPS)':
 'DDR2_SA_CA6': CDS_PINID='DDR2_SA_CA6';
NODE_NAME     J21 72
 '@S9S_MB_2U_LIB.S9S_MB_2U(SCH_1):PAGE102_I13@PURE_QUANTA.SCONN288_ADR50017P130CC(CHIPS)':
 'CA6_A': CDS_PINID='CA6_A';
NODE_NAME     J22 72
 '@S9S_MB_2U_LIB.S9S_MB_2U(SCH_1):PAGE103_I51@PURE_QUANTA.SCONN288_ADR50017P087CC(CHIPS)':
 'CA6_A': CDS_PINID='CA6_A';
NET_NAME
'M_C_CPU1_SA_CB<0>'
 '@S9S_MB_2U_LIB.S9S_MB_2U(SCH_1):M_C_CPU1_SA_CB'<0>:
 C_SIGNAL='@s9s_mb_2u_lib.s9s_mb_2u(sch_1):m_c_cpu1_sa_cb(0)';
NODE_NAME     U1 AD57
 '@S9S_MB_2U_LIB.S9S_MB_2U(SCH_1):PAGE53_I91@PURE_QUANTA.SOCKET4677_AZIF0045P001C01CS(CHIPS)':
 'DDR2_SA_ECC0': CDS_PINID='DDR2_SA_ECC0';
NODE_NAME     J21 51
 '@S9S_MB_2U_LIB.S9S_MB_2U(SCH_1):PAGE102_I13@PURE_QUANTA.SCONN288_ADR50017P130CC(CHIPS)':
 'CB0_A': CDS_PINID='CB0_A';
NODE_NAME     J22 51
 '@S9S_MB_2U_LIB.S9S_MB_2U(SCH_1):PAGE103_I51@PURE_QUANTA.SCONN288_ADR50017P087CC(CHIPS)':
 'CB0_A': CDS_PINID='CB0_A';
NET_NAME
'M_C_CPU1_SA_CB<1>'
 '@S9S_MB_2U_LIB.S9S_MB_2U(SCH_1):M_C_CPU1_SA_CB'<1>:
 C_SIGNAL='@s9s_mb_2u_lib.s9s_mb_2u(sch_1):m_c_cpu1_sa_cb(1)';
NODE_NAME     U1 AC56
 '@S9S_MB_2U_LIB.S9S_MB_2U(SCH_1):PAGE53_I91@PURE_QUANTA.SOCKET4677_AZIF0045P001C01CS(CHIPS)':
 'DDR2_SA_ECC1': CDS_PINID='DDR2_SA_ECC1';
NODE_NAME     J21 53
 '@S9S_MB_2U_LIB.S9S_MB_2U(SCH_1):PAGE102_I13@PURE_QUANTA.SCONN288_ADR50017P130CC(CHIPS)':
 'CB1_A': CDS_PINID='CB1_A';
NODE_NAME     J22 53
 '@S9S_MB_2U_LIB.S9S_MB_2U(SCH_1):PAGE103_I51@PURE_QUANTA.SCONN288_ADR50017P087CC(CHIPS)':
 'CB1_A': CDS_PINID='CB1_A';
NET_NAME
'M_C_CPU1_SA_CB<2>'
 '@S9S_MB_2U_LIB.S9S_MB_2U(SCH_1):M_C_CPU1_SA_CB'<2>:
 C_SIGNAL='@s9s_mb_2u_lib.s9s_mb_2u(sch_1):m_c_cpu1_sa_cb(2)';
NODE_NAME     U1 AF57
 '@S9S_MB_2U_LIB.S9S_MB_2U(SCH_1):PAGE53_I91@PURE_QUANTA.SOCKET4677_AZIF0045P001C01CS(CHIPS)':
 'DDR2_SA_ECC2': CDS_PINID='DDR2_SA_ECC2';
NODE_NAME     J21 196
 '@S9S_MB_2U_LIB.S9S_MB_2U(SCH_1):PAGE102_I13@PURE_QUANTA.SCONN288_ADR50017P130CC(CHIPS)':
 'CB2_A': CDS_PINID='CB2_A';
NODE_NAME     J22 196
 '@S9S_MB_2U_LIB.S9S_MB_2U(SCH_1):PAGE103_I51@PURE_QUANTA.SCONN288_ADR50017P087CC(CHIPS)':
 'CB2_A': CDS_PINID='CB2_A';
NET_NAME
'M_C_CPU1_SA_CB<3>'
 '@S9S_MB_2U_LIB.S9S_MB_2U(SCH_1):M_C_CPU1_SA_CB'<3>:
 C_SIGNAL='@s9s_mb_2u_lib.s9s_mb_2u(sch_1):m_c_cpu1_sa_cb(3)';
NODE_NAME     U1 AG56
 '@S9S_MB_2U_LIB.S9S_MB_2U(SCH_1):PAGE53_I91@PURE_QUANTA.SOCKET4677_AZIF0045P001C01CS(CHIPS)':
 'DDR2_SA_ECC3': CDS_PINID='DDR2_SA_ECC3';
NODE_NAME     J21 198
 '@S9S_MB_2U_LIB.S9S_MB_2U(SCH_1):PAGE102_I13@PURE_QUANTA.SCONN288_ADR50017P130CC(CHIPS)':
 'CB3_A': CDS_PINID='CB3_A';
NODE_NAME     J22 198
 '@S9S_MB_2U_LIB.S9S_MB_2U(SCH_1):PAGE103_I51@PURE_QUANTA.SCONN288_ADR50017P087CC(CHIPS)':
 'CB3_A': CDS_PINID='CB3_A';
NET_NAME
'M_C_CPU1_SA_CB<4>'
 '@S9S_MB_2U_LIB.S9S_MB_2U(SCH_1):M_C_CPU1_SA_CB'<4>:
 C_SIGNAL='@s9s_mb_2u_lib.s9s_mb_2u(sch_1):m_c_cpu1_sa_cb(4)';
NODE_NAME     U1 AC54
 '@S9S_MB_2U_LIB.S9S_MB_2U(SCH_1):PAGE53_I91@PURE_QUANTA.SOCKET4677_AZIF0045P001C01CS(CHIPS)':
 'DDR2_SA_ECC4': CDS_PINID='DDR2_SA_ECC4';
NODE_NAME     J21 58
 '@S9S_MB_2U_LIB.S9S_MB_2U(SCH_1):PAGE102_I13@PURE_QUANTA.SCONN288_ADR50017P130CC(CHIPS)':
 'CB4_A': CDS_PINID='CB4_A';
NODE_NAME     J22 58
 '@S9S_MB_2U_LIB.S9S_MB_2U(SCH_1):PAGE103_I51@PURE_QUANTA.SCONN288_ADR50017P087CC(CHIPS)':
 'CB4_A': CDS_PINID='CB4_A';
NET_NAME
'M_C_CPU1_SA_CB<5>'
 '@S9S_MB_2U_LIB.S9S_MB_2U(SCH_1):M_C_CPU1_SA_CB'<5>:
 C_SIGNAL='@s9s_mb_2u_lib.s9s_mb_2u(sch_1):m_c_cpu1_sa_cb(5)';
NODE_NAME     U1 AD53
 '@S9S_MB_2U_LIB.S9S_MB_2U(SCH_1):PAGE53_I91@PURE_QUANTA.SOCKET4677_AZIF0045P001C01CS(CHIPS)':
 'DDR2_SA_ECC5': CDS_PINID='DDR2_SA_ECC5';
NODE_NAME     J21 60
 '@S9S_MB_2U_LIB.S9S_MB_2U(SCH_1):PAGE102_I13@PURE_QUANTA.SCONN288_ADR50017P130CC(CHIPS)':
 'CB5_A': CDS_PINID='CB5_A';
NODE_NAME     J22 60
 '@S9S_MB_2U_LIB.S9S_MB_2U(SCH_1):PAGE103_I51@PURE_QUANTA.SCONN288_ADR50017P087CC(CHIPS)':
 'CB5_A': CDS_PINID='CB5_A';
NET_NAME
'M_C_CPU1_SA_CB<6>'
 '@S9S_MB_2U_LIB.S9S_MB_2U(SCH_1):M_C_CPU1_SA_CB'<6>:
 C_SIGNAL='@s9s_mb_2u_lib.s9s_mb_2u(sch_1):m_c_cpu1_sa_cb(6)';
NODE_NAME     U1 AG54
 '@S9S_MB_2U_LIB.S9S_MB_2U(SCH_1):PAGE53_I91@PURE_QUANTA.SOCKET4677_AZIF0045P001C01CS(CHIPS)':
 'DDR2_SA_ECC6': CDS_PINID='DDR2_SA_ECC6';
NODE_NAME     J21 203
 '@S9S_MB_2U_LIB.S9S_MB_2U(SCH_1):PAGE102_I13@PURE_QUANTA.SCONN288_ADR50017P130CC(CHIPS)':
 'CB6_A': CDS_PINID='CB6_A';
NODE_NAME     J22 203
 '@S9S_MB_2U_LIB.S9S_MB_2U(SCH_1):PAGE103_I51@PURE_QUANTA.SCONN288_ADR50017P087CC(CHIPS)':
 'CB6_A': CDS_PINID='CB6_A';
NET_NAME
'M_C_CPU1_SA_CB<7>'
 '@S9S_MB_2U_LIB.S9S_MB_2U(SCH_1):M_C_CPU1_SA_CB'<7>:
 C_SIGNAL='@s9s_mb_2u_lib.s9s_mb_2u(sch_1):m_c_cpu1_sa_cb(7)';
NODE_NAME     U1 AF53
 '@S9S_MB_2U_LIB.S9S_MB_2U(SCH_1):PAGE53_I91@PURE_QUANTA.SOCKET4677_AZIF0045P001C01CS(CHIPS)':
 'DDR2_SA_ECC7': CDS_PINID='DDR2_SA_ECC7';
NODE_NAME     J21 205
 '@S9S_MB_2U_LIB.S9S_MB_2U(SCH_1):PAGE102_I13@PURE_QUANTA.SCONN288_ADR50017P130CC(CHIPS)':
 'CB7_A': CDS_PINID='CB7_A';
NODE_NAME     J22 205
 '@S9S_MB_2U_LIB.S9S_MB_2U(SCH_1):PAGE103_I51@PURE_QUANTA.SCONN288_ADR50017P087CC(CHIPS)':
 'CB7_A': CDS_PINID='CB7_A';
NET_NAME
'M_C_CPU1_SA_CS_N<0>'
 '@S9S_MB_2U_LIB.S9S_MB_2U(SCH_1):M_C_CPU1_SA_CS_N'<0>:
 C_SIGNAL='@s9s_mb_2u_lib.s9s_mb_2u(sch_1):m_c_cpu1_sa_cs_n(0)';
NODE_NAME     U1 U54
 '@S9S_MB_2U_LIB.S9S_MB_2U(SCH_1):PAGE53_I91@PURE_QUANTA.SOCKET4677_AZIF0045P001C01CS(CHIPS)':
 'DDR2_SA_CS_N0': CDS_PINID='DDR2_SA_CS_N0';
NODE_NAME     J21 64
 '@S9S_MB_2U_LIB.S9S_MB_2U(SCH_1):PAGE102_I13@PURE_QUANTA.SCONN288_ADR50017P130CC(CHIPS)':
 'CS0_A_N': CDS_PINID='CS0_A_N';
NET_NAME
'M_C_CPU1_SA_CS_N<1>'
 '@S9S_MB_2U_LIB.S9S_MB_2U(SCH_1):M_C_CPU1_SA_CS_N'<1>:
 C_SIGNAL='@s9s_mb_2u_lib.s9s_mb_2u(sch_1):m_c_cpu1_sa_cs_n(1)';
NODE_NAME     U1 T53
 '@S9S_MB_2U_LIB.S9S_MB_2U(SCH_1):PAGE53_I91@PURE_QUANTA.SOCKET4677_AZIF0045P001C01CS(CHIPS)':
 'DDR2_SA_CS_N1': CDS_PINID='DDR2_SA_CS_N1';
NODE_NAME     J21 209
 '@S9S_MB_2U_LIB.S9S_MB_2U(SCH_1):PAGE102_I13@PURE_QUANTA.SCONN288_ADR50017P130CC(CHIPS)':
 'CS1_A_N': CDS_PINID='CS1_A_N';
NET_NAME
'M_C_CPU1_SA_CS_N<2>'
 '@S9S_MB_2U_LIB.S9S_MB_2U(SCH_1):M_C_CPU1_SA_CS_N'<2>:
 C_SIGNAL='@s9s_mb_2u_lib.s9s_mb_2u(sch_1):m_c_cpu1_sa_cs_n(2)';
NODE_NAME     U1 W54
 '@S9S_MB_2U_LIB.S9S_MB_2U(SCH_1):PAGE53_I91@PURE_QUANTA.SOCKET4677_AZIF0045P001C01CS(CHIPS)':
 'DDR2_SA_CS_N2': CDS_PINID='DDR2_SA_CS_N2';
NODE_NAME     J22 64
 '@S9S_MB_2U_LIB.S9S_MB_2U(SCH_1):PAGE103_I51@PURE_QUANTA.SCONN288_ADR50017P087CC(CHIPS)':
 'CS0_A_N': CDS_PINID='CS0_A_N';
NET_NAME
'M_C_CPU1_SA_CS_N<3>'
 '@S9S_MB_2U_LIB.S9S_MB_2U(SCH_1):M_C_CPU1_SA_CS_N'<3>:
 C_SIGNAL='@s9s_mb_2u_lib.s9s_mb_2u(sch_1):m_c_cpu1_sa_cs_n(3)';
NODE_NAME     U1 Y53
 '@S9S_MB_2U_LIB.S9S_MB_2U(SCH_1):PAGE53_I91@PURE_QUANTA.SOCKET4677_AZIF0045P001C01CS(CHIPS)':
 'DDR2_SA_CS_N3': CDS_PINID='DDR2_SA_CS_N3';
NODE_NAME     J22 209
 '@S9S_MB_2U_LIB.S9S_MB_2U(SCH_1):PAGE103_I51@PURE_QUANTA.SCONN288_ADR50017P087CC(CHIPS)':
 'CS1_A_N': CDS_PINID='CS1_A_N';
NET_NAME
'M_C_CPU1_SA_DQ<0>'
 '@S9S_MB_2U_LIB.S9S_MB_2U(SCH_1):M_C_CPU1_SA_DQ'<0>:
 C_SIGNAL='@s9s_mb_2u_lib.s9s_mb_2u(sch_1):m_c_cpu1_sa_dq(0)';
NODE_NAME     U1 U78
 '@S9S_MB_2U_LIB.S9S_MB_2U(SCH_1):PAGE53_I91@PURE_QUANTA.SOCKET4677_AZIF0045P001C01CS(CHIPS)':
 'DDR2_SA_DQ0': CDS_PINID='DDR2_SA_DQ0';
NODE_NAME     J21 7
 '@S9S_MB_2U_LIB.S9S_MB_2U(SCH_1):PAGE102_I13@PURE_QUANTA.SCONN288_ADR50017P130CC(CHIPS)':
 'DQ0_A': CDS_PINID='DQ0_A';
NODE_NAME     J22 7
 '@S9S_MB_2U_LIB.S9S_MB_2U(SCH_1):PAGE103_I51@PURE_QUANTA.SCONN288_ADR50017P087CC(CHIPS)':
 'DQ0_A': CDS_PINID='DQ0_A';
NET_NAME
'M_C_CPU1_SA_DQ<10>'
 '@S9S_MB_2U_LIB.S9S_MB_2U(SCH_1):M_C_CPU1_SA_DQ'<10>:
 C_SIGNAL='@s9s_mb_2u_lib.s9s_mb_2u(sch_1):m_c_cpu1_sa_dq(10)';
NODE_NAME     U1 AF69
 '@S9S_MB_2U_LIB.S9S_MB_2U(SCH_1):PAGE53_I91@PURE_QUANTA.SOCKET4677_AZIF0045P001C01CS(CHIPS)':
 'DDR2_SA_DQ10': CDS_PINID='DDR2_SA_DQ10';
NODE_NAME     J21 163
 '@S9S_MB_2U_LIB.S9S_MB_2U(SCH_1):PAGE102_I13@PURE_QUANTA.SCONN288_ADR50017P130CC(CHIPS)':
 'DQ10_A': CDS_PINID='DQ10_A';
NODE_NAME     J22 163
 '@S9S_MB_2U_LIB.S9S_MB_2U(SCH_1):PAGE103_I51@PURE_QUANTA.SCONN288_ADR50017P087CC(CHIPS)':
 'DQ10_A': CDS_PINID='DQ10_A';
NET_NAME
'M_C_CPU1_SA_DQ<11>'
 '@S9S_MB_2U_LIB.S9S_MB_2U(SCH_1):M_C_CPU1_SA_DQ'<11>:
 C_SIGNAL='@s9s_mb_2u_lib.s9s_mb_2u(sch_1):m_c_cpu1_sa_dq(11)';
NODE_NAME     U1 AG68
 '@S9S_MB_2U_LIB.S9S_MB_2U(SCH_1):PAGE53_I91@PURE_QUANTA.SOCKET4677_AZIF0045P001C01CS(CHIPS)':
 'DDR2_SA_DQ11': CDS_PINID='DDR2_SA_DQ11';
NODE_NAME     J21 165
 '@S9S_MB_2U_LIB.S9S_MB_2U(SCH_1):PAGE102_I13@PURE_QUANTA.SCONN288_ADR50017P130CC(CHIPS)':
 'DQ11_A': CDS_PINID='DQ11_A';
NODE_NAME     J22 165
 '@S9S_MB_2U_LIB.S9S_MB_2U(SCH_1):PAGE103_I51@PURE_QUANTA.SCONN288_ADR50017P087CC(CHIPS)':
 'DQ11_A': CDS_PINID='DQ11_A';
NET_NAME
'M_C_CPU1_SA_DQ<12>'
 '@S9S_MB_2U_LIB.S9S_MB_2U(SCH_1):M_C_CPU1_SA_DQ'<12>:
 C_SIGNAL='@s9s_mb_2u_lib.s9s_mb_2u(sch_1):m_c_cpu1_sa_dq(12)';
NODE_NAME     U1 AC66
 '@S9S_MB_2U_LIB.S9S_MB_2U(SCH_1):PAGE53_I91@PURE_QUANTA.SOCKET4677_AZIF0045P001C01CS(CHIPS)':
 'DDR2_SA_DQ12': CDS_PINID='DDR2_SA_DQ12';
NODE_NAME     J21 25
 '@S9S_MB_2U_LIB.S9S_MB_2U(SCH_1):PAGE102_I13@PURE_QUANTA.SCONN288_ADR50017P130CC(CHIPS)':
 'DQ12_A': CDS_PINID='DQ12_A';
NODE_NAME     J22 25
 '@S9S_MB_2U_LIB.S9S_MB_2U(SCH_1):PAGE103_I51@PURE_QUANTA.SCONN288_ADR50017P087CC(CHIPS)':
 'DQ12_A': CDS_PINID='DQ12_A';
NET_NAME
'M_C_CPU1_SA_DQ<13>'
 '@S9S_MB_2U_LIB.S9S_MB_2U(SCH_1):M_C_CPU1_SA_DQ'<13>:
 C_SIGNAL='@s9s_mb_2u_lib.s9s_mb_2u(sch_1):m_c_cpu1_sa_dq(13)';
NODE_NAME     U1 AD65
 '@S9S_MB_2U_LIB.S9S_MB_2U(SCH_1):PAGE53_I91@PURE_QUANTA.SOCKET4677_AZIF0045P001C01CS(CHIPS)':
 'DDR2_SA_DQ13': CDS_PINID='DDR2_SA_DQ13';
NODE_NAME     J21 27
 '@S9S_MB_2U_LIB.S9S_MB_2U(SCH_1):PAGE102_I13@PURE_QUANTA.SCONN288_ADR50017P130CC(CHIPS)':
 'DQ13_A': CDS_PINID='DQ13_A';
NODE_NAME     J22 27
 '@S9S_MB_2U_LIB.S9S_MB_2U(SCH_1):PAGE103_I51@PURE_QUANTA.SCONN288_ADR50017P087CC(CHIPS)':
 'DQ13_A': CDS_PINID='DQ13_A';
NET_NAME
'M_C_CPU1_SA_DQ<14>'
 '@S9S_MB_2U_LIB.S9S_MB_2U(SCH_1):M_C_CPU1_SA_DQ'<14>:
 C_SIGNAL='@s9s_mb_2u_lib.s9s_mb_2u(sch_1):m_c_cpu1_sa_dq(14)';
NODE_NAME     U1 AG66
 '@S9S_MB_2U_LIB.S9S_MB_2U(SCH_1):PAGE53_I91@PURE_QUANTA.SOCKET4677_AZIF0045P001C01CS(CHIPS)':
 'DDR2_SA_DQ14': CDS_PINID='DDR2_SA_DQ14';
NODE_NAME     J21 170
 '@S9S_MB_2U_LIB.S9S_MB_2U(SCH_1):PAGE102_I13@PURE_QUANTA.SCONN288_ADR50017P130CC(CHIPS)':
 'DQ14_A': CDS_PINID='DQ14_A';
NODE_NAME     J22 170
 '@S9S_MB_2U_LIB.S9S_MB_2U(SCH_1):PAGE103_I51@PURE_QUANTA.SCONN288_ADR50017P087CC(CHIPS)':
 'DQ14_A': CDS_PINID='DQ14_A';
NET_NAME
'M_C_CPU1_SA_DQ<15>'
 '@S9S_MB_2U_LIB.S9S_MB_2U(SCH_1):M_C_CPU1_SA_DQ'<15>:
 C_SIGNAL='@s9s_mb_2u_lib.s9s_mb_2u(sch_1):m_c_cpu1_sa_dq(15)';
NODE_NAME     U1 AF65
 '@S9S_MB_2U_LIB.S9S_MB_2U(SCH_1):PAGE53_I91@PURE_QUANTA.SOCKET4677_AZIF0045P001C01CS(CHIPS)':
 'DDR2_SA_DQ15': CDS_PINID='DDR2_SA_DQ15';
NODE_NAME     J21 172
 '@S9S_MB_2U_LIB.S9S_MB_2U(SCH_1):PAGE102_I13@PURE_QUANTA.SCONN288_ADR50017P130CC(CHIPS)':
 'DQ15_A': CDS_PINID='DQ15_A';
NODE_NAME     J22 172
 '@S9S_MB_2U_LIB.S9S_MB_2U(SCH_1):PAGE103_I51@PURE_QUANTA.SCONN288_ADR50017P087CC(CHIPS)':
 'DQ15_A': CDS_PINID='DQ15_A';
NET_NAME
'M_C_CPU1_SA_DQ<16>'
 '@S9S_MB_2U_LIB.S9S_MB_2U(SCH_1):M_C_CPU1_SA_DQ'<16>:
 C_SIGNAL='@s9s_mb_2u_lib.s9s_mb_2u(sch_1):m_c_cpu1_sa_dq(16)';
NODE_NAME     U1 U66
 '@S9S_MB_2U_LIB.S9S_MB_2U(SCH_1):PAGE53_I91@PURE_QUANTA.SOCKET4677_AZIF0045P001C01CS(CHIPS)':
 'DDR2_SA_DQ16': CDS_PINID='DDR2_SA_DQ16';
NODE_NAME     J21 29
 '@S9S_MB_2U_LIB.S9S_MB_2U(SCH_1):PAGE102_I13@PURE_QUANTA.SCONN288_ADR50017P130CC(CHIPS)':
 'DQ16_A': CDS_PINID='DQ16_A';
NODE_NAME     J22 29
 '@S9S_MB_2U_LIB.S9S_MB_2U(SCH_1):PAGE103_I51@PURE_QUANTA.SCONN288_ADR50017P087CC(CHIPS)':
 'DQ16_A': CDS_PINID='DQ16_A';
NET_NAME
'M_C_CPU1_SA_DQ<17>'
 '@S9S_MB_2U_LIB.S9S_MB_2U(SCH_1):M_C_CPU1_SA_DQ'<17>:
 C_SIGNAL='@s9s_mb_2u_lib.s9s_mb_2u(sch_1):m_c_cpu1_sa_dq(17)';
NODE_NAME     U1 T65
 '@S9S_MB_2U_LIB.S9S_MB_2U(SCH_1):PAGE53_I91@PURE_QUANTA.SOCKET4677_AZIF0045P001C01CS(CHIPS)':
 'DDR2_SA_DQ17': CDS_PINID='DDR2_SA_DQ17';
NODE_NAME     J21 31
 '@S9S_MB_2U_LIB.S9S_MB_2U(SCH_1):PAGE102_I13@PURE_QUANTA.SCONN288_ADR50017P130CC(CHIPS)':
 'DQ17_A': CDS_PINID='DQ17_A';
NODE_NAME     J22 31
 '@S9S_MB_2U_LIB.S9S_MB_2U(SCH_1):PAGE103_I51@PURE_QUANTA.SCONN288_ADR50017P087CC(CHIPS)':
 'DQ17_A': CDS_PINID='DQ17_A';
NET_NAME
'M_C_CPU1_SA_DQ<18>'
 '@S9S_MB_2U_LIB.S9S_MB_2U(SCH_1):M_C_CPU1_SA_DQ'<18>:
 C_SIGNAL='@s9s_mb_2u_lib.s9s_mb_2u(sch_1):m_c_cpu1_sa_dq(18)';
NODE_NAME     U1 W66
 '@S9S_MB_2U_LIB.S9S_MB_2U(SCH_1):PAGE53_I91@PURE_QUANTA.SOCKET4677_AZIF0045P001C01CS(CHIPS)':
 'DDR2_SA_DQ18': CDS_PINID='DDR2_SA_DQ18';
NODE_NAME     J21 174
 '@S9S_MB_2U_LIB.S9S_MB_2U(SCH_1):PAGE102_I13@PURE_QUANTA.SCONN288_ADR50017P130CC(CHIPS)':
 'DQ18_A': CDS_PINID='DQ18_A';
NODE_NAME     J22 174
 '@S9S_MB_2U_LIB.S9S_MB_2U(SCH_1):PAGE103_I51@PURE_QUANTA.SCONN288_ADR50017P087CC(CHIPS)':
 'DQ18_A': CDS_PINID='DQ18_A';
NET_NAME
'M_C_CPU1_SA_DQ<19>'
 '@S9S_MB_2U_LIB.S9S_MB_2U(SCH_1):M_C_CPU1_SA_DQ'<19>:
 C_SIGNAL='@s9s_mb_2u_lib.s9s_mb_2u(sch_1):m_c_cpu1_sa_dq(19)';
NODE_NAME     U1 Y65
 '@S9S_MB_2U_LIB.S9S_MB_2U(SCH_1):PAGE53_I91@PURE_QUANTA.SOCKET4677_AZIF0045P001C01CS(CHIPS)':
 'DDR2_SA_DQ19': CDS_PINID='DDR2_SA_DQ19';
NODE_NAME     J21 176
 '@S9S_MB_2U_LIB.S9S_MB_2U(SCH_1):PAGE102_I13@PURE_QUANTA.SCONN288_ADR50017P130CC(CHIPS)':
 'DQ19_A': CDS_PINID='DQ19_A';
NODE_NAME     J22 176
 '@S9S_MB_2U_LIB.S9S_MB_2U(SCH_1):PAGE103_I51@PURE_QUANTA.SCONN288_ADR50017P087CC(CHIPS)':
 'DQ19_A': CDS_PINID='DQ19_A';
NET_NAME
'M_C_CPU1_SA_DQ<1>'
 '@S9S_MB_2U_LIB.S9S_MB_2U(SCH_1):M_C_CPU1_SA_DQ'<1>:
 C_SIGNAL='@s9s_mb_2u_lib.s9s_mb_2u(sch_1):m_c_cpu1_sa_dq(1)';
NODE_NAME     U1 T77
 '@S9S_MB_2U_LIB.S9S_MB_2U(SCH_1):PAGE53_I91@PURE_QUANTA.SOCKET4677_AZIF0045P001C01CS(CHIPS)':
 'DDR2_SA_DQ1': CDS_PINID='DDR2_SA_DQ1';
NODE_NAME     J21 9
 '@S9S_MB_2U_LIB.S9S_MB_2U(SCH_1):PAGE102_I13@PURE_QUANTA.SCONN288_ADR50017P130CC(CHIPS)':
 'DQ1_A': CDS_PINID='DQ1_A';
NODE_NAME     J22 9
 '@S9S_MB_2U_LIB.S9S_MB_2U(SCH_1):PAGE103_I51@PURE_QUANTA.SCONN288_ADR50017P087CC(CHIPS)':
 'DQ1_A': CDS_PINID='DQ1_A';
NET_NAME
'M_C_CPU1_SA_DQ<20>'
 '@S9S_MB_2U_LIB.S9S_MB_2U(SCH_1):M_C_CPU1_SA_DQ'<20>:
 C_SIGNAL='@s9s_mb_2u_lib.s9s_mb_2u(sch_1):m_c_cpu1_sa_dq(20)';
NODE_NAME     U1 T63
 '@S9S_MB_2U_LIB.S9S_MB_2U(SCH_1):PAGE53_I91@PURE_QUANTA.SOCKET4677_AZIF0045P001C01CS(CHIPS)':
 'DDR2_SA_DQ20': CDS_PINID='DDR2_SA_DQ20';
NODE_NAME     J21 36
 '@S9S_MB_2U_LIB.S9S_MB_2U(SCH_1):PAGE102_I13@PURE_QUANTA.SCONN288_ADR50017P130CC(CHIPS)':
 'DQ20_A': CDS_PINID='DQ20_A';
NODE_NAME     J22 36
 '@S9S_MB_2U_LIB.S9S_MB_2U(SCH_1):PAGE103_I51@PURE_QUANTA.SCONN288_ADR50017P087CC(CHIPS)':
 'DQ20_A': CDS_PINID='DQ20_A';
NET_NAME
'M_C_CPU1_SA_DQ<21>'
 '@S9S_MB_2U_LIB.S9S_MB_2U(SCH_1):M_C_CPU1_SA_DQ'<21>:
 C_SIGNAL='@s9s_mb_2u_lib.s9s_mb_2u(sch_1):m_c_cpu1_sa_dq(21)';
NODE_NAME     U1 U62
 '@S9S_MB_2U_LIB.S9S_MB_2U(SCH_1):PAGE53_I91@PURE_QUANTA.SOCKET4677_AZIF0045P001C01CS(CHIPS)':
 'DDR2_SA_DQ21': CDS_PINID='DDR2_SA_DQ21';
NODE_NAME     J21 38
 '@S9S_MB_2U_LIB.S9S_MB_2U(SCH_1):PAGE102_I13@PURE_QUANTA.SCONN288_ADR50017P130CC(CHIPS)':
 'DQ21_A': CDS_PINID='DQ21_A';
NODE_NAME     J22 38
 '@S9S_MB_2U_LIB.S9S_MB_2U(SCH_1):PAGE103_I51@PURE_QUANTA.SCONN288_ADR50017P087CC(CHIPS)':
 'DQ21_A': CDS_PINID='DQ21_A';
NET_NAME
'M_C_CPU1_SA_DQ<22>'
 '@S9S_MB_2U_LIB.S9S_MB_2U(SCH_1):M_C_CPU1_SA_DQ'<22>:
 C_SIGNAL='@s9s_mb_2u_lib.s9s_mb_2u(sch_1):m_c_cpu1_sa_dq(22)';
NODE_NAME     U1 Y63
 '@S9S_MB_2U_LIB.S9S_MB_2U(SCH_1):PAGE53_I91@PURE_QUANTA.SOCKET4677_AZIF0045P001C01CS(CHIPS)':
 'DDR2_SA_DQ22': CDS_PINID='DDR2_SA_DQ22';
NODE_NAME     J21 181
 '@S9S_MB_2U_LIB.S9S_MB_2U(SCH_1):PAGE102_I13@PURE_QUANTA.SCONN288_ADR50017P130CC(CHIPS)':
 'DQ22_A': CDS_PINID='DQ22_A';
NODE_NAME     J22 181
 '@S9S_MB_2U_LIB.S9S_MB_2U(SCH_1):PAGE103_I51@PURE_QUANTA.SCONN288_ADR50017P087CC(CHIPS)':
 'DQ22_A': CDS_PINID='DQ22_A';
NET_NAME
'M_C_CPU1_SA_DQ<23>'
 '@S9S_MB_2U_LIB.S9S_MB_2U(SCH_1):M_C_CPU1_SA_DQ'<23>:
 C_SIGNAL='@s9s_mb_2u_lib.s9s_mb_2u(sch_1):m_c_cpu1_sa_dq(23)';
NODE_NAME     U1 W62
 '@S9S_MB_2U_LIB.S9S_MB_2U(SCH_1):PAGE53_I91@PURE_QUANTA.SOCKET4677_AZIF0045P001C01CS(CHIPS)':
 'DDR2_SA_DQ23': CDS_PINID='DDR2_SA_DQ23';
NODE_NAME     J21 183
 '@S9S_MB_2U_LIB.S9S_MB_2U(SCH_1):PAGE102_I13@PURE_QUANTA.SCONN288_ADR50017P130CC(CHIPS)':
 'DQ23_A': CDS_PINID='DQ23_A';
NODE_NAME     J22 183
 '@S9S_MB_2U_LIB.S9S_MB_2U(SCH_1):PAGE103_I51@PURE_QUANTA.SCONN288_ADR50017P087CC(CHIPS)':
 'DQ23_A': CDS_PINID='DQ23_A';
NET_NAME
'M_C_CPU1_SA_DQ<24>'
 '@S9S_MB_2U_LIB.S9S_MB_2U(SCH_1):M_C_CPU1_SA_DQ'<24>:
 C_SIGNAL='@s9s_mb_2u_lib.s9s_mb_2u(sch_1):m_c_cpu1_sa_dq(24)';
NODE_NAME     U1 AD63
 '@S9S_MB_2U_LIB.S9S_MB_2U(SCH_1):PAGE53_I91@PURE_QUANTA.SOCKET4677_AZIF0045P001C01CS(CHIPS)':
 'DDR2_SA_DQ24': CDS_PINID='DDR2_SA_DQ24';
NODE_NAME     J21 40
 '@S9S_MB_2U_LIB.S9S_MB_2U(SCH_1):PAGE102_I13@PURE_QUANTA.SCONN288_ADR50017P130CC(CHIPS)':
 'DQ24_A': CDS_PINID='DQ24_A';
NODE_NAME     J22 40
 '@S9S_MB_2U_LIB.S9S_MB_2U(SCH_1):PAGE103_I51@PURE_QUANTA.SCONN288_ADR50017P087CC(CHIPS)':
 'DQ24_A': CDS_PINID='DQ24_A';
NET_NAME
'M_C_CPU1_SA_DQ<25>'
 '@S9S_MB_2U_LIB.S9S_MB_2U(SCH_1):M_C_CPU1_SA_DQ'<25>:
 C_SIGNAL='@s9s_mb_2u_lib.s9s_mb_2u(sch_1):m_c_cpu1_sa_dq(25)';
NODE_NAME     U1 AC62
 '@S9S_MB_2U_LIB.S9S_MB_2U(SCH_1):PAGE53_I91@PURE_QUANTA.SOCKET4677_AZIF0045P001C01CS(CHIPS)':
 'DDR2_SA_DQ25': CDS_PINID='DDR2_SA_DQ25';
NODE_NAME     J21 42
 '@S9S_MB_2U_LIB.S9S_MB_2U(SCH_1):PAGE102_I13@PURE_QUANTA.SCONN288_ADR50017P130CC(CHIPS)':
 'DQ25_A': CDS_PINID='DQ25_A';
NODE_NAME     J22 42
 '@S9S_MB_2U_LIB.S9S_MB_2U(SCH_1):PAGE103_I51@PURE_QUANTA.SCONN288_ADR50017P087CC(CHIPS)':
 'DQ25_A': CDS_PINID='DQ25_A';
NET_NAME
'M_C_CPU1_SA_DQ<26>'
 '@S9S_MB_2U_LIB.S9S_MB_2U(SCH_1):M_C_CPU1_SA_DQ'<26>:
 C_SIGNAL='@s9s_mb_2u_lib.s9s_mb_2u(sch_1):m_c_cpu1_sa_dq(26)';
NODE_NAME     U1 AF63
 '@S9S_MB_2U_LIB.S9S_MB_2U(SCH_1):PAGE53_I91@PURE_QUANTA.SOCKET4677_AZIF0045P001C01CS(CHIPS)':
 'DDR2_SA_DQ26': CDS_PINID='DDR2_SA_DQ26';
NODE_NAME     J21 185
 '@S9S_MB_2U_LIB.S9S_MB_2U(SCH_1):PAGE102_I13@PURE_QUANTA.SCONN288_ADR50017P130CC(CHIPS)':
 'DQ26_A': CDS_PINID='DQ26_A';
NODE_NAME     J22 185
 '@S9S_MB_2U_LIB.S9S_MB_2U(SCH_1):PAGE103_I51@PURE_QUANTA.SCONN288_ADR50017P087CC(CHIPS)':
 'DQ26_A': CDS_PINID='DQ26_A';
NET_NAME
'M_C_CPU1_SA_DQ<27>'
 '@S9S_MB_2U_LIB.S9S_MB_2U(SCH_1):M_C_CPU1_SA_DQ'<27>:
 C_SIGNAL='@s9s_mb_2u_lib.s9s_mb_2u(sch_1):m_c_cpu1_sa_dq(27)';
NODE_NAME     U1 AG62
 '@S9S_MB_2U_LIB.S9S_MB_2U(SCH_1):PAGE53_I91@PURE_QUANTA.SOCKET4677_AZIF0045P001C01CS(CHIPS)':
 'DDR2_SA_DQ27': CDS_PINID='DDR2_SA_DQ27';
NODE_NAME     J21 187
 '@S9S_MB_2U_LIB.S9S_MB_2U(SCH_1):PAGE102_I13@PURE_QUANTA.SCONN288_ADR50017P130CC(CHIPS)':
 'DQ27_A': CDS_PINID='DQ27_A';
NODE_NAME     J22 187
 '@S9S_MB_2U_LIB.S9S_MB_2U(SCH_1):PAGE103_I51@PURE_QUANTA.SCONN288_ADR50017P087CC(CHIPS)':
 'DQ27_A': CDS_PINID='DQ27_A';
NET_NAME
'M_C_CPU1_SA_DQ<28>'
 '@S9S_MB_2U_LIB.S9S_MB_2U(SCH_1):M_C_CPU1_SA_DQ'<28>:
 C_SIGNAL='@s9s_mb_2u_lib.s9s_mb_2u(sch_1):m_c_cpu1_sa_dq(28)';
NODE_NAME     U1 AC60
 '@S9S_MB_2U_LIB.S9S_MB_2U(SCH_1):PAGE53_I91@PURE_QUANTA.SOCKET4677_AZIF0045P001C01CS(CHIPS)':
 'DDR2_SA_DQ28': CDS_PINID='DDR2_SA_DQ28';
NODE_NAME     J21 47
 '@S9S_MB_2U_LIB.S9S_MB_2U(SCH_1):PAGE102_I13@PURE_QUANTA.SCONN288_ADR50017P130CC(CHIPS)':
 'DQ28_A': CDS_PINID='DQ28_A';
NODE_NAME     J22 47
 '@S9S_MB_2U_LIB.S9S_MB_2U(SCH_1):PAGE103_I51@PURE_QUANTA.SCONN288_ADR50017P087CC(CHIPS)':
 'DQ28_A': CDS_PINID='DQ28_A';
NET_NAME
'M_C_CPU1_SA_DQ<29>'
 '@S9S_MB_2U_LIB.S9S_MB_2U(SCH_1):M_C_CPU1_SA_DQ'<29>:
 C_SIGNAL='@s9s_mb_2u_lib.s9s_mb_2u(sch_1):m_c_cpu1_sa_dq(29)';
NODE_NAME     U1 AD59
 '@S9S_MB_2U_LIB.S9S_MB_2U(SCH_1):PAGE53_I91@PURE_QUANTA.SOCKET4677_AZIF0045P001C01CS(CHIPS)':
 'DDR2_SA_DQ29': CDS_PINID='DDR2_SA_DQ29';
NODE_NAME     J21 49
 '@S9S_MB_2U_LIB.S9S_MB_2U(SCH_1):PAGE102_I13@PURE_QUANTA.SCONN288_ADR50017P130CC(CHIPS)':
 'DQ29_A': CDS_PINID='DQ29_A';
NODE_NAME     J22 49
 '@S9S_MB_2U_LIB.S9S_MB_2U(SCH_1):PAGE103_I51@PURE_QUANTA.SCONN288_ADR50017P087CC(CHIPS)':
 'DQ29_A': CDS_PINID='DQ29_A';
NET_NAME
'M_C_CPU1_SA_DQ<2>'
 '@S9S_MB_2U_LIB.S9S_MB_2U(SCH_1):M_C_CPU1_SA_DQ'<2>:
 C_SIGNAL='@s9s_mb_2u_lib.s9s_mb_2u(sch_1):m_c_cpu1_sa_dq(2)';
NODE_NAME     U1 W78
 '@S9S_MB_2U_LIB.S9S_MB_2U(SCH_1):PAGE53_I91@PURE_QUANTA.SOCKET4677_AZIF0045P001C01CS(CHIPS)':
 'DDR2_SA_DQ2': CDS_PINID='DDR2_SA_DQ2';
NODE_NAME     J21 152
 '@S9S_MB_2U_LIB.S9S_MB_2U(SCH_1):PAGE102_I13@PURE_QUANTA.SCONN288_ADR50017P130CC(CHIPS)':
 'DQ2_A': CDS_PINID='DQ2_A';
NODE_NAME     J22 152
 '@S9S_MB_2U_LIB.S9S_MB_2U(SCH_1):PAGE103_I51@PURE_QUANTA.SCONN288_ADR50017P087CC(CHIPS)':
 'DQ2_A': CDS_PINID='DQ2_A';
NET_NAME
'M_C_CPU1_SA_DQ<30>'
 '@S9S_MB_2U_LIB.S9S_MB_2U(SCH_1):M_C_CPU1_SA_DQ'<30>:
 C_SIGNAL='@s9s_mb_2u_lib.s9s_mb_2u(sch_1):m_c_cpu1_sa_dq(30)';
NODE_NAME     U1 AG60
 '@S9S_MB_2U_LIB.S9S_MB_2U(SCH_1):PAGE53_I91@PURE_QUANTA.SOCKET4677_AZIF0045P001C01CS(CHIPS)':
 'DDR2_SA_DQ30': CDS_PINID='DDR2_SA_DQ30';
NODE_NAME     J21 192
 '@S9S_MB_2U_LIB.S9S_MB_2U(SCH_1):PAGE102_I13@PURE_QUANTA.SCONN288_ADR50017P130CC(CHIPS)':
 'DQ30_A': CDS_PINID='DQ30_A';
NODE_NAME     J22 192
 '@S9S_MB_2U_LIB.S9S_MB_2U(SCH_1):PAGE103_I51@PURE_QUANTA.SCONN288_ADR50017P087CC(CHIPS)':
 'DQ30_A': CDS_PINID='DQ30_A';
NET_NAME
'M_C_CPU1_SA_DQ<31>'
 '@S9S_MB_2U_LIB.S9S_MB_2U(SCH_1):M_C_CPU1_SA_DQ'<31>:
 C_SIGNAL='@s9s_mb_2u_lib.s9s_mb_2u(sch_1):m_c_cpu1_sa_dq(31)';
NODE_NAME     U1 AF59
 '@S9S_MB_2U_LIB.S9S_MB_2U(SCH_1):PAGE53_I91@PURE_QUANTA.SOCKET4677_AZIF0045P001C01CS(CHIPS)':
 'DDR2_SA_DQ31': CDS_PINID='DDR2_SA_DQ31';
NODE_NAME     J21 194
 '@S9S_MB_2U_LIB.S9S_MB_2U(SCH_1):PAGE102_I13@PURE_QUANTA.SCONN288_ADR50017P130CC(CHIPS)':
 'DQ31_A': CDS_PINID='DQ31_A';
NODE_NAME     J22 194
 '@S9S_MB_2U_LIB.S9S_MB_2U(SCH_1):PAGE103_I51@PURE_QUANTA.SCONN288_ADR50017P087CC(CHIPS)':
 'DQ31_A': CDS_PINID='DQ31_A';
NET_NAME
'M_C_CPU1_SA_DQ<3>'
 '@S9S_MB_2U_LIB.S9S_MB_2U(SCH_1):M_C_CPU1_SA_DQ'<3>:
 C_SIGNAL='@s9s_mb_2u_lib.s9s_mb_2u(sch_1):m_c_cpu1_sa_dq(3)';
NODE_NAME     U1 Y77
 '@S9S_MB_2U_LIB.S9S_MB_2U(SCH_1):PAGE53_I91@PURE_QUANTA.SOCKET4677_AZIF0045P001C01CS(CHIPS)':
 'DDR2_SA_DQ3': CDS_PINID='DDR2_SA_DQ3';
NODE_NAME     J21 154
 '@S9S_MB_2U_LIB.S9S_MB_2U(SCH_1):PAGE102_I13@PURE_QUANTA.SCONN288_ADR50017P130CC(CHIPS)':
 'DQ3_A': CDS_PINID='DQ3_A';
NODE_NAME     J22 154
 '@S9S_MB_2U_LIB.S9S_MB_2U(SCH_1):PAGE103_I51@PURE_QUANTA.SCONN288_ADR50017P087CC(CHIPS)':
 'DQ3_A': CDS_PINID='DQ3_A';
NET_NAME
'M_C_CPU1_SA_DQ<4>'
 '@S9S_MB_2U_LIB.S9S_MB_2U(SCH_1):M_C_CPU1_SA_DQ'<4>:
 C_SIGNAL='@s9s_mb_2u_lib.s9s_mb_2u(sch_1):m_c_cpu1_sa_dq(4)';
NODE_NAME     U1 T75
 '@S9S_MB_2U_LIB.S9S_MB_2U(SCH_1):PAGE53_I91@PURE_QUANTA.SOCKET4677_AZIF0045P001C01CS(CHIPS)':
 'DDR2_SA_DQ4': CDS_PINID='DDR2_SA_DQ4';
NODE_NAME     J21 14
 '@S9S_MB_2U_LIB.S9S_MB_2U(SCH_1):PAGE102_I13@PURE_QUANTA.SCONN288_ADR50017P130CC(CHIPS)':
 'DQ4_A': CDS_PINID='DQ4_A';
NODE_NAME     J22 14
 '@S9S_MB_2U_LIB.S9S_MB_2U(SCH_1):PAGE103_I51@PURE_QUANTA.SCONN288_ADR50017P087CC(CHIPS)':
 'DQ4_A': CDS_PINID='DQ4_A';
NET_NAME
'M_C_CPU1_SA_DQ<5>'
 '@S9S_MB_2U_LIB.S9S_MB_2U(SCH_1):M_C_CPU1_SA_DQ'<5>:
 C_SIGNAL='@s9s_mb_2u_lib.s9s_mb_2u(sch_1):m_c_cpu1_sa_dq(5)';
NODE_NAME     U1 U74
 '@S9S_MB_2U_LIB.S9S_MB_2U(SCH_1):PAGE53_I91@PURE_QUANTA.SOCKET4677_AZIF0045P001C01CS(CHIPS)':
 'DDR2_SA_DQ5': CDS_PINID='DDR2_SA_DQ5';
NODE_NAME     J21 16
 '@S9S_MB_2U_LIB.S9S_MB_2U(SCH_1):PAGE102_I13@PURE_QUANTA.SCONN288_ADR50017P130CC(CHIPS)':
 'DQ5_A': CDS_PINID='DQ5_A';
NODE_NAME     J22 16
 '@S9S_MB_2U_LIB.S9S_MB_2U(SCH_1):PAGE103_I51@PURE_QUANTA.SCONN288_ADR50017P087CC(CHIPS)':
 'DQ5_A': CDS_PINID='DQ5_A';
NET_NAME
'M_C_CPU1_SA_DQ<6>'
 '@S9S_MB_2U_LIB.S9S_MB_2U(SCH_1):M_C_CPU1_SA_DQ'<6>:
 C_SIGNAL='@s9s_mb_2u_lib.s9s_mb_2u(sch_1):m_c_cpu1_sa_dq(6)';
NODE_NAME     U1 Y75
 '@S9S_MB_2U_LIB.S9S_MB_2U(SCH_1):PAGE53_I91@PURE_QUANTA.SOCKET4677_AZIF0045P001C01CS(CHIPS)':
 'DDR2_SA_DQ6': CDS_PINID='DDR2_SA_DQ6';
NODE_NAME     J21 159
 '@S9S_MB_2U_LIB.S9S_MB_2U(SCH_1):PAGE102_I13@PURE_QUANTA.SCONN288_ADR50017P130CC(CHIPS)':
 'DQ6_A': CDS_PINID='DQ6_A';
NODE_NAME     J22 159
 '@S9S_MB_2U_LIB.S9S_MB_2U(SCH_1):PAGE103_I51@PURE_QUANTA.SCONN288_ADR50017P087CC(CHIPS)':
 'DQ6_A': CDS_PINID='DQ6_A';
NET_NAME
'M_C_CPU1_SA_DQ<7>'
 '@S9S_MB_2U_LIB.S9S_MB_2U(SCH_1):M_C_CPU1_SA_DQ'<7>:
 C_SIGNAL='@s9s_mb_2u_lib.s9s_mb_2u(sch_1):m_c_cpu1_sa_dq(7)';
NODE_NAME     U1 W74
 '@S9S_MB_2U_LIB.S9S_MB_2U(SCH_1):PAGE53_I91@PURE_QUANTA.SOCKET4677_AZIF0045P001C01CS(CHIPS)':
 'DDR2_SA_DQ7': CDS_PINID='DDR2_SA_DQ7';
NODE_NAME     J21 161
 '@S9S_MB_2U_LIB.S9S_MB_2U(SCH_1):PAGE102_I13@PURE_QUANTA.SCONN288_ADR50017P130CC(CHIPS)':
 'DQ7_A': CDS_PINID='DQ7_A';
NODE_NAME     J22 161
 '@S9S_MB_2U_LIB.S9S_MB_2U(SCH_1):PAGE103_I51@PURE_QUANTA.SCONN288_ADR50017P087CC(CHIPS)':
 'DQ7_A': CDS_PINID='DQ7_A';
NET_NAME
'M_C_CPU1_SA_DQ<8>'
 '@S9S_MB_2U_LIB.S9S_MB_2U(SCH_1):M_C_CPU1_SA_DQ'<8>:
 C_SIGNAL='@s9s_mb_2u_lib.s9s_mb_2u(sch_1):m_c_cpu1_sa_dq(8)';
NODE_NAME     U1 AD69
 '@S9S_MB_2U_LIB.S9S_MB_2U(SCH_1):PAGE53_I91@PURE_QUANTA.SOCKET4677_AZIF0045P001C01CS(CHIPS)':
 'DDR2_SA_DQ8': CDS_PINID='DDR2_SA_DQ8';
NODE_NAME     J21 18
 '@S9S_MB_2U_LIB.S9S_MB_2U(SCH_1):PAGE102_I13@PURE_QUANTA.SCONN288_ADR50017P130CC(CHIPS)':
 'DQ8_A': CDS_PINID='DQ8_A';
NODE_NAME     J22 18
 '@S9S_MB_2U_LIB.S9S_MB_2U(SCH_1):PAGE103_I51@PURE_QUANTA.SCONN288_ADR50017P087CC(CHIPS)':
 'DQ8_A': CDS_PINID='DQ8_A';
NET_NAME
'M_C_CPU1_SA_DQ<9>'
 '@S9S_MB_2U_LIB.S9S_MB_2U(SCH_1):M_C_CPU1_SA_DQ'<9>:
 C_SIGNAL='@s9s_mb_2u_lib.s9s_mb_2u(sch_1):m_c_cpu1_sa_dq(9)';
NODE_NAME     U1 AC68
 '@S9S_MB_2U_LIB.S9S_MB_2U(SCH_1):PAGE53_I91@PURE_QUANTA.SOCKET4677_AZIF0045P001C01CS(CHIPS)':
 'DDR2_SA_DQ9': CDS_PINID='DDR2_SA_DQ9';
NODE_NAME     J21 20
 '@S9S_MB_2U_LIB.S9S_MB_2U(SCH_1):PAGE102_I13@PURE_QUANTA.SCONN288_ADR50017P130CC(CHIPS)':
 'DQ9_A': CDS_PINID='DQ9_A';
NODE_NAME     J22 20
 '@S9S_MB_2U_LIB.S9S_MB_2U(SCH_1):PAGE103_I51@PURE_QUANTA.SCONN288_ADR50017P087CC(CHIPS)':
 'DQ9_A': CDS_PINID='DQ9_A';
NET_NAME
'M_C_CPU1_SA_DQS_DN<0>'
 '@S9S_MB_2U_LIB.S9S_MB_2U(SCH_1):M_C_CPU1_SA_DQS_DN'<0>:
 C_SIGNAL='@s9s_mb_2u_lib.s9s_mb_2u(sch_1):m_c_cpu1_sa_dqs_dn(0)';
NODE_NAME     U1 R76
 '@S9S_MB_2U_LIB.S9S_MB_2U(SCH_1):PAGE53_I91@PURE_QUANTA.SOCKET4677_AZIF0045P001C01CS(CHIPS)':
 'DDR2_SA_DQS_DN0': CDS_PINID='DDR2_SA_DQS_DN0';
NODE_NAME     J21 12
 '@S9S_MB_2U_LIB.S9S_MB_2U(SCH_1):PAGE102_I178@PURE_QUANTA.SCONN288_ADR50017P130CC(CHIPS)':
 'DQS0_A_C': CDS_PINID='DQS0_A_C';
NODE_NAME     J22 12
 '@S9S_MB_2U_LIB.S9S_MB_2U(SCH_1):PAGE103_I178@PURE_QUANTA.SCONN288_ADR50017P087CC(CHIPS)':
 'DQS0_A_C': CDS_PINID='DQS0_A_C';
NET_NAME
'M_C_CPU1_SA_DQS_DN<1>'
 '@S9S_MB_2U_LIB.S9S_MB_2U(SCH_1):M_C_CPU1_SA_DQS_DN'<1>:
 C_SIGNAL='@s9s_mb_2u_lib.s9s_mb_2u(sch_1):m_c_cpu1_sa_dqs_dn(1)';
NODE_NAME     U1 AB67
 '@S9S_MB_2U_LIB.S9S_MB_2U(SCH_1):PAGE53_I91@PURE_QUANTA.SOCKET4677_AZIF0045P001C01CS(CHIPS)':
 'DDR2_SA_DQS_DN1': CDS_PINID='DDR2_SA_DQS_DN1';
NODE_NAME     J21 23
 '@S9S_MB_2U_LIB.S9S_MB_2U(SCH_1):PAGE102_I178@PURE_QUANTA.SCONN288_ADR50017P130CC(CHIPS)':
 'DQS1_A_C': CDS_PINID='DQS1_A_C';
NODE_NAME     J22 23
 '@S9S_MB_2U_LIB.S9S_MB_2U(SCH_1):PAGE103_I178@PURE_QUANTA.SCONN288_ADR50017P087CC(CHIPS)':
 'DQS1_A_C': CDS_PINID='DQS1_A_C';
NET_NAME
'M_C_CPU1_SA_DQS_DN<2>'
 '@S9S_MB_2U_LIB.S9S_MB_2U(SCH_1):M_C_CPU1_SA_DQS_DN'<2>:
 C_SIGNAL='@s9s_mb_2u_lib.s9s_mb_2u(sch_1):m_c_cpu1_sa_dqs_dn(2)';
NODE_NAME     U1 R64
 '@S9S_MB_2U_LIB.S9S_MB_2U(SCH_1):PAGE53_I91@PURE_QUANTA.SOCKET4677_AZIF0045P001C01CS(CHIPS)':
 'DDR2_SA_DQS_DN2': CDS_PINID='DDR2_SA_DQS_DN2';
NODE_NAME     J21 34
 '@S9S_MB_2U_LIB.S9S_MB_2U(SCH_1):PAGE102_I178@PURE_QUANTA.SCONN288_ADR50017P130CC(CHIPS)':
 'DQS2_A_C': CDS_PINID='DQS2_A_C';
NODE_NAME     J22 34
 '@S9S_MB_2U_LIB.S9S_MB_2U(SCH_1):PAGE103_I178@PURE_QUANTA.SCONN288_ADR50017P087CC(CHIPS)':
 'DQS2_A_C': CDS_PINID='DQS2_A_C';
NET_NAME
'M_C_CPU1_SA_DQS_DN<3>'
 '@S9S_MB_2U_LIB.S9S_MB_2U(SCH_1):M_C_CPU1_SA_DQS_DN'<3>:
 C_SIGNAL='@s9s_mb_2u_lib.s9s_mb_2u(sch_1):m_c_cpu1_sa_dqs_dn(3)';
NODE_NAME     U1 AB61
 '@S9S_MB_2U_LIB.S9S_MB_2U(SCH_1):PAGE53_I91@PURE_QUANTA.SOCKET4677_AZIF0045P001C01CS(CHIPS)':
 'DDR2_SA_DQS_DN3': CDS_PINID='DDR2_SA_DQS_DN3';
NODE_NAME     J21 45
 '@S9S_MB_2U_LIB.S9S_MB_2U(SCH_1):PAGE102_I178@PURE_QUANTA.SCONN288_ADR50017P130CC(CHIPS)':
 'DQS3_A_C': CDS_PINID='DQS3_A_C';
NODE_NAME     J22 45
 '@S9S_MB_2U_LIB.S9S_MB_2U(SCH_1):PAGE103_I178@PURE_QUANTA.SCONN288_ADR50017P087CC(CHIPS)':
 'DQS3_A_C': CDS_PINID='DQS3_A_C';
NET_NAME
'M_C_CPU1_SA_DQS_DN<4>'
 '@S9S_MB_2U_LIB.S9S_MB_2U(SCH_1):M_C_CPU1_SA_DQS_DN'<4>:
 C_SIGNAL='@s9s_mb_2u_lib.s9s_mb_2u(sch_1):m_c_cpu1_sa_dqs_dn(4)';
NODE_NAME     U1 AD55
 '@S9S_MB_2U_LIB.S9S_MB_2U(SCH_1):PAGE53_I91@PURE_QUANTA.SOCKET4677_AZIF0045P001C01CS(CHIPS)':
 'DDR2_SA_DQS_DN4': CDS_PINID='DDR2_SA_DQS_DN4';
NODE_NAME     J21 56
 '@S9S_MB_2U_LIB.S9S_MB_2U(SCH_1):PAGE102_I178@PURE_QUANTA.SCONN288_ADR50017P130CC(CHIPS)':
 'DQS4_A_C': CDS_PINID='DQS4_A_C';
NODE_NAME     J22 56
 '@S9S_MB_2U_LIB.S9S_MB_2U(SCH_1):PAGE103_I178@PURE_QUANTA.SCONN288_ADR50017P087CC(CHIPS)':
 'DQS4_A_C': CDS_PINID='DQS4_A_C';
NET_NAME
'M_C_CPU1_SA_DQS_DN<5>'
 '@S9S_MB_2U_LIB.S9S_MB_2U(SCH_1):M_C_CPU1_SA_DQS_DN'<5>:
 C_SIGNAL='@s9s_mb_2u_lib.s9s_mb_2u(sch_1):m_c_cpu1_sa_dqs_dn(5)';
NODE_NAME     U1 W76
 '@S9S_MB_2U_LIB.S9S_MB_2U(SCH_1):PAGE53_I91@PURE_QUANTA.SOCKET4677_AZIF0045P001C01CS(CHIPS)':
 'DDR2_SA_DQS_DN5': CDS_PINID='DDR2_SA_DQS_DN5';
NODE_NAME     J21 156
 '@S9S_MB_2U_LIB.S9S_MB_2U(SCH_1):PAGE102_I178@PURE_QUANTA.SCONN288_ADR50017P130CC(CHIPS)':
 'DQS5_A_C||TDQS5_A_C||DQS5_A_T||TDQS5_A_T': CDS_PINID='\dqs5_a_c||tdqs5_a_c||dqs5_a_t||tdqs5_a_t\';
NODE_NAME     J22 156
 '@S9S_MB_2U_LIB.S9S_MB_2U(SCH_1):PAGE103_I178@PURE_QUANTA.SCONN288_ADR50017P087CC(CHIPS)':
 'DQS5_A_C||TDQS5_A_C||DQS5_A_T||TDQS5_A_T': CDS_PINID='\dqs5_a_c||tdqs5_a_c||dqs5_a_t||tdqs5_a_t\';
NET_NAME
'M_C_CPU1_SA_DQS_DN<6>'
 '@S9S_MB_2U_LIB.S9S_MB_2U(SCH_1):M_C_CPU1_SA_DQS_DN'<6>:
 C_SIGNAL='@s9s_mb_2u_lib.s9s_mb_2u(sch_1):m_c_cpu1_sa_dqs_dn(6)';
NODE_NAME     U1 AH67
 '@S9S_MB_2U_LIB.S9S_MB_2U(SCH_1):PAGE53_I91@PURE_QUANTA.SOCKET4677_AZIF0045P001C01CS(CHIPS)':
 'DDR2_SA_DQS_DN6': CDS_PINID='DDR2_SA_DQS_DN6';
NODE_NAME     J21 167
 '@S9S_MB_2U_LIB.S9S_MB_2U(SCH_1):PAGE102_I178@PURE_QUANTA.SCONN288_ADR50017P130CC(CHIPS)':
 'DQS6_A_C||TDQS6_A_C||DQS6_A_T||TDQS6_A_T': CDS_PINID='\dqs6_a_c||tdqs6_a_c||dqs6_a_t||tdqs6_a_t\';
NODE_NAME     J22 167
 '@S9S_MB_2U_LIB.S9S_MB_2U(SCH_1):PAGE103_I178@PURE_QUANTA.SCONN288_ADR50017P087CC(CHIPS)':
 'DQS6_A_C||TDQS6_A_C||DQS6_A_T||TDQS6_A_T': CDS_PINID='\dqs6_a_c||tdqs6_a_c||dqs6_a_t||tdqs6_a_t\';
NET_NAME
'M_C_CPU1_SA_DQS_DN<7>'
 '@S9S_MB_2U_LIB.S9S_MB_2U(SCH_1):M_C_CPU1_SA_DQS_DN'<7>:
 C_SIGNAL='@s9s_mb_2u_lib.s9s_mb_2u(sch_1):m_c_cpu1_sa_dqs_dn(7)';
NODE_NAME     U1 AA64
 '@S9S_MB_2U_LIB.S9S_MB_2U(SCH_1):PAGE53_I91@PURE_QUANTA.SOCKET4677_AZIF0045P001C01CS(CHIPS)':
 'DDR2_SA_DQS_DN7': CDS_PINID='DDR2_SA_DQS_DN7';
NODE_NAME     J21 178
 '@S9S_MB_2U_LIB.S9S_MB_2U(SCH_1):PAGE102_I178@PURE_QUANTA.SCONN288_ADR50017P130CC(CHIPS)':
 'DQS7_A_C||TDQS7_A_C': CDS_PINID='\dqs7_a_c||tdqs7_a_c\';
NODE_NAME     J22 178
 '@S9S_MB_2U_LIB.S9S_MB_2U(SCH_1):PAGE103_I178@PURE_QUANTA.SCONN288_ADR50017P087CC(CHIPS)':
 'DQS7_A_C||TDQS7_A_C': CDS_PINID='\dqs7_a_c||tdqs7_a_c\';
NET_NAME
'M_C_CPU1_SA_DQS_DN<8>'
 '@S9S_MB_2U_LIB.S9S_MB_2U(SCH_1):M_C_CPU1_SA_DQS_DN'<8>:
 C_SIGNAL='@s9s_mb_2u_lib.s9s_mb_2u(sch_1):m_c_cpu1_sa_dqs_dn(8)';
NODE_NAME     U1 AF61
 '@S9S_MB_2U_LIB.S9S_MB_2U(SCH_1):PAGE53_I91@PURE_QUANTA.SOCKET4677_AZIF0045P001C01CS(CHIPS)':
 'DDR2_SA_DQS_DN8': CDS_PINID='DDR2_SA_DQS_DN8';
NODE_NAME     J21 189
 '@S9S_MB_2U_LIB.S9S_MB_2U(SCH_1):PAGE102_I178@PURE_QUANTA.SCONN288_ADR50017P130CC(CHIPS)':
 'DQS8_A_C||TDQS8_A_C': CDS_PINID='\dqs8_a_c||tdqs8_a_c\';
NODE_NAME     J22 189
 '@S9S_MB_2U_LIB.S9S_MB_2U(SCH_1):PAGE103_I178@PURE_QUANTA.SCONN288_ADR50017P087CC(CHIPS)':
 'DQS8_A_C||TDQS8_A_C': CDS_PINID='\dqs8_a_c||tdqs8_a_c\';
NET_NAME
'M_C_CPU1_SA_DQS_DN<9>'
 '@S9S_MB_2U_LIB.S9S_MB_2U(SCH_1):M_C_CPU1_SA_DQS_DN'<9>:
 C_SIGNAL='@s9s_mb_2u_lib.s9s_mb_2u(sch_1):m_c_cpu1_sa_dqs_dn(9)';
NODE_NAME     U1 AH55
 '@S9S_MB_2U_LIB.S9S_MB_2U(SCH_1):PAGE53_I91@PURE_QUANTA.SOCKET4677_AZIF0045P001C01CS(CHIPS)':
 'DDR2_SA_DQS_DN9': CDS_PINID='DDR2_SA_DQS_DN9';
NODE_NAME     J21 200
 '@S9S_MB_2U_LIB.S9S_MB_2U(SCH_1):PAGE102_I178@PURE_QUANTA.SCONN288_ADR50017P130CC(CHIPS)':
 'DQS9_A_C||TDQS9_A_C': CDS_PINID='\dqs9_a_c||tdqs9_a_c\';
NODE_NAME     J22 200
 '@S9S_MB_2U_LIB.S9S_MB_2U(SCH_1):PAGE103_I178@PURE_QUANTA.SCONN288_ADR50017P087CC(CHIPS)':
 'DQS9_A_C||TDQS9_A_C': CDS_PINID='\dqs9_a_c||tdqs9_a_c\';
NET_NAME
'M_C_CPU1_SA_DQS_DP<0>'
 '@S9S_MB_2U_LIB.S9S_MB_2U(SCH_1):M_C_CPU1_SA_DQS_DP'<0>:
 C_SIGNAL='@s9s_mb_2u_lib.s9s_mb_2u(sch_1):m_c_cpu1_sa_dqs_dp(0)';
NODE_NAME     U1 U76
 '@S9S_MB_2U_LIB.S9S_MB_2U(SCH_1):PAGE53_I91@PURE_QUANTA.SOCKET4677_AZIF0045P001C01CS(CHIPS)':
 'DDR2_SA_DQS_DP0': CDS_PINID='DDR2_SA_DQS_DP0';
NODE_NAME     J21 11
 '@S9S_MB_2U_LIB.S9S_MB_2U(SCH_1):PAGE102_I178@PURE_QUANTA.SCONN288_ADR50017P130CC(CHIPS)':
 'DQS0_A_T': CDS_PINID='DQS0_A_T';
NODE_NAME     J22 11
 '@S9S_MB_2U_LIB.S9S_MB_2U(SCH_1):PAGE103_I178@PURE_QUANTA.SCONN288_ADR50017P087CC(CHIPS)':
 'DQS0_A_T': CDS_PINID='DQS0_A_T';
NET_NAME
'M_C_CPU1_SA_DQS_DP<1>'
 '@S9S_MB_2U_LIB.S9S_MB_2U(SCH_1):M_C_CPU1_SA_DQS_DP'<1>:
 C_SIGNAL='@s9s_mb_2u_lib.s9s_mb_2u(sch_1):m_c_cpu1_sa_dqs_dp(1)';
NODE_NAME     U1 AD67
 '@S9S_MB_2U_LIB.S9S_MB_2U(SCH_1):PAGE53_I91@PURE_QUANTA.SOCKET4677_AZIF0045P001C01CS(CHIPS)':
 'DDR2_SA_DQS_DP1': CDS_PINID='DDR2_SA_DQS_DP1';
NODE_NAME     J21 22
 '@S9S_MB_2U_LIB.S9S_MB_2U(SCH_1):PAGE102_I178@PURE_QUANTA.SCONN288_ADR50017P130CC(CHIPS)':
 'DQS1_A_T': CDS_PINID='DQS1_A_T';
NODE_NAME     J22 22
 '@S9S_MB_2U_LIB.S9S_MB_2U(SCH_1):PAGE103_I178@PURE_QUANTA.SCONN288_ADR50017P087CC(CHIPS)':
 'DQS1_A_T': CDS_PINID='DQS1_A_T';
NET_NAME
'M_C_CPU1_SA_DQS_DP<2>'
 '@S9S_MB_2U_LIB.S9S_MB_2U(SCH_1):M_C_CPU1_SA_DQS_DP'<2>:
 C_SIGNAL='@s9s_mb_2u_lib.s9s_mb_2u(sch_1):m_c_cpu1_sa_dqs_dp(2)';
NODE_NAME     U1 U64
 '@S9S_MB_2U_LIB.S9S_MB_2U(SCH_1):PAGE53_I91@PURE_QUANTA.SOCKET4677_AZIF0045P001C01CS(CHIPS)':
 'DDR2_SA_DQS_DP2': CDS_PINID='DDR2_SA_DQS_DP2';
NODE_NAME     J21 33
 '@S9S_MB_2U_LIB.S9S_MB_2U(SCH_1):PAGE102_I178@PURE_QUANTA.SCONN288_ADR50017P130CC(CHIPS)':
 'DQS2_A_T': CDS_PINID='DQS2_A_T';
NODE_NAME     J22 33
 '@S9S_MB_2U_LIB.S9S_MB_2U(SCH_1):PAGE103_I178@PURE_QUANTA.SCONN288_ADR50017P087CC(CHIPS)':
 'DQS2_A_T': CDS_PINID='DQS2_A_T';
NET_NAME
'M_C_CPU1_SA_DQS_DP<3>'
 '@S9S_MB_2U_LIB.S9S_MB_2U(SCH_1):M_C_CPU1_SA_DQS_DP'<3>:
 C_SIGNAL='@s9s_mb_2u_lib.s9s_mb_2u(sch_1):m_c_cpu1_sa_dqs_dp(3)';
NODE_NAME     U1 AD61
 '@S9S_MB_2U_LIB.S9S_MB_2U(SCH_1):PAGE53_I91@PURE_QUANTA.SOCKET4677_AZIF0045P001C01CS(CHIPS)':
 'DDR2_SA_DQS_DP3': CDS_PINID='DDR2_SA_DQS_DP3';
NODE_NAME     J21 44
 '@S9S_MB_2U_LIB.S9S_MB_2U(SCH_1):PAGE102_I178@PURE_QUANTA.SCONN288_ADR50017P130CC(CHIPS)':
 'DQS3_A_T': CDS_PINID='DQS3_A_T';
NODE_NAME     J22 44
 '@S9S_MB_2U_LIB.S9S_MB_2U(SCH_1):PAGE103_I178@PURE_QUANTA.SCONN288_ADR50017P087CC(CHIPS)':
 'DQS3_A_T': CDS_PINID='DQS3_A_T';
NET_NAME
'M_C_CPU1_SA_DQS_DP<4>'
 '@S9S_MB_2U_LIB.S9S_MB_2U(SCH_1):M_C_CPU1_SA_DQS_DP'<4>:
 C_SIGNAL='@s9s_mb_2u_lib.s9s_mb_2u(sch_1):m_c_cpu1_sa_dqs_dp(4)';
NODE_NAME     U1 AB55
 '@S9S_MB_2U_LIB.S9S_MB_2U(SCH_1):PAGE53_I91@PURE_QUANTA.SOCKET4677_AZIF0045P001C01CS(CHIPS)':
 'DDR2_SA_DQS_DP4': CDS_PINID='DDR2_SA_DQS_DP4';
NODE_NAME     J21 55
 '@S9S_MB_2U_LIB.S9S_MB_2U(SCH_1):PAGE102_I178@PURE_QUANTA.SCONN288_ADR50017P130CC(CHIPS)':
 'DQS4_A_T': CDS_PINID='DQS4_A_T';
NODE_NAME     J22 55
 '@S9S_MB_2U_LIB.S9S_MB_2U(SCH_1):PAGE103_I178@PURE_QUANTA.SCONN288_ADR50017P087CC(CHIPS)':
 'DQS4_A_T': CDS_PINID='DQS4_A_T';
NET_NAME
'M_C_CPU1_SA_DQS_DP<5>'
 '@S9S_MB_2U_LIB.S9S_MB_2U(SCH_1):M_C_CPU1_SA_DQS_DP'<5>:
 C_SIGNAL='@s9s_mb_2u_lib.s9s_mb_2u(sch_1):m_c_cpu1_sa_dqs_dp(5)';
NODE_NAME     U1 AA76
 '@S9S_MB_2U_LIB.S9S_MB_2U(SCH_1):PAGE53_I91@PURE_QUANTA.SOCKET4677_AZIF0045P001C01CS(CHIPS)':
 'DDR2_SA_DQS_DP5': CDS_PINID='DDR2_SA_DQS_DP5';
NODE_NAME     J21 157
 '@S9S_MB_2U_LIB.S9S_MB_2U(SCH_1):PAGE102_I178@PURE_QUANTA.SCONN288_ADR50017P130CC(CHIPS)':
 'DQS5_A_T||TDQS5_A_T': CDS_PINID='\dqs5_a_t||tdqs5_a_t\';
NODE_NAME     J22 157
 '@S9S_MB_2U_LIB.S9S_MB_2U(SCH_1):PAGE103_I178@PURE_QUANTA.SCONN288_ADR50017P087CC(CHIPS)':
 'DQS5_A_T||TDQS5_A_T': CDS_PINID='\dqs5_a_t||tdqs5_a_t\';
NET_NAME
'M_C_CPU1_SA_DQS_DP<6>'
 '@S9S_MB_2U_LIB.S9S_MB_2U(SCH_1):M_C_CPU1_SA_DQS_DP'<6>:
 C_SIGNAL='@s9s_mb_2u_lib.s9s_mb_2u(sch_1):m_c_cpu1_sa_dqs_dp(6)';
NODE_NAME     U1 AF67
 '@S9S_MB_2U_LIB.S9S_MB_2U(SCH_1):PAGE53_I91@PURE_QUANTA.SOCKET4677_AZIF0045P001C01CS(CHIPS)':
 'DDR2_SA_DQS_DP6': CDS_PINID='DDR2_SA_DQS_DP6';
NODE_NAME     J21 168
 '@S9S_MB_2U_LIB.S9S_MB_2U(SCH_1):PAGE102_I178@PURE_QUANTA.SCONN288_ADR50017P130CC(CHIPS)':
 'DQS6_A_T||TDQS6_A_T': CDS_PINID='\dqs6_a_t||tdqs6_a_t\';
NODE_NAME     J22 168
 '@S9S_MB_2U_LIB.S9S_MB_2U(SCH_1):PAGE103_I178@PURE_QUANTA.SCONN288_ADR50017P087CC(CHIPS)':
 'DQS6_A_T||TDQS6_A_T': CDS_PINID='\dqs6_a_t||tdqs6_a_t\';
NET_NAME
'M_C_CPU1_SA_DQS_DP<7>'
 '@S9S_MB_2U_LIB.S9S_MB_2U(SCH_1):M_C_CPU1_SA_DQS_DP'<7>:
 C_SIGNAL='@s9s_mb_2u_lib.s9s_mb_2u(sch_1):m_c_cpu1_sa_dqs_dp(7)';
NODE_NAME     U1 W64
 '@S9S_MB_2U_LIB.S9S_MB_2U(SCH_1):PAGE53_I91@PURE_QUANTA.SOCKET4677_AZIF0045P001C01CS(CHIPS)':
 'DDR2_SA_DQS_DP7': CDS_PINID='DDR2_SA_DQS_DP7';
NODE_NAME     J21 179
 '@S9S_MB_2U_LIB.S9S_MB_2U(SCH_1):PAGE102_I178@PURE_QUANTA.SCONN288_ADR50017P130CC(CHIPS)':
 'DQS7_A_T||TDQS7_A_T': CDS_PINID='\dqs7_a_t||tdqs7_a_t\';
NODE_NAME     J22 179
 '@S9S_MB_2U_LIB.S9S_MB_2U(SCH_1):PAGE103_I178@PURE_QUANTA.SCONN288_ADR50017P087CC(CHIPS)':
 'DQS7_A_T||TDQS7_A_T': CDS_PINID='\dqs7_a_t||tdqs7_a_t\';
NET_NAME
'M_C_CPU1_SA_DQS_DP<8>'
 '@S9S_MB_2U_LIB.S9S_MB_2U(SCH_1):M_C_CPU1_SA_DQS_DP'<8>:
 C_SIGNAL='@s9s_mb_2u_lib.s9s_mb_2u(sch_1):m_c_cpu1_sa_dqs_dp(8)';
NODE_NAME     U1 AH61
 '@S9S_MB_2U_LIB.S9S_MB_2U(SCH_1):PAGE53_I91@PURE_QUANTA.SOCKET4677_AZIF0045P001C01CS(CHIPS)':
 'DDR2_SA_DQS_DP8': CDS_PINID='DDR2_SA_DQS_DP8';
NODE_NAME     J21 190
 '@S9S_MB_2U_LIB.S9S_MB_2U(SCH_1):PAGE102_I178@PURE_QUANTA.SCONN288_ADR50017P130CC(CHIPS)':
 'DQS8_A_T||TDQS8_A_T': CDS_PINID='\dqs8_a_t||tdqs8_a_t\';
NODE_NAME     J22 190
 '@S9S_MB_2U_LIB.S9S_MB_2U(SCH_1):PAGE103_I178@PURE_QUANTA.SCONN288_ADR50017P087CC(CHIPS)':
 'DQS8_A_T||TDQS8_A_T': CDS_PINID='\dqs8_a_t||tdqs8_a_t\';
NET_NAME
'M_C_CPU1_SA_DQS_DP<9>'
 '@S9S_MB_2U_LIB.S9S_MB_2U(SCH_1):M_C_CPU1_SA_DQS_DP'<9>:
 C_SIGNAL='@s9s_mb_2u_lib.s9s_mb_2u(sch_1):m_c_cpu1_sa_dqs_dp(9)';
NODE_NAME     U1 AF55
 '@S9S_MB_2U_LIB.S9S_MB_2U(SCH_1):PAGE53_I91@PURE_QUANTA.SOCKET4677_AZIF0045P001C01CS(CHIPS)':
 'DDR2_SA_DQS_DP9': CDS_PINID='DDR2_SA_DQS_DP9';
NODE_NAME     J21 201
 '@S9S_MB_2U_LIB.S9S_MB_2U(SCH_1):PAGE102_I178@PURE_QUANTA.SCONN288_ADR50017P130CC(CHIPS)':
 'DQS9_A_T||TDQS9_A_T': CDS_PINID='\dqs9_a_t||tdqs9_a_t\';
NODE_NAME     J22 201
 '@S9S_MB_2U_LIB.S9S_MB_2U(SCH_1):PAGE103_I178@PURE_QUANTA.SCONN288_ADR50017P087CC(CHIPS)':
 'DQS9_A_T||TDQS9_A_T': CDS_PINID='\dqs9_a_t||tdqs9_a_t\';
NET_NAME
'M_C_CPU1_SA_PAR'
 '@S9S_MB_2U_LIB.S9S_MB_2U(SCH_1):M_C_CPU1_SA_PAR':
 C_SIGNAL='@s9s_mb_2u_lib.s9s_mb_2u(sch_1):m_c_cpu1_sa_par';
NODE_NAME     U1 T47
 '@S9S_MB_2U_LIB.S9S_MB_2U(SCH_1):PAGE53_I91@PURE_QUANTA.SOCKET4677_AZIF0045P001C01CS(CHIPS)':
 'DDR2_SA_PAR': CDS_PINID='DDR2_SA_PAR';
NODE_NAME     J21 74
 '@S9S_MB_2U_LIB.S9S_MB_2U(SCH_1):PAGE102_I13@PURE_QUANTA.SCONN288_ADR50017P130CC(CHIPS)':
 'PAR_A': CDS_PINID='PAR_A';
NODE_NAME     J22 74
 '@S9S_MB_2U_LIB.S9S_MB_2U(SCH_1):PAGE103_I51@PURE_QUANTA.SCONN288_ADR50017P087CC(CHIPS)':
 'PAR_A': CDS_PINID='PAR_A';
NET_NAME
'M_C_CPU1_SA_RSP<0>'
 '@S9S_MB_2U_LIB.S9S_MB_2U(SCH_1):M_C_CPU1_SA_RSP'<0>:
 C_SIGNAL='@s9s_mb_2u_lib.s9s_mb_2u(sch_1):m_c_cpu1_sa_rsp(0)';
NODE_NAME     U1 AC48
 '@S9S_MB_2U_LIB.S9S_MB_2U(SCH_1):PAGE53_I91@PURE_QUANTA.SOCKET4677_AZIF0045P001C01CS(CHIPS)':
 'DDR2_A_RSP0': CDS_PINID='DDR2_A_RSP0';
NODE_NAME     J21 86
 '@S9S_MB_2U_LIB.S9S_MB_2U(SCH_1):PAGE102_I13@PURE_QUANTA.SCONN288_ADR50017P130CC(CHIPS)':
 'LBD||RSP_A_N': CDS_PINID='\lbd||rsp_a_n\';
NET_NAME
'M_C_CPU1_SA_RSP<1>'
 '@S9S_MB_2U_LIB.S9S_MB_2U(SCH_1):M_C_CPU1_SA_RSP'<1>:
 C_SIGNAL='@s9s_mb_2u_lib.s9s_mb_2u(sch_1):m_c_cpu1_sa_rsp(1)';
NODE_NAME     U1 AD47
 '@S9S_MB_2U_LIB.S9S_MB_2U(SCH_1):PAGE53_I91@PURE_QUANTA.SOCKET4677_AZIF0045P001C01CS(CHIPS)':
 'DDR2_A_RSP1': CDS_PINID='DDR2_A_RSP1';
NODE_NAME     J22 86
 '@S9S_MB_2U_LIB.S9S_MB_2U(SCH_1):PAGE103_I51@PURE_QUANTA.SCONN288_ADR50017P087CC(CHIPS)':
 'LBD||RSP_A_N': CDS_PINID='\lbd||rsp_a_n\';
NET_NAME
'M_C_CPU1_SB_CA<0>'
 '@S9S_MB_2U_LIB.S9S_MB_2U(SCH_1):M_C_CPU1_SB_CA'<0>:
 C_SIGNAL='@s9s_mb_2u_lib.s9s_mb_2u(sch_1):m_c_cpu1_sb_ca(0)';
NODE_NAME     U1 W48
 '@S9S_MB_2U_LIB.S9S_MB_2U(SCH_1):PAGE53_I91@PURE_QUANTA.SOCKET4677_AZIF0045P001C01CS(CHIPS)':
 'DDR2_SB_CA0': CDS_PINID='DDR2_SB_CA0';
NODE_NAME     J21 76
 '@S9S_MB_2U_LIB.S9S_MB_2U(SCH_1):PAGE102_I13@PURE_QUANTA.SCONN288_ADR50017P130CC(CHIPS)':
 'CA0_B': CDS_PINID='CA0_B';
NODE_NAME     J22 76
 '@S9S_MB_2U_LIB.S9S_MB_2U(SCH_1):PAGE103_I51@PURE_QUANTA.SCONN288_ADR50017P087CC(CHIPS)':
 'CA0_B': CDS_PINID='CA0_B';
NET_NAME
'M_C_CPU1_SB_CA<1>'
 '@S9S_MB_2U_LIB.S9S_MB_2U(SCH_1):M_C_CPU1_SB_CA'<1>:
 C_SIGNAL='@s9s_mb_2u_lib.s9s_mb_2u(sch_1):m_c_cpu1_sb_ca(1)';
NODE_NAME     U1 Y47
 '@S9S_MB_2U_LIB.S9S_MB_2U(SCH_1):PAGE53_I91@PURE_QUANTA.SOCKET4677_AZIF0045P001C01CS(CHIPS)':
 'DDR2_SB_CA1': CDS_PINID='DDR2_SB_CA1';
NODE_NAME     J21 221
 '@S9S_MB_2U_LIB.S9S_MB_2U(SCH_1):PAGE102_I13@PURE_QUANTA.SCONN288_ADR50017P130CC(CHIPS)':
 'CA1_B': CDS_PINID='CA1_B';
NODE_NAME     J22 221
 '@S9S_MB_2U_LIB.S9S_MB_2U(SCH_1):PAGE103_I51@PURE_QUANTA.SCONN288_ADR50017P087CC(CHIPS)':
 'CA1_B': CDS_PINID='CA1_B';
NET_NAME
'M_C_CPU1_SB_CA<2>'
 '@S9S_MB_2U_LIB.S9S_MB_2U(SCH_1):M_C_CPU1_SB_CA'<2>:
 C_SIGNAL='@s9s_mb_2u_lib.s9s_mb_2u(sch_1):m_c_cpu1_sb_ca(2)';
NODE_NAME     U1 U41
 '@S9S_MB_2U_LIB.S9S_MB_2U(SCH_1):PAGE53_I91@PURE_QUANTA.SOCKET4677_AZIF0045P001C01CS(CHIPS)':
 'DDR2_SB_CA2': CDS_PINID='DDR2_SB_CA2';
NODE_NAME     J21 78
 '@S9S_MB_2U_LIB.S9S_MB_2U(SCH_1):PAGE102_I13@PURE_QUANTA.SCONN288_ADR50017P130CC(CHIPS)':
 'CA2_B': CDS_PINID='CA2_B';
NODE_NAME     J22 78
 '@S9S_MB_2U_LIB.S9S_MB_2U(SCH_1):PAGE103_I51@PURE_QUANTA.SCONN288_ADR50017P087CC(CHIPS)':
 'CA2_B': CDS_PINID='CA2_B';
NET_NAME
'M_C_CPU1_SB_CA<3>'
 '@S9S_MB_2U_LIB.S9S_MB_2U(SCH_1):M_C_CPU1_SB_CA'<3>:
 C_SIGNAL='@s9s_mb_2u_lib.s9s_mb_2u(sch_1):m_c_cpu1_sb_ca(3)';
NODE_NAME     U1 W41
 '@S9S_MB_2U_LIB.S9S_MB_2U(SCH_1):PAGE53_I91@PURE_QUANTA.SOCKET4677_AZIF0045P001C01CS(CHIPS)':
 'DDR2_SB_CA3': CDS_PINID='DDR2_SB_CA3';
NODE_NAME     J21 223
 '@S9S_MB_2U_LIB.S9S_MB_2U(SCH_1):PAGE102_I13@PURE_QUANTA.SCONN288_ADR50017P130CC(CHIPS)':
 'CA3_B': CDS_PINID='CA3_B';
NODE_NAME     J22 223
 '@S9S_MB_2U_LIB.S9S_MB_2U(SCH_1):PAGE103_I51@PURE_QUANTA.SCONN288_ADR50017P087CC(CHIPS)':
 'CA3_B': CDS_PINID='CA3_B';
NET_NAME
'M_C_CPU1_SB_CA<4>'
 '@S9S_MB_2U_LIB.S9S_MB_2U(SCH_1):M_C_CPU1_SB_CA'<4>:
 C_SIGNAL='@s9s_mb_2u_lib.s9s_mb_2u(sch_1):m_c_cpu1_sb_ca(4)';
NODE_NAME     U1 T40
 '@S9S_MB_2U_LIB.S9S_MB_2U(SCH_1):PAGE53_I91@PURE_QUANTA.SOCKET4677_AZIF0045P001C01CS(CHIPS)':
 'DDR2_SB_CA4': CDS_PINID='DDR2_SB_CA4';
NODE_NAME     J21 80
 '@S9S_MB_2U_LIB.S9S_MB_2U(SCH_1):PAGE102_I13@PURE_QUANTA.SCONN288_ADR50017P130CC(CHIPS)':
 'CA4_B': CDS_PINID='CA4_B';
NODE_NAME     J22 80
 '@S9S_MB_2U_LIB.S9S_MB_2U(SCH_1):PAGE103_I51@PURE_QUANTA.SCONN288_ADR50017P087CC(CHIPS)':
 'CA4_B': CDS_PINID='CA4_B';
NET_NAME
'M_C_CPU1_SB_CA<5>'
 '@S9S_MB_2U_LIB.S9S_MB_2U(SCH_1):M_C_CPU1_SB_CA'<5>:
 C_SIGNAL='@s9s_mb_2u_lib.s9s_mb_2u(sch_1):m_c_cpu1_sb_ca(5)';
NODE_NAME     U1 Y40
 '@S9S_MB_2U_LIB.S9S_MB_2U(SCH_1):PAGE53_I91@PURE_QUANTA.SOCKET4677_AZIF0045P001C01CS(CHIPS)':
 'DDR2_SB_CA5': CDS_PINID='DDR2_SB_CA5';
NODE_NAME     J21 225
 '@S9S_MB_2U_LIB.S9S_MB_2U(SCH_1):PAGE102_I13@PURE_QUANTA.SCONN288_ADR50017P130CC(CHIPS)':
 'CA5_B': CDS_PINID='CA5_B';
NODE_NAME     J22 225
 '@S9S_MB_2U_LIB.S9S_MB_2U(SCH_1):PAGE103_I51@PURE_QUANTA.SCONN288_ADR50017P087CC(CHIPS)':
 'CA5_B': CDS_PINID='CA5_B';
NET_NAME
'M_C_CPU1_SB_CA<6>'
 '@S9S_MB_2U_LIB.S9S_MB_2U(SCH_1):M_C_CPU1_SB_CA'<6>:
 C_SIGNAL='@s9s_mb_2u_lib.s9s_mb_2u(sch_1):m_c_cpu1_sb_ca(6)';
NODE_NAME     U1 R39
 '@S9S_MB_2U_LIB.S9S_MB_2U(SCH_1):PAGE53_I91@PURE_QUANTA.SOCKET4677_AZIF0045P001C01CS(CHIPS)':
 'DDR2_SB_CA6': CDS_PINID='DDR2_SB_CA6';
NODE_NAME     J21 82
 '@S9S_MB_2U_LIB.S9S_MB_2U(SCH_1):PAGE102_I13@PURE_QUANTA.SCONN288_ADR50017P130CC(CHIPS)':
 'CA6_B': CDS_PINID='CA6_B';
NODE_NAME     J22 82
 '@S9S_MB_2U_LIB.S9S_MB_2U(SCH_1):PAGE103_I51@PURE_QUANTA.SCONN288_ADR50017P087CC(CHIPS)':
 'CA6_B': CDS_PINID='CA6_B';
NET_NAME
'M_C_CPU1_SB_CB<0>'
 '@S9S_MB_2U_LIB.S9S_MB_2U(SCH_1):M_C_CPU1_SB_CB'<0>:
 C_SIGNAL='@s9s_mb_2u_lib.s9s_mb_2u(sch_1):m_c_cpu1_sb_cb(0)';
NODE_NAME     U1 T32
 '@S9S_MB_2U_LIB.S9S_MB_2U(SCH_1):PAGE53_I91@PURE_QUANTA.SOCKET4677_AZIF0045P001C01CS(CHIPS)':
 'DDR2_SB_ECC0': CDS_PINID='DDR2_SB_ECC0';
NODE_NAME     J21 96
 '@S9S_MB_2U_LIB.S9S_MB_2U(SCH_1):PAGE102_I13@PURE_QUANTA.SCONN288_ADR50017P130CC(CHIPS)':
 'CB0_B': CDS_PINID='CB0_B';
NODE_NAME     J22 96
 '@S9S_MB_2U_LIB.S9S_MB_2U(SCH_1):PAGE103_I51@PURE_QUANTA.SCONN288_ADR50017P087CC(CHIPS)':
 'CB0_B': CDS_PINID='CB0_B';
NET_NAME
'M_C_CPU1_SB_CB<1>'
 '@S9S_MB_2U_LIB.S9S_MB_2U(SCH_1):M_C_CPU1_SB_CB'<1>:
 C_SIGNAL='@s9s_mb_2u_lib.s9s_mb_2u(sch_1):m_c_cpu1_sb_cb(1)';
NODE_NAME     U1 U31
 '@S9S_MB_2U_LIB.S9S_MB_2U(SCH_1):PAGE53_I91@PURE_QUANTA.SOCKET4677_AZIF0045P001C01CS(CHIPS)':
 'DDR2_SB_ECC1': CDS_PINID='DDR2_SB_ECC1';
NODE_NAME     J21 98
 '@S9S_MB_2U_LIB.S9S_MB_2U(SCH_1):PAGE102_I13@PURE_QUANTA.SCONN288_ADR50017P130CC(CHIPS)':
 'CB1_B': CDS_PINID='CB1_B';
NODE_NAME     J22 98
 '@S9S_MB_2U_LIB.S9S_MB_2U(SCH_1):PAGE103_I51@PURE_QUANTA.SCONN288_ADR50017P087CC(CHIPS)':
 'CB1_B': CDS_PINID='CB1_B';
NET_NAME
'M_C_CPU1_SB_CB<2>'
 '@S9S_MB_2U_LIB.S9S_MB_2U(SCH_1):M_C_CPU1_SB_CB'<2>:
 C_SIGNAL='@s9s_mb_2u_lib.s9s_mb_2u(sch_1):m_c_cpu1_sb_cb(2)';
NODE_NAME     U1 Y32
 '@S9S_MB_2U_LIB.S9S_MB_2U(SCH_1):PAGE53_I91@PURE_QUANTA.SOCKET4677_AZIF0045P001C01CS(CHIPS)':
 'DDR2_SB_ECC2': CDS_PINID='DDR2_SB_ECC2';
NODE_NAME     J21 241
 '@S9S_MB_2U_LIB.S9S_MB_2U(SCH_1):PAGE102_I13@PURE_QUANTA.SCONN288_ADR50017P130CC(CHIPS)':
 'CB2_B': CDS_PINID='CB2_B';
NODE_NAME     J22 241
 '@S9S_MB_2U_LIB.S9S_MB_2U(SCH_1):PAGE103_I51@PURE_QUANTA.SCONN288_ADR50017P087CC(CHIPS)':
 'CB2_B': CDS_PINID='CB2_B';
NET_NAME
'M_C_CPU1_SB_CB<3>'
 '@S9S_MB_2U_LIB.S9S_MB_2U(SCH_1):M_C_CPU1_SB_CB'<3>:
 C_SIGNAL='@s9s_mb_2u_lib.s9s_mb_2u(sch_1):m_c_cpu1_sb_cb(3)';
NODE_NAME     U1 W31
 '@S9S_MB_2U_LIB.S9S_MB_2U(SCH_1):PAGE53_I91@PURE_QUANTA.SOCKET4677_AZIF0045P001C01CS(CHIPS)':
 'DDR2_SB_ECC3': CDS_PINID='DDR2_SB_ECC3';
NODE_NAME     J21 243
 '@S9S_MB_2U_LIB.S9S_MB_2U(SCH_1):PAGE102_I13@PURE_QUANTA.SCONN288_ADR50017P130CC(CHIPS)':
 'CB3_B': CDS_PINID='CB3_B';
NODE_NAME     J22 243
 '@S9S_MB_2U_LIB.S9S_MB_2U(SCH_1):PAGE103_I51@PURE_QUANTA.SCONN288_ADR50017P087CC(CHIPS)':
 'CB3_B': CDS_PINID='CB3_B';
NET_NAME
'M_C_CPU1_SB_CB<4>'
 '@S9S_MB_2U_LIB.S9S_MB_2U(SCH_1):M_C_CPU1_SB_CB'<4>:
 C_SIGNAL='@s9s_mb_2u_lib.s9s_mb_2u(sch_1):m_c_cpu1_sb_cb(4)';
NODE_NAME     U1 U35
 '@S9S_MB_2U_LIB.S9S_MB_2U(SCH_1):PAGE53_I91@PURE_QUANTA.SOCKET4677_AZIF0045P001C01CS(CHIPS)':
 'DDR2_SB_ECC4': CDS_PINID='DDR2_SB_ECC4';
NODE_NAME     J21 89
 '@S9S_MB_2U_LIB.S9S_MB_2U(SCH_1):PAGE102_I13@PURE_QUANTA.SCONN288_ADR50017P130CC(CHIPS)':
 'CB4_B': CDS_PINID='CB4_B';
NODE_NAME     J22 89
 '@S9S_MB_2U_LIB.S9S_MB_2U(SCH_1):PAGE103_I51@PURE_QUANTA.SCONN288_ADR50017P087CC(CHIPS)':
 'CB4_B': CDS_PINID='CB4_B';
NET_NAME
'M_C_CPU1_SB_CB<5>'
 '@S9S_MB_2U_LIB.S9S_MB_2U(SCH_1):M_C_CPU1_SB_CB'<5>:
 C_SIGNAL='@s9s_mb_2u_lib.s9s_mb_2u(sch_1):m_c_cpu1_sb_cb(5)';
NODE_NAME     U1 T34
 '@S9S_MB_2U_LIB.S9S_MB_2U(SCH_1):PAGE53_I91@PURE_QUANTA.SOCKET4677_AZIF0045P001C01CS(CHIPS)':
 'DDR2_SB_ECC5': CDS_PINID='DDR2_SB_ECC5';
NODE_NAME     J21 91
 '@S9S_MB_2U_LIB.S9S_MB_2U(SCH_1):PAGE102_I13@PURE_QUANTA.SCONN288_ADR50017P130CC(CHIPS)':
 'CB5_B': CDS_PINID='CB5_B';
NODE_NAME     J22 91
 '@S9S_MB_2U_LIB.S9S_MB_2U(SCH_1):PAGE103_I51@PURE_QUANTA.SCONN288_ADR50017P087CC(CHIPS)':
 'CB5_B': CDS_PINID='CB5_B';
NET_NAME
'M_C_CPU1_SB_CB<6>'
 '@S9S_MB_2U_LIB.S9S_MB_2U(SCH_1):M_C_CPU1_SB_CB'<6>:
 C_SIGNAL='@s9s_mb_2u_lib.s9s_mb_2u(sch_1):m_c_cpu1_sb_cb(6)';
NODE_NAME     U1 W35
 '@S9S_MB_2U_LIB.S9S_MB_2U(SCH_1):PAGE53_I91@PURE_QUANTA.SOCKET4677_AZIF0045P001C01CS(CHIPS)':
 'DDR2_SB_ECC6': CDS_PINID='DDR2_SB_ECC6';
NODE_NAME     J21 234
 '@S9S_MB_2U_LIB.S9S_MB_2U(SCH_1):PAGE102_I13@PURE_QUANTA.SCONN288_ADR50017P130CC(CHIPS)':
 'CB6_B': CDS_PINID='CB6_B';
NODE_NAME     J22 234
 '@S9S_MB_2U_LIB.S9S_MB_2U(SCH_1):PAGE103_I51@PURE_QUANTA.SCONN288_ADR50017P087CC(CHIPS)':
 'CB6_B': CDS_PINID='CB6_B';
NET_NAME
'M_C_CPU1_SB_CB<7>'
 '@S9S_MB_2U_LIB.S9S_MB_2U(SCH_1):M_C_CPU1_SB_CB'<7>:
 C_SIGNAL='@s9s_mb_2u_lib.s9s_mb_2u(sch_1):m_c_cpu1_sb_cb(7)';
NODE_NAME     U1 Y34
 '@S9S_MB_2U_LIB.S9S_MB_2U(SCH_1):PAGE53_I91@PURE_QUANTA.SOCKET4677_AZIF0045P001C01CS(CHIPS)':
 'DDR2_SB_ECC7': CDS_PINID='DDR2_SB_ECC7';
NODE_NAME     J21 236
 '@S9S_MB_2U_LIB.S9S_MB_2U(SCH_1):PAGE102_I13@PURE_QUANTA.SCONN288_ADR50017P130CC(CHIPS)':
 'CB7_B': CDS_PINID='CB7_B';
NODE_NAME     J22 236
 '@S9S_MB_2U_LIB.S9S_MB_2U(SCH_1):PAGE103_I51@PURE_QUANTA.SCONN288_ADR50017P087CC(CHIPS)':
 'CB7_B': CDS_PINID='CB7_B';
NET_NAME
'M_C_CPU1_SB_CS_N<0>'
 '@S9S_MB_2U_LIB.S9S_MB_2U(SCH_1):M_C_CPU1_SB_CS_N'<0>:
 C_SIGNAL='@s9s_mb_2u_lib.s9s_mb_2u(sch_1):m_c_cpu1_sb_cs_n(0)';
NODE_NAME     U1 T38
 '@S9S_MB_2U_LIB.S9S_MB_2U(SCH_1):PAGE53_I91@PURE_QUANTA.SOCKET4677_AZIF0045P001C01CS(CHIPS)':
 'DDR2_SB_CS_N0': CDS_PINID='DDR2_SB_CS_N0';
NODE_NAME     J21 84
 '@S9S_MB_2U_LIB.S9S_MB_2U(SCH_1):PAGE102_I13@PURE_QUANTA.SCONN288_ADR50017P130CC(CHIPS)':
 'CS0_B_N': CDS_PINID='CS0_B_N';
NET_NAME
'M_C_CPU1_SB_CS_N<1>'
 '@S9S_MB_2U_LIB.S9S_MB_2U(SCH_1):M_C_CPU1_SB_CS_N'<1>:
 C_SIGNAL='@s9s_mb_2u_lib.s9s_mb_2u(sch_1):m_c_cpu1_sb_cs_n(1)';
NODE_NAME     U1 U37
 '@S9S_MB_2U_LIB.S9S_MB_2U(SCH_1):PAGE53_I91@PURE_QUANTA.SOCKET4677_AZIF0045P001C01CS(CHIPS)':
 'DDR2_SB_CS_N1': CDS_PINID='DDR2_SB_CS_N1';
NODE_NAME     J21 229
 '@S9S_MB_2U_LIB.S9S_MB_2U(SCH_1):PAGE102_I13@PURE_QUANTA.SCONN288_ADR50017P130CC(CHIPS)':
 'CS1_B_N': CDS_PINID='CS1_B_N';
NET_NAME
'M_C_CPU1_SB_CS_N<2>'
 '@S9S_MB_2U_LIB.S9S_MB_2U(SCH_1):M_C_CPU1_SB_CS_N'<2>:
 C_SIGNAL='@s9s_mb_2u_lib.s9s_mb_2u(sch_1):m_c_cpu1_sb_cs_n(2)';
NODE_NAME     U1 Y38
 '@S9S_MB_2U_LIB.S9S_MB_2U(SCH_1):PAGE53_I91@PURE_QUANTA.SOCKET4677_AZIF0045P001C01CS(CHIPS)':
 'DDR2_SB_CS_N2': CDS_PINID='DDR2_SB_CS_N2';
NODE_NAME     J22 84
 '@S9S_MB_2U_LIB.S9S_MB_2U(SCH_1):PAGE103_I51@PURE_QUANTA.SCONN288_ADR50017P087CC(CHIPS)':
 'CS0_B_N': CDS_PINID='CS0_B_N';
NET_NAME
'M_C_CPU1_SB_CS_N<3>'
 '@S9S_MB_2U_LIB.S9S_MB_2U(SCH_1):M_C_CPU1_SB_CS_N'<3>:
 C_SIGNAL='@s9s_mb_2u_lib.s9s_mb_2u(sch_1):m_c_cpu1_sb_cs_n(3)';
NODE_NAME     U1 W37
 '@S9S_MB_2U_LIB.S9S_MB_2U(SCH_1):PAGE53_I91@PURE_QUANTA.SOCKET4677_AZIF0045P001C01CS(CHIPS)':
 'DDR2_SB_CS_N3': CDS_PINID='DDR2_SB_CS_N3';
NODE_NAME     J22 229
 '@S9S_MB_2U_LIB.S9S_MB_2U(SCH_1):PAGE103_I51@PURE_QUANTA.SCONN288_ADR50017P087CC(CHIPS)':
 'CS1_B_N': CDS_PINID='CS1_B_N';
NET_NAME
'M_C_CPU1_SB_DQ<0>'
 '@S9S_MB_2U_LIB.S9S_MB_2U(SCH_1):M_C_CPU1_SB_DQ'<0>:
 C_SIGNAL='@s9s_mb_2u_lib.s9s_mb_2u(sch_1):m_c_cpu1_sb_dq(0)';
NODE_NAME     U1 AD38
 '@S9S_MB_2U_LIB.S9S_MB_2U(SCH_1):PAGE53_I91@PURE_QUANTA.SOCKET4677_AZIF0045P001C01CS(CHIPS)':
 'DDR2_SB_DQ0': CDS_PINID='DDR2_SB_DQ0';
NODE_NAME     J21 100
 '@S9S_MB_2U_LIB.S9S_MB_2U(SCH_1):PAGE102_I13@PURE_QUANTA.SCONN288_ADR50017P130CC(CHIPS)':
 'DQ0_B': CDS_PINID='DQ0_B';
NODE_NAME     J22 100
 '@S9S_MB_2U_LIB.S9S_MB_2U(SCH_1):PAGE103_I51@PURE_QUANTA.SCONN288_ADR50017P087CC(CHIPS)':
 'DQ0_B': CDS_PINID='DQ0_B';
NET_NAME
'M_C_CPU1_SB_DQ<10>'
 '@S9S_MB_2U_LIB.S9S_MB_2U(SCH_1):M_C_CPU1_SB_DQ'<10>:
 C_SIGNAL='@s9s_mb_2u_lib.s9s_mb_2u(sch_1):m_c_cpu1_sb_dq(10)';
NODE_NAME     U1 AF32
 '@S9S_MB_2U_LIB.S9S_MB_2U(SCH_1):PAGE53_I91@PURE_QUANTA.SOCKET4677_AZIF0045P001C01CS(CHIPS)':
 'DDR2_SB_DQ10': CDS_PINID='DDR2_SB_DQ10';
NODE_NAME     J21 256
 '@S9S_MB_2U_LIB.S9S_MB_2U(SCH_1):PAGE102_I13@PURE_QUANTA.SCONN288_ADR50017P130CC(CHIPS)':
 'DQ10_B': CDS_PINID='DQ10_B';
NODE_NAME     J22 256
 '@S9S_MB_2U_LIB.S9S_MB_2U(SCH_1):PAGE103_I51@PURE_QUANTA.SCONN288_ADR50017P087CC(CHIPS)':
 'DQ10_B': CDS_PINID='DQ10_B';
NET_NAME
'M_C_CPU1_SB_DQ<11>'
 '@S9S_MB_2U_LIB.S9S_MB_2U(SCH_1):M_C_CPU1_SB_DQ'<11>:
 C_SIGNAL='@s9s_mb_2u_lib.s9s_mb_2u(sch_1):m_c_cpu1_sb_dq(11)';
NODE_NAME     U1 AG31
 '@S9S_MB_2U_LIB.S9S_MB_2U(SCH_1):PAGE53_I91@PURE_QUANTA.SOCKET4677_AZIF0045P001C01CS(CHIPS)':
 'DDR2_SB_DQ11': CDS_PINID='DDR2_SB_DQ11';
NODE_NAME     J21 258
 '@S9S_MB_2U_LIB.S9S_MB_2U(SCH_1):PAGE102_I13@PURE_QUANTA.SCONN288_ADR50017P130CC(CHIPS)':
 'DQ11_B': CDS_PINID='DQ11_B';
NODE_NAME     J22 258
 '@S9S_MB_2U_LIB.S9S_MB_2U(SCH_1):PAGE103_I51@PURE_QUANTA.SCONN288_ADR50017P087CC(CHIPS)':
 'DQ11_B': CDS_PINID='DQ11_B';
NET_NAME
'M_C_CPU1_SB_DQ<12>'
 '@S9S_MB_2U_LIB.S9S_MB_2U(SCH_1):M_C_CPU1_SB_DQ'<12>:
 C_SIGNAL='@s9s_mb_2u_lib.s9s_mb_2u(sch_1):m_c_cpu1_sb_dq(12)';
NODE_NAME     U1 AC29
 '@S9S_MB_2U_LIB.S9S_MB_2U(SCH_1):PAGE53_I91@PURE_QUANTA.SOCKET4677_AZIF0045P001C01CS(CHIPS)':
 'DDR2_SB_DQ12': CDS_PINID='DDR2_SB_DQ12';
NODE_NAME     J21 118
 '@S9S_MB_2U_LIB.S9S_MB_2U(SCH_1):PAGE102_I13@PURE_QUANTA.SCONN288_ADR50017P130CC(CHIPS)':
 'DQ12_B': CDS_PINID='DQ12_B';
NODE_NAME     J22 118
 '@S9S_MB_2U_LIB.S9S_MB_2U(SCH_1):PAGE103_I51@PURE_QUANTA.SCONN288_ADR50017P087CC(CHIPS)':
 'DQ12_B': CDS_PINID='DQ12_B';
NET_NAME
'M_C_CPU1_SB_DQ<13>'
 '@S9S_MB_2U_LIB.S9S_MB_2U(SCH_1):M_C_CPU1_SB_DQ'<13>:
 C_SIGNAL='@s9s_mb_2u_lib.s9s_mb_2u(sch_1):m_c_cpu1_sb_dq(13)';
NODE_NAME     U1 AD28
 '@S9S_MB_2U_LIB.S9S_MB_2U(SCH_1):PAGE53_I91@PURE_QUANTA.SOCKET4677_AZIF0045P001C01CS(CHIPS)':
 'DDR2_SB_DQ13': CDS_PINID='DDR2_SB_DQ13';
NODE_NAME     J21 120
 '@S9S_MB_2U_LIB.S9S_MB_2U(SCH_1):PAGE102_I13@PURE_QUANTA.SCONN288_ADR50017P130CC(CHIPS)':
 'DQ13_B': CDS_PINID='DQ13_B';
NODE_NAME     J22 120
 '@S9S_MB_2U_LIB.S9S_MB_2U(SCH_1):PAGE103_I51@PURE_QUANTA.SCONN288_ADR50017P087CC(CHIPS)':
 'DQ13_B': CDS_PINID='DQ13_B';
NET_NAME
'M_C_CPU1_SB_DQ<14>'
 '@S9S_MB_2U_LIB.S9S_MB_2U(SCH_1):M_C_CPU1_SB_DQ'<14>:
 C_SIGNAL='@s9s_mb_2u_lib.s9s_mb_2u(sch_1):m_c_cpu1_sb_dq(14)';
NODE_NAME     U1 AG29
 '@S9S_MB_2U_LIB.S9S_MB_2U(SCH_1):PAGE53_I91@PURE_QUANTA.SOCKET4677_AZIF0045P001C01CS(CHIPS)':
 'DDR2_SB_DQ14': CDS_PINID='DDR2_SB_DQ14';
NODE_NAME     J21 263
 '@S9S_MB_2U_LIB.S9S_MB_2U(SCH_1):PAGE102_I13@PURE_QUANTA.SCONN288_ADR50017P130CC(CHIPS)':
 'DQ14_B': CDS_PINID='DQ14_B';
NODE_NAME     J22 263
 '@S9S_MB_2U_LIB.S9S_MB_2U(SCH_1):PAGE103_I51@PURE_QUANTA.SCONN288_ADR50017P087CC(CHIPS)':
 'DQ14_B': CDS_PINID='DQ14_B';
NET_NAME
'M_C_CPU1_SB_DQ<15>'
 '@S9S_MB_2U_LIB.S9S_MB_2U(SCH_1):M_C_CPU1_SB_DQ'<15>:
 C_SIGNAL='@s9s_mb_2u_lib.s9s_mb_2u(sch_1):m_c_cpu1_sb_dq(15)';
NODE_NAME     U1 AF28
 '@S9S_MB_2U_LIB.S9S_MB_2U(SCH_1):PAGE53_I91@PURE_QUANTA.SOCKET4677_AZIF0045P001C01CS(CHIPS)':
 'DDR2_SB_DQ15': CDS_PINID='DDR2_SB_DQ15';
NODE_NAME     J21 265
 '@S9S_MB_2U_LIB.S9S_MB_2U(SCH_1):PAGE102_I13@PURE_QUANTA.SCONN288_ADR50017P130CC(CHIPS)':
 'DQ15_B': CDS_PINID='DQ15_B';
NODE_NAME     J22 265
 '@S9S_MB_2U_LIB.S9S_MB_2U(SCH_1):PAGE103_I51@PURE_QUANTA.SCONN288_ADR50017P087CC(CHIPS)':
 'DQ15_B': CDS_PINID='DQ15_B';
NET_NAME
'M_C_CPU1_SB_DQ<16>'
 '@S9S_MB_2U_LIB.S9S_MB_2U(SCH_1):M_C_CPU1_SB_DQ'<16>:
 C_SIGNAL='@s9s_mb_2u_lib.s9s_mb_2u(sch_1):m_c_cpu1_sb_dq(16)';
NODE_NAME     U1 U23
 '@S9S_MB_2U_LIB.S9S_MB_2U(SCH_1):PAGE53_I91@PURE_QUANTA.SOCKET4677_AZIF0045P001C01CS(CHIPS)':
 'DDR2_SB_DQ16': CDS_PINID='DDR2_SB_DQ16';
NODE_NAME     J21 122
 '@S9S_MB_2U_LIB.S9S_MB_2U(SCH_1):PAGE102_I13@PURE_QUANTA.SCONN288_ADR50017P130CC(CHIPS)':
 'DQ16_B': CDS_PINID='DQ16_B';
NODE_NAME     J22 122
 '@S9S_MB_2U_LIB.S9S_MB_2U(SCH_1):PAGE103_I51@PURE_QUANTA.SCONN288_ADR50017P087CC(CHIPS)':
 'DQ16_B': CDS_PINID='DQ16_B';
NET_NAME
'M_C_CPU1_SB_DQ<17>'
 '@S9S_MB_2U_LIB.S9S_MB_2U(SCH_1):M_C_CPU1_SB_DQ'<17>:
 C_SIGNAL='@s9s_mb_2u_lib.s9s_mb_2u(sch_1):m_c_cpu1_sb_dq(17)';
NODE_NAME     U1 T22
 '@S9S_MB_2U_LIB.S9S_MB_2U(SCH_1):PAGE53_I91@PURE_QUANTA.SOCKET4677_AZIF0045P001C01CS(CHIPS)':
 'DDR2_SB_DQ17': CDS_PINID='DDR2_SB_DQ17';
NODE_NAME     J21 124
 '@S9S_MB_2U_LIB.S9S_MB_2U(SCH_1):PAGE102_I13@PURE_QUANTA.SCONN288_ADR50017P130CC(CHIPS)':
 'DQ17_B': CDS_PINID='DQ17_B';
NODE_NAME     J22 124
 '@S9S_MB_2U_LIB.S9S_MB_2U(SCH_1):PAGE103_I51@PURE_QUANTA.SCONN288_ADR50017P087CC(CHIPS)':
 'DQ17_B': CDS_PINID='DQ17_B';
NET_NAME
'M_C_CPU1_SB_DQ<18>'
 '@S9S_MB_2U_LIB.S9S_MB_2U(SCH_1):M_C_CPU1_SB_DQ'<18>:
 C_SIGNAL='@s9s_mb_2u_lib.s9s_mb_2u(sch_1):m_c_cpu1_sb_dq(18)';
NODE_NAME     U1 W23
 '@S9S_MB_2U_LIB.S9S_MB_2U(SCH_1):PAGE53_I91@PURE_QUANTA.SOCKET4677_AZIF0045P001C01CS(CHIPS)':
 'DDR2_SB_DQ18': CDS_PINID='DDR2_SB_DQ18';
NODE_NAME     J21 267
 '@S9S_MB_2U_LIB.S9S_MB_2U(SCH_1):PAGE102_I13@PURE_QUANTA.SCONN288_ADR50017P130CC(CHIPS)':
 'DQ18_B': CDS_PINID='DQ18_B';
NODE_NAME     J22 267
 '@S9S_MB_2U_LIB.S9S_MB_2U(SCH_1):PAGE103_I51@PURE_QUANTA.SCONN288_ADR50017P087CC(CHIPS)':
 'DQ18_B': CDS_PINID='DQ18_B';
NET_NAME
'M_C_CPU1_SB_DQ<19>'
 '@S9S_MB_2U_LIB.S9S_MB_2U(SCH_1):M_C_CPU1_SB_DQ'<19>:
 C_SIGNAL='@s9s_mb_2u_lib.s9s_mb_2u(sch_1):m_c_cpu1_sb_dq(19)';
NODE_NAME     U1 Y22
 '@S9S_MB_2U_LIB.S9S_MB_2U(SCH_1):PAGE53_I91@PURE_QUANTA.SOCKET4677_AZIF0045P001C01CS(CHIPS)':
 'DDR2_SB_DQ19': CDS_PINID='DDR2_SB_DQ19';
NODE_NAME     J21 269
 '@S9S_MB_2U_LIB.S9S_MB_2U(SCH_1):PAGE102_I13@PURE_QUANTA.SCONN288_ADR50017P130CC(CHIPS)':
 'DQ19_B': CDS_PINID='DQ19_B';
NODE_NAME     J22 269
 '@S9S_MB_2U_LIB.S9S_MB_2U(SCH_1):PAGE103_I51@PURE_QUANTA.SCONN288_ADR50017P087CC(CHIPS)':
 'DQ19_B': CDS_PINID='DQ19_B';
NET_NAME
'M_C_CPU1_SB_DQ<1>'
 '@S9S_MB_2U_LIB.S9S_MB_2U(SCH_1):M_C_CPU1_SB_DQ'<1>:
 C_SIGNAL='@s9s_mb_2u_lib.s9s_mb_2u(sch_1):m_c_cpu1_sb_dq(1)';
NODE_NAME     U1 AC37
 '@S9S_MB_2U_LIB.S9S_MB_2U(SCH_1):PAGE53_I91@PURE_QUANTA.SOCKET4677_AZIF0045P001C01CS(CHIPS)':
 'DDR2_SB_DQ1': CDS_PINID='DDR2_SB_DQ1';
NODE_NAME     J21 102
 '@S9S_MB_2U_LIB.S9S_MB_2U(SCH_1):PAGE102_I13@PURE_QUANTA.SCONN288_ADR50017P130CC(CHIPS)':
 'DQ1_B': CDS_PINID='DQ1_B';
NODE_NAME     J22 102
 '@S9S_MB_2U_LIB.S9S_MB_2U(SCH_1):PAGE103_I51@PURE_QUANTA.SCONN288_ADR50017P087CC(CHIPS)':
 'DQ1_B': CDS_PINID='DQ1_B';
NET_NAME
'M_C_CPU1_SB_DQ<20>'
 '@S9S_MB_2U_LIB.S9S_MB_2U(SCH_1):M_C_CPU1_SB_DQ'<20>:
 C_SIGNAL='@s9s_mb_2u_lib.s9s_mb_2u(sch_1):m_c_cpu1_sb_dq(20)';
NODE_NAME     U1 T20
 '@S9S_MB_2U_LIB.S9S_MB_2U(SCH_1):PAGE53_I91@PURE_QUANTA.SOCKET4677_AZIF0045P001C01CS(CHIPS)':
 'DDR2_SB_DQ20': CDS_PINID='DDR2_SB_DQ20';
NODE_NAME     J21 129
 '@S9S_MB_2U_LIB.S9S_MB_2U(SCH_1):PAGE102_I13@PURE_QUANTA.SCONN288_ADR50017P130CC(CHIPS)':
 'DQ20_B': CDS_PINID='DQ20_B';
NODE_NAME     J22 129
 '@S9S_MB_2U_LIB.S9S_MB_2U(SCH_1):PAGE103_I51@PURE_QUANTA.SCONN288_ADR50017P087CC(CHIPS)':
 'DQ20_B': CDS_PINID='DQ20_B';
NET_NAME
'M_C_CPU1_SB_DQ<21>'
 '@S9S_MB_2U_LIB.S9S_MB_2U(SCH_1):M_C_CPU1_SB_DQ'<21>:
 C_SIGNAL='@s9s_mb_2u_lib.s9s_mb_2u(sch_1):m_c_cpu1_sb_dq(21)';
NODE_NAME     U1 U19
 '@S9S_MB_2U_LIB.S9S_MB_2U(SCH_1):PAGE53_I91@PURE_QUANTA.SOCKET4677_AZIF0045P001C01CS(CHIPS)':
 'DDR2_SB_DQ21': CDS_PINID='DDR2_SB_DQ21';
NODE_NAME     J21 131
 '@S9S_MB_2U_LIB.S9S_MB_2U(SCH_1):PAGE102_I13@PURE_QUANTA.SCONN288_ADR50017P130CC(CHIPS)':
 'DQ21_B': CDS_PINID='DQ21_B';
NODE_NAME     J22 131
 '@S9S_MB_2U_LIB.S9S_MB_2U(SCH_1):PAGE103_I51@PURE_QUANTA.SCONN288_ADR50017P087CC(CHIPS)':
 'DQ21_B': CDS_PINID='DQ21_B';
NET_NAME
'M_C_CPU1_SB_DQ<22>'
 '@S9S_MB_2U_LIB.S9S_MB_2U(SCH_1):M_C_CPU1_SB_DQ'<22>:
 C_SIGNAL='@s9s_mb_2u_lib.s9s_mb_2u(sch_1):m_c_cpu1_sb_dq(22)';
NODE_NAME     U1 Y20
 '@S9S_MB_2U_LIB.S9S_MB_2U(SCH_1):PAGE53_I91@PURE_QUANTA.SOCKET4677_AZIF0045P001C01CS(CHIPS)':
 'DDR2_SB_DQ22': CDS_PINID='DDR2_SB_DQ22';
NODE_NAME     J21 274
 '@S9S_MB_2U_LIB.S9S_MB_2U(SCH_1):PAGE102_I13@PURE_QUANTA.SCONN288_ADR50017P130CC(CHIPS)':
 'DQ22_B': CDS_PINID='DQ22_B';
NODE_NAME     J22 274
 '@S9S_MB_2U_LIB.S9S_MB_2U(SCH_1):PAGE103_I51@PURE_QUANTA.SCONN288_ADR50017P087CC(CHIPS)':
 'DQ22_B': CDS_PINID='DQ22_B';
NET_NAME
'M_C_CPU1_SB_DQ<23>'
 '@S9S_MB_2U_LIB.S9S_MB_2U(SCH_1):M_C_CPU1_SB_DQ'<23>:
 C_SIGNAL='@s9s_mb_2u_lib.s9s_mb_2u(sch_1):m_c_cpu1_sb_dq(23)';
NODE_NAME     U1 W19
 '@S9S_MB_2U_LIB.S9S_MB_2U(SCH_1):PAGE53_I91@PURE_QUANTA.SOCKET4677_AZIF0045P001C01CS(CHIPS)':
 'DDR2_SB_DQ23': CDS_PINID='DDR2_SB_DQ23';
NODE_NAME     J21 276
 '@S9S_MB_2U_LIB.S9S_MB_2U(SCH_1):PAGE102_I13@PURE_QUANTA.SCONN288_ADR50017P130CC(CHIPS)':
 'DQ23_B': CDS_PINID='DQ23_B';
NODE_NAME     J22 276
 '@S9S_MB_2U_LIB.S9S_MB_2U(SCH_1):PAGE103_I51@PURE_QUANTA.SCONN288_ADR50017P087CC(CHIPS)':
 'DQ23_B': CDS_PINID='DQ23_B';
NET_NAME
'M_C_CPU1_SB_DQ<24>'
 '@S9S_MB_2U_LIB.S9S_MB_2U(SCH_1):M_C_CPU1_SB_DQ'<24>:
 C_SIGNAL='@s9s_mb_2u_lib.s9s_mb_2u(sch_1):m_c_cpu1_sb_dq(24)';
NODE_NAME     U1 AD20
 '@S9S_MB_2U_LIB.S9S_MB_2U(SCH_1):PAGE53_I91@PURE_QUANTA.SOCKET4677_AZIF0045P001C01CS(CHIPS)':
 'DDR2_SB_DQ24': CDS_PINID='DDR2_SB_DQ24';
NODE_NAME     J21 133
 '@S9S_MB_2U_LIB.S9S_MB_2U(SCH_1):PAGE102_I13@PURE_QUANTA.SCONN288_ADR50017P130CC(CHIPS)':
 'DQ24_B': CDS_PINID='DQ24_B';
NODE_NAME     J22 133
 '@S9S_MB_2U_LIB.S9S_MB_2U(SCH_1):PAGE103_I51@PURE_QUANTA.SCONN288_ADR50017P087CC(CHIPS)':
 'DQ24_B': CDS_PINID='DQ24_B';
NET_NAME
'M_C_CPU1_SB_DQ<25>'
 '@S9S_MB_2U_LIB.S9S_MB_2U(SCH_1):M_C_CPU1_SB_DQ'<25>:
 C_SIGNAL='@s9s_mb_2u_lib.s9s_mb_2u(sch_1):m_c_cpu1_sb_dq(25)';
NODE_NAME     U1 AC19
 '@S9S_MB_2U_LIB.S9S_MB_2U(SCH_1):PAGE53_I91@PURE_QUANTA.SOCKET4677_AZIF0045P001C01CS(CHIPS)':
 'DDR2_SB_DQ25': CDS_PINID='DDR2_SB_DQ25';
NODE_NAME     J21 135
 '@S9S_MB_2U_LIB.S9S_MB_2U(SCH_1):PAGE102_I13@PURE_QUANTA.SCONN288_ADR50017P130CC(CHIPS)':
 'DQ25_B': CDS_PINID='DQ25_B';
NODE_NAME     J22 135
 '@S9S_MB_2U_LIB.S9S_MB_2U(SCH_1):PAGE103_I51@PURE_QUANTA.SCONN288_ADR50017P087CC(CHIPS)':
 'DQ25_B': CDS_PINID='DQ25_B';
NET_NAME
'M_C_CPU1_SB_DQ<26>'
 '@S9S_MB_2U_LIB.S9S_MB_2U(SCH_1):M_C_CPU1_SB_DQ'<26>:
 C_SIGNAL='@s9s_mb_2u_lib.s9s_mb_2u(sch_1):m_c_cpu1_sb_dq(26)';
NODE_NAME     U1 AF20
 '@S9S_MB_2U_LIB.S9S_MB_2U(SCH_1):PAGE53_I91@PURE_QUANTA.SOCKET4677_AZIF0045P001C01CS(CHIPS)':
 'DDR2_SB_DQ26': CDS_PINID='DDR2_SB_DQ26';
NODE_NAME     J21 278
 '@S9S_MB_2U_LIB.S9S_MB_2U(SCH_1):PAGE102_I13@PURE_QUANTA.SCONN288_ADR50017P130CC(CHIPS)':
 'DQ26_B': CDS_PINID='DQ26_B';
NODE_NAME     J22 278
 '@S9S_MB_2U_LIB.S9S_MB_2U(SCH_1):PAGE103_I51@PURE_QUANTA.SCONN288_ADR50017P087CC(CHIPS)':
 'DQ26_B': CDS_PINID='DQ26_B';
NET_NAME
'M_C_CPU1_SB_DQ<27>'
 '@S9S_MB_2U_LIB.S9S_MB_2U(SCH_1):M_C_CPU1_SB_DQ'<27>:
 C_SIGNAL='@s9s_mb_2u_lib.s9s_mb_2u(sch_1):m_c_cpu1_sb_dq(27)';
NODE_NAME     U1 AG19
 '@S9S_MB_2U_LIB.S9S_MB_2U(SCH_1):PAGE53_I91@PURE_QUANTA.SOCKET4677_AZIF0045P001C01CS(CHIPS)':
 'DDR2_SB_DQ27': CDS_PINID='DDR2_SB_DQ27';
NODE_NAME     J21 280
 '@S9S_MB_2U_LIB.S9S_MB_2U(SCH_1):PAGE102_I13@PURE_QUANTA.SCONN288_ADR50017P130CC(CHIPS)':
 'DQ27_B': CDS_PINID='DQ27_B';
NODE_NAME     J22 280
 '@S9S_MB_2U_LIB.S9S_MB_2U(SCH_1):PAGE103_I51@PURE_QUANTA.SCONN288_ADR50017P087CC(CHIPS)':
 'DQ27_B': CDS_PINID='DQ27_B';
NET_NAME
'M_C_CPU1_SB_DQ<28>'
 '@S9S_MB_2U_LIB.S9S_MB_2U(SCH_1):M_C_CPU1_SB_DQ'<28>:
 C_SIGNAL='@s9s_mb_2u_lib.s9s_mb_2u(sch_1):m_c_cpu1_sb_dq(28)';
NODE_NAME     U1 AA17
 '@S9S_MB_2U_LIB.S9S_MB_2U(SCH_1):PAGE53_I91@PURE_QUANTA.SOCKET4677_AZIF0045P001C01CS(CHIPS)':
 'DDR2_SB_DQ28': CDS_PINID='DDR2_SB_DQ28';
NODE_NAME     J21 140
 '@S9S_MB_2U_LIB.S9S_MB_2U(SCH_1):PAGE102_I13@PURE_QUANTA.SCONN288_ADR50017P130CC(CHIPS)':
 'DQ28_B': CDS_PINID='DQ28_B';
NODE_NAME     J22 140
 '@S9S_MB_2U_LIB.S9S_MB_2U(SCH_1):PAGE103_I51@PURE_QUANTA.SCONN288_ADR50017P087CC(CHIPS)':
 'DQ28_B': CDS_PINID='DQ28_B';
NET_NAME
'M_C_CPU1_SB_DQ<29>'
 '@S9S_MB_2U_LIB.S9S_MB_2U(SCH_1):M_C_CPU1_SB_DQ'<29>:
 C_SIGNAL='@s9s_mb_2u_lib.s9s_mb_2u(sch_1):m_c_cpu1_sb_dq(29)';
NODE_NAME     U1 AG17
 '@S9S_MB_2U_LIB.S9S_MB_2U(SCH_1):PAGE53_I91@PURE_QUANTA.SOCKET4677_AZIF0045P001C01CS(CHIPS)':
 'DDR2_SB_DQ29': CDS_PINID='DDR2_SB_DQ29';
NODE_NAME     J21 142
 '@S9S_MB_2U_LIB.S9S_MB_2U(SCH_1):PAGE102_I13@PURE_QUANTA.SCONN288_ADR50017P130CC(CHIPS)':
 'DQ29_B': CDS_PINID='DQ29_B';
NODE_NAME     J22 142
 '@S9S_MB_2U_LIB.S9S_MB_2U(SCH_1):PAGE103_I51@PURE_QUANTA.SCONN288_ADR50017P087CC(CHIPS)':
 'DQ29_B': CDS_PINID='DQ29_B';
NET_NAME
'M_C_CPU1_SB_DQ<2>'
 '@S9S_MB_2U_LIB.S9S_MB_2U(SCH_1):M_C_CPU1_SB_DQ'<2>:
 C_SIGNAL='@s9s_mb_2u_lib.s9s_mb_2u(sch_1):m_c_cpu1_sb_dq(2)';
NODE_NAME     U1 AF38
 '@S9S_MB_2U_LIB.S9S_MB_2U(SCH_1):PAGE53_I91@PURE_QUANTA.SOCKET4677_AZIF0045P001C01CS(CHIPS)':
 'DDR2_SB_DQ2': CDS_PINID='DDR2_SB_DQ2';
NODE_NAME     J21 245
 '@S9S_MB_2U_LIB.S9S_MB_2U(SCH_1):PAGE102_I13@PURE_QUANTA.SCONN288_ADR50017P130CC(CHIPS)':
 'DQ2_B': CDS_PINID='DQ2_B';
NODE_NAME     J22 245
 '@S9S_MB_2U_LIB.S9S_MB_2U(SCH_1):PAGE103_I51@PURE_QUANTA.SCONN288_ADR50017P087CC(CHIPS)':
 'DQ2_B': CDS_PINID='DQ2_B';
NET_NAME
'M_C_CPU1_SB_DQ<30>'
 '@S9S_MB_2U_LIB.S9S_MB_2U(SCH_1):M_C_CPU1_SB_DQ'<30>:
 C_SIGNAL='@s9s_mb_2u_lib.s9s_mb_2u(sch_1):m_c_cpu1_sb_dq(30)';
NODE_NAME     U1 AC17
 '@S9S_MB_2U_LIB.S9S_MB_2U(SCH_1):PAGE53_I91@PURE_QUANTA.SOCKET4677_AZIF0045P001C01CS(CHIPS)':
 'DDR2_SB_DQ30': CDS_PINID='DDR2_SB_DQ30';
NODE_NAME     J21 285
 '@S9S_MB_2U_LIB.S9S_MB_2U(SCH_1):PAGE102_I13@PURE_QUANTA.SCONN288_ADR50017P130CC(CHIPS)':
 'DQ30_B': CDS_PINID='DQ30_B';
NODE_NAME     J22 285
 '@S9S_MB_2U_LIB.S9S_MB_2U(SCH_1):PAGE103_I51@PURE_QUANTA.SCONN288_ADR50017P087CC(CHIPS)':
 'DQ30_B': CDS_PINID='DQ30_B';
NET_NAME
'M_C_CPU1_SB_DQ<31>'
 '@S9S_MB_2U_LIB.S9S_MB_2U(SCH_1):M_C_CPU1_SB_DQ'<31>:
 C_SIGNAL='@s9s_mb_2u_lib.s9s_mb_2u(sch_1):m_c_cpu1_sb_dq(31)';
NODE_NAME     U1 AJ17
 '@S9S_MB_2U_LIB.S9S_MB_2U(SCH_1):PAGE53_I91@PURE_QUANTA.SOCKET4677_AZIF0045P001C01CS(CHIPS)':
 'DDR2_SB_DQ31': CDS_PINID='DDR2_SB_DQ31';
NODE_NAME     J21 287
 '@S9S_MB_2U_LIB.S9S_MB_2U(SCH_1):PAGE102_I13@PURE_QUANTA.SCONN288_ADR50017P130CC(CHIPS)':
 'DQ31_B': CDS_PINID='DQ31_B';
NODE_NAME     J22 287
 '@S9S_MB_2U_LIB.S9S_MB_2U(SCH_1):PAGE103_I51@PURE_QUANTA.SCONN288_ADR50017P087CC(CHIPS)':
 'DQ31_B': CDS_PINID='DQ31_B';
NET_NAME
'M_C_CPU1_SB_DQ<3>'
 '@S9S_MB_2U_LIB.S9S_MB_2U(SCH_1):M_C_CPU1_SB_DQ'<3>:
 C_SIGNAL='@s9s_mb_2u_lib.s9s_mb_2u(sch_1):m_c_cpu1_sb_dq(3)';
NODE_NAME     U1 AG37
 '@S9S_MB_2U_LIB.S9S_MB_2U(SCH_1):PAGE53_I91@PURE_QUANTA.SOCKET4677_AZIF0045P001C01CS(CHIPS)':
 'DDR2_SB_DQ3': CDS_PINID='DDR2_SB_DQ3';
NODE_NAME     J21 247
 '@S9S_MB_2U_LIB.S9S_MB_2U(SCH_1):PAGE102_I13@PURE_QUANTA.SCONN288_ADR50017P130CC(CHIPS)':
 'DQ3_B': CDS_PINID='DQ3_B';
NODE_NAME     J22 247
 '@S9S_MB_2U_LIB.S9S_MB_2U(SCH_1):PAGE103_I51@PURE_QUANTA.SCONN288_ADR50017P087CC(CHIPS)':
 'DQ3_B': CDS_PINID='DQ3_B';
NET_NAME
'M_C_CPU1_SB_DQ<4>'
 '@S9S_MB_2U_LIB.S9S_MB_2U(SCH_1):M_C_CPU1_SB_DQ'<4>:
 C_SIGNAL='@s9s_mb_2u_lib.s9s_mb_2u(sch_1):m_c_cpu1_sb_dq(4)';
NODE_NAME     U1 AC35
 '@S9S_MB_2U_LIB.S9S_MB_2U(SCH_1):PAGE53_I91@PURE_QUANTA.SOCKET4677_AZIF0045P001C01CS(CHIPS)':
 'DDR2_SB_DQ4': CDS_PINID='DDR2_SB_DQ4';
NODE_NAME     J21 107
 '@S9S_MB_2U_LIB.S9S_MB_2U(SCH_1):PAGE102_I13@PURE_QUANTA.SCONN288_ADR50017P130CC(CHIPS)':
 'DQ4_B': CDS_PINID='DQ4_B';
NODE_NAME     J22 107
 '@S9S_MB_2U_LIB.S9S_MB_2U(SCH_1):PAGE103_I51@PURE_QUANTA.SCONN288_ADR50017P087CC(CHIPS)':
 'DQ4_B': CDS_PINID='DQ4_B';
NET_NAME
'M_C_CPU1_SB_DQ<5>'
 '@S9S_MB_2U_LIB.S9S_MB_2U(SCH_1):M_C_CPU1_SB_DQ'<5>:
 C_SIGNAL='@s9s_mb_2u_lib.s9s_mb_2u(sch_1):m_c_cpu1_sb_dq(5)';
NODE_NAME     U1 AD34
 '@S9S_MB_2U_LIB.S9S_MB_2U(SCH_1):PAGE53_I91@PURE_QUANTA.SOCKET4677_AZIF0045P001C01CS(CHIPS)':
 'DDR2_SB_DQ5': CDS_PINID='DDR2_SB_DQ5';
NODE_NAME     J21 109
 '@S9S_MB_2U_LIB.S9S_MB_2U(SCH_1):PAGE102_I13@PURE_QUANTA.SCONN288_ADR50017P130CC(CHIPS)':
 'DQ5_B': CDS_PINID='DQ5_B';
NODE_NAME     J22 109
 '@S9S_MB_2U_LIB.S9S_MB_2U(SCH_1):PAGE103_I51@PURE_QUANTA.SCONN288_ADR50017P087CC(CHIPS)':
 'DQ5_B': CDS_PINID='DQ5_B';
NET_NAME
'M_C_CPU1_SB_DQ<6>'
 '@S9S_MB_2U_LIB.S9S_MB_2U(SCH_1):M_C_CPU1_SB_DQ'<6>:
 C_SIGNAL='@s9s_mb_2u_lib.s9s_mb_2u(sch_1):m_c_cpu1_sb_dq(6)';
NODE_NAME     U1 AG35
 '@S9S_MB_2U_LIB.S9S_MB_2U(SCH_1):PAGE53_I91@PURE_QUANTA.SOCKET4677_AZIF0045P001C01CS(CHIPS)':
 'DDR2_SB_DQ6': CDS_PINID='DDR2_SB_DQ6';
NODE_NAME     J21 252
 '@S9S_MB_2U_LIB.S9S_MB_2U(SCH_1):PAGE102_I13@PURE_QUANTA.SCONN288_ADR50017P130CC(CHIPS)':
 'DQ6_B': CDS_PINID='DQ6_B';
NODE_NAME     J22 252
 '@S9S_MB_2U_LIB.S9S_MB_2U(SCH_1):PAGE103_I51@PURE_QUANTA.SCONN288_ADR50017P087CC(CHIPS)':
 'DQ6_B': CDS_PINID='DQ6_B';
NET_NAME
'M_C_CPU1_SB_DQ<7>'
 '@S9S_MB_2U_LIB.S9S_MB_2U(SCH_1):M_C_CPU1_SB_DQ'<7>:
 C_SIGNAL='@s9s_mb_2u_lib.s9s_mb_2u(sch_1):m_c_cpu1_sb_dq(7)';
NODE_NAME     U1 AF34
 '@S9S_MB_2U_LIB.S9S_MB_2U(SCH_1):PAGE53_I91@PURE_QUANTA.SOCKET4677_AZIF0045P001C01CS(CHIPS)':
 'DDR2_SB_DQ7': CDS_PINID='DDR2_SB_DQ7';
NODE_NAME     J21 254
 '@S9S_MB_2U_LIB.S9S_MB_2U(SCH_1):PAGE102_I13@PURE_QUANTA.SCONN288_ADR50017P130CC(CHIPS)':
 'DQ7_B': CDS_PINID='DQ7_B';
NODE_NAME     J22 254
 '@S9S_MB_2U_LIB.S9S_MB_2U(SCH_1):PAGE103_I51@PURE_QUANTA.SCONN288_ADR50017P087CC(CHIPS)':
 'DQ7_B': CDS_PINID='DQ7_B';
NET_NAME
'M_C_CPU1_SB_DQ<8>'
 '@S9S_MB_2U_LIB.S9S_MB_2U(SCH_1):M_C_CPU1_SB_DQ'<8>:
 C_SIGNAL='@s9s_mb_2u_lib.s9s_mb_2u(sch_1):m_c_cpu1_sb_dq(8)';
NODE_NAME     U1 AD32
 '@S9S_MB_2U_LIB.S9S_MB_2U(SCH_1):PAGE53_I91@PURE_QUANTA.SOCKET4677_AZIF0045P001C01CS(CHIPS)':
 'DDR2_SB_DQ8': CDS_PINID='DDR2_SB_DQ8';
NODE_NAME     J21 111
 '@S9S_MB_2U_LIB.S9S_MB_2U(SCH_1):PAGE102_I13@PURE_QUANTA.SCONN288_ADR50017P130CC(CHIPS)':
 'DQ8_B': CDS_PINID='DQ8_B';
NODE_NAME     J22 111
 '@S9S_MB_2U_LIB.S9S_MB_2U(SCH_1):PAGE103_I51@PURE_QUANTA.SCONN288_ADR50017P087CC(CHIPS)':
 'DQ8_B': CDS_PINID='DQ8_B';
NET_NAME
'M_C_CPU1_SB_DQ<9>'
 '@S9S_MB_2U_LIB.S9S_MB_2U(SCH_1):M_C_CPU1_SB_DQ'<9>:
 C_SIGNAL='@s9s_mb_2u_lib.s9s_mb_2u(sch_1):m_c_cpu1_sb_dq(9)';
NODE_NAME     U1 AC31
 '@S9S_MB_2U_LIB.S9S_MB_2U(SCH_1):PAGE53_I91@PURE_QUANTA.SOCKET4677_AZIF0045P001C01CS(CHIPS)':
 'DDR2_SB_DQ9': CDS_PINID='DDR2_SB_DQ9';
NODE_NAME     J21 113
 '@S9S_MB_2U_LIB.S9S_MB_2U(SCH_1):PAGE102_I13@PURE_QUANTA.SCONN288_ADR50017P130CC(CHIPS)':
 'DQ9_B': CDS_PINID='DQ9_B';
NODE_NAME     J22 113
 '@S9S_MB_2U_LIB.S9S_MB_2U(SCH_1):PAGE103_I51@PURE_QUANTA.SCONN288_ADR50017P087CC(CHIPS)':
 'DQ9_B': CDS_PINID='DQ9_B';
NET_NAME
'M_C_CPU1_SB_DQS_DN<0>'
 '@S9S_MB_2U_LIB.S9S_MB_2U(SCH_1):M_C_CPU1_SB_DQS_DN'<0>:
 C_SIGNAL='@s9s_mb_2u_lib.s9s_mb_2u(sch_1):m_c_cpu1_sb_dqs_dn(0)';
NODE_NAME     U1 AB36
 '@S9S_MB_2U_LIB.S9S_MB_2U(SCH_1):PAGE53_I91@PURE_QUANTA.SOCKET4677_AZIF0045P001C01CS(CHIPS)':
 'DDR2_SB_DQS_DN0': CDS_PINID='DDR2_SB_DQS_DN0';
NODE_NAME     J21 105
 '@S9S_MB_2U_LIB.S9S_MB_2U(SCH_1):PAGE102_I178@PURE_QUANTA.SCONN288_ADR50017P130CC(CHIPS)':
 'DQS0_B_C': CDS_PINID='DQS0_B_C';
NODE_NAME     J22 105
 '@S9S_MB_2U_LIB.S9S_MB_2U(SCH_1):PAGE103_I178@PURE_QUANTA.SCONN288_ADR50017P087CC(CHIPS)':
 'DQS0_B_C': CDS_PINID='DQS0_B_C';
NET_NAME
'M_C_CPU1_SB_DQS_DN<1>'
 '@S9S_MB_2U_LIB.S9S_MB_2U(SCH_1):M_C_CPU1_SB_DQS_DN'<1>:
 C_SIGNAL='@s9s_mb_2u_lib.s9s_mb_2u(sch_1):m_c_cpu1_sb_dqs_dn(1)';
NODE_NAME     U1 AB30
 '@S9S_MB_2U_LIB.S9S_MB_2U(SCH_1):PAGE53_I91@PURE_QUANTA.SOCKET4677_AZIF0045P001C01CS(CHIPS)':
 'DDR2_SB_DQS_DN1': CDS_PINID='DDR2_SB_DQS_DN1';
NODE_NAME     J21 116
 '@S9S_MB_2U_LIB.S9S_MB_2U(SCH_1):PAGE102_I178@PURE_QUANTA.SCONN288_ADR50017P130CC(CHIPS)':
 'DQS1_B_C': CDS_PINID='DQS1_B_C';
NODE_NAME     J22 116
 '@S9S_MB_2U_LIB.S9S_MB_2U(SCH_1):PAGE103_I178@PURE_QUANTA.SCONN288_ADR50017P087CC(CHIPS)':
 'DQS1_B_C': CDS_PINID='DQS1_B_C';
NET_NAME
'M_C_CPU1_SB_DQS_DN<2>'
 '@S9S_MB_2U_LIB.S9S_MB_2U(SCH_1):M_C_CPU1_SB_DQS_DN'<2>:
 C_SIGNAL='@s9s_mb_2u_lib.s9s_mb_2u(sch_1):m_c_cpu1_sb_dqs_dn(2)';
NODE_NAME     U1 R21
 '@S9S_MB_2U_LIB.S9S_MB_2U(SCH_1):PAGE53_I91@PURE_QUANTA.SOCKET4677_AZIF0045P001C01CS(CHIPS)':
 'DDR2_SB_DQS_DN2': CDS_PINID='DDR2_SB_DQS_DN2';
NODE_NAME     J21 127
 '@S9S_MB_2U_LIB.S9S_MB_2U(SCH_1):PAGE102_I178@PURE_QUANTA.SCONN288_ADR50017P130CC(CHIPS)':
 'DQS2_B_C': CDS_PINID='DQS2_B_C';
NODE_NAME     J22 127
 '@S9S_MB_2U_LIB.S9S_MB_2U(SCH_1):PAGE103_I178@PURE_QUANTA.SCONN288_ADR50017P087CC(CHIPS)':
 'DQS2_B_C': CDS_PINID='DQS2_B_C';
NET_NAME
'M_C_CPU1_SB_DQS_DN<3>'
 '@S9S_MB_2U_LIB.S9S_MB_2U(SCH_1):M_C_CPU1_SB_DQS_DN'<3>:
 C_SIGNAL='@s9s_mb_2u_lib.s9s_mb_2u(sch_1):m_c_cpu1_sb_dqs_dn(3)';
NODE_NAME     U1 AB18
 '@S9S_MB_2U_LIB.S9S_MB_2U(SCH_1):PAGE53_I91@PURE_QUANTA.SOCKET4677_AZIF0045P001C01CS(CHIPS)':
 'DDR2_SB_DQS_DN3': CDS_PINID='DDR2_SB_DQS_DN3';
NODE_NAME     J21 138
 '@S9S_MB_2U_LIB.S9S_MB_2U(SCH_1):PAGE102_I178@PURE_QUANTA.SCONN288_ADR50017P130CC(CHIPS)':
 'DQS3_B_C': CDS_PINID='DQS3_B_C';
NODE_NAME     J22 138
 '@S9S_MB_2U_LIB.S9S_MB_2U(SCH_1):PAGE103_I178@PURE_QUANTA.SCONN288_ADR50017P087CC(CHIPS)':
 'DQS3_B_C': CDS_PINID='DQS3_B_C';
NET_NAME
'M_C_CPU1_SB_DQS_DN<4>'
 '@S9S_MB_2U_LIB.S9S_MB_2U(SCH_1):M_C_CPU1_SB_DQS_DN'<4>:
 C_SIGNAL='@s9s_mb_2u_lib.s9s_mb_2u(sch_1):m_c_cpu1_sb_dqs_dn(4)';
NODE_NAME     U1 W33
 '@S9S_MB_2U_LIB.S9S_MB_2U(SCH_1):PAGE53_I91@PURE_QUANTA.SOCKET4677_AZIF0045P001C01CS(CHIPS)':
 'DDR2_SB_DQS_DN4': CDS_PINID='DDR2_SB_DQS_DN4';
NODE_NAME     J21 238
 '@S9S_MB_2U_LIB.S9S_MB_2U(SCH_1):PAGE102_I178@PURE_QUANTA.SCONN288_ADR50017P130CC(CHIPS)':
 'DQS4_B_C': CDS_PINID='DQS4_B_C';
NODE_NAME     J22 238
 '@S9S_MB_2U_LIB.S9S_MB_2U(SCH_1):PAGE103_I178@PURE_QUANTA.SCONN288_ADR50017P087CC(CHIPS)':
 'DQS4_B_C': CDS_PINID='DQS4_B_C';
NET_NAME
'M_C_CPU1_SB_DQS_DN<5>'
 '@S9S_MB_2U_LIB.S9S_MB_2U(SCH_1):M_C_CPU1_SB_DQS_DN'<5>:
 C_SIGNAL='@s9s_mb_2u_lib.s9s_mb_2u(sch_1):m_c_cpu1_sb_dqs_dn(5)';
NODE_NAME     U1 AF36
 '@S9S_MB_2U_LIB.S9S_MB_2U(SCH_1):PAGE53_I91@PURE_QUANTA.SOCKET4677_AZIF0045P001C01CS(CHIPS)':
 'DDR2_SB_DQS_DN5': CDS_PINID='DDR2_SB_DQS_DN5';
NODE_NAME     J21 249
 '@S9S_MB_2U_LIB.S9S_MB_2U(SCH_1):PAGE102_I178@PURE_QUANTA.SCONN288_ADR50017P130CC(CHIPS)':
 'DQS5_B_C||TDQS5_B_C': CDS_PINID='\dqs5_b_c||tdqs5_b_c\';
NODE_NAME     J22 249
 '@S9S_MB_2U_LIB.S9S_MB_2U(SCH_1):PAGE103_I178@PURE_QUANTA.SCONN288_ADR50017P087CC(CHIPS)':
 'DQS5_B_C||TDQS5_B_C': CDS_PINID='\dqs5_b_c||tdqs5_b_c\';
NET_NAME
'M_C_CPU1_SB_DQS_DN<6>'
 '@S9S_MB_2U_LIB.S9S_MB_2U(SCH_1):M_C_CPU1_SB_DQS_DN'<6>:
 C_SIGNAL='@s9s_mb_2u_lib.s9s_mb_2u(sch_1):m_c_cpu1_sb_dqs_dn(6)';
NODE_NAME     U1 AF30
 '@S9S_MB_2U_LIB.S9S_MB_2U(SCH_1):PAGE53_I91@PURE_QUANTA.SOCKET4677_AZIF0045P001C01CS(CHIPS)':
 'DDR2_SB_DQS_DN6': CDS_PINID='DDR2_SB_DQS_DN6';
NODE_NAME     J21 260
 '@S9S_MB_2U_LIB.S9S_MB_2U(SCH_1):PAGE102_I178@PURE_QUANTA.SCONN288_ADR50017P130CC(CHIPS)':
 'DQS6_B_C||TDQS6_B_C': CDS_PINID='\dqs6_b_c||tdqs6_b_c\';
NODE_NAME     J22 260
 '@S9S_MB_2U_LIB.S9S_MB_2U(SCH_1):PAGE103_I178@PURE_QUANTA.SCONN288_ADR50017P087CC(CHIPS)':
 'DQS6_B_C||TDQS6_B_C': CDS_PINID='\dqs6_b_c||tdqs6_b_c\';
NET_NAME
'M_C_CPU1_SB_DQS_DN<7>'
 '@S9S_MB_2U_LIB.S9S_MB_2U(SCH_1):M_C_CPU1_SB_DQS_DN'<7>:
 C_SIGNAL='@s9s_mb_2u_lib.s9s_mb_2u(sch_1):m_c_cpu1_sb_dqs_dn(7)';
NODE_NAME     U1 W21
 '@S9S_MB_2U_LIB.S9S_MB_2U(SCH_1):PAGE53_I91@PURE_QUANTA.SOCKET4677_AZIF0045P001C01CS(CHIPS)':
 'DDR2_SB_DQS_DN7': CDS_PINID='DDR2_SB_DQS_DN7';
NODE_NAME     J21 271
 '@S9S_MB_2U_LIB.S9S_MB_2U(SCH_1):PAGE102_I178@PURE_QUANTA.SCONN288_ADR50017P130CC(CHIPS)':
 'DQS7_B_C||TDQS7_B_C': CDS_PINID='\dqs7_b_c||tdqs7_b_c\';
NODE_NAME     J22 271
 '@S9S_MB_2U_LIB.S9S_MB_2U(SCH_1):PAGE103_I178@PURE_QUANTA.SCONN288_ADR50017P087CC(CHIPS)':
 'DQS7_B_C||TDQS7_B_C': CDS_PINID='\dqs7_b_c||tdqs7_b_c\';
NET_NAME
'M_C_CPU1_SB_DQS_DN<8>'
 '@S9S_MB_2U_LIB.S9S_MB_2U(SCH_1):M_C_CPU1_SB_DQS_DN'<8>:
 C_SIGNAL='@s9s_mb_2u_lib.s9s_mb_2u(sch_1):m_c_cpu1_sb_dqs_dn(8)';
NODE_NAME     U1 AF18
 '@S9S_MB_2U_LIB.S9S_MB_2U(SCH_1):PAGE53_I91@PURE_QUANTA.SOCKET4677_AZIF0045P001C01CS(CHIPS)':
 'DDR2_SB_DQS_DN8': CDS_PINID='DDR2_SB_DQS_DN8';
NODE_NAME     J21 282
 '@S9S_MB_2U_LIB.S9S_MB_2U(SCH_1):PAGE102_I178@PURE_QUANTA.SCONN288_ADR50017P130CC(CHIPS)':
 'DQS8_B_C||TDQS8_B_C': CDS_PINID='\dqs8_b_c||tdqs8_b_c\';
NODE_NAME     J22 282
 '@S9S_MB_2U_LIB.S9S_MB_2U(SCH_1):PAGE103_I178@PURE_QUANTA.SCONN288_ADR50017P087CC(CHIPS)':
 'DQS8_B_C||TDQS8_B_C': CDS_PINID='\dqs8_b_c||tdqs8_b_c\';
NET_NAME
'M_C_CPU1_SB_DQS_DN<9>'
 '@S9S_MB_2U_LIB.S9S_MB_2U(SCH_1):M_C_CPU1_SB_DQS_DN'<9>:
 C_SIGNAL='@s9s_mb_2u_lib.s9s_mb_2u(sch_1):m_c_cpu1_sb_dqs_dn(9)';
NODE_NAME     U1 R33
 '@S9S_MB_2U_LIB.S9S_MB_2U(SCH_1):PAGE53_I91@PURE_QUANTA.SOCKET4677_AZIF0045P001C01CS(CHIPS)':
 'DDR2_SB_DQS_DN9': CDS_PINID='DDR2_SB_DQS_DN9';
NODE_NAME     J21 94
 '@S9S_MB_2U_LIB.S9S_MB_2U(SCH_1):PAGE102_I178@PURE_QUANTA.SCONN288_ADR50017P130CC(CHIPS)':
 'DQS9_B_C||TDQS9_B_C': CDS_PINID='\dqs9_b_c||tdqs9_b_c\';
NODE_NAME     J22 94
 '@S9S_MB_2U_LIB.S9S_MB_2U(SCH_1):PAGE103_I178@PURE_QUANTA.SCONN288_ADR50017P087CC(CHIPS)':
 'DQS9_B_C||TDQS9_B_C': CDS_PINID='\dqs9_b_c||tdqs9_b_c\';
NET_NAME
'M_C_CPU1_SB_DQS_DP<0>'
 '@S9S_MB_2U_LIB.S9S_MB_2U(SCH_1):M_C_CPU1_SB_DQS_DP'<0>:
 C_SIGNAL='@s9s_mb_2u_lib.s9s_mb_2u(sch_1):m_c_cpu1_sb_dqs_dp(0)';
NODE_NAME     U1 AD36
 '@S9S_MB_2U_LIB.S9S_MB_2U(SCH_1):PAGE53_I91@PURE_QUANTA.SOCKET4677_AZIF0045P001C01CS(CHIPS)':
 'DDR2_SB_DQS_DP0': CDS_PINID='DDR2_SB_DQS_DP0';
NODE_NAME     J21 104
 '@S9S_MB_2U_LIB.S9S_MB_2U(SCH_1):PAGE102_I178@PURE_QUANTA.SCONN288_ADR50017P130CC(CHIPS)':
 'DQS0_B_T': CDS_PINID='DQS0_B_T';
NODE_NAME     J22 104
 '@S9S_MB_2U_LIB.S9S_MB_2U(SCH_1):PAGE103_I178@PURE_QUANTA.SCONN288_ADR50017P087CC(CHIPS)':
 'DQS0_B_T': CDS_PINID='DQS0_B_T';
NET_NAME
'M_C_CPU1_SB_DQS_DP<1>'
 '@S9S_MB_2U_LIB.S9S_MB_2U(SCH_1):M_C_CPU1_SB_DQS_DP'<1>:
 C_SIGNAL='@s9s_mb_2u_lib.s9s_mb_2u(sch_1):m_c_cpu1_sb_dqs_dp(1)';
NODE_NAME     U1 AD30
 '@S9S_MB_2U_LIB.S9S_MB_2U(SCH_1):PAGE53_I91@PURE_QUANTA.SOCKET4677_AZIF0045P001C01CS(CHIPS)':
 'DDR2_SB_DQS_DP1': CDS_PINID='DDR2_SB_DQS_DP1';
NODE_NAME     J21 115
 '@S9S_MB_2U_LIB.S9S_MB_2U(SCH_1):PAGE102_I178@PURE_QUANTA.SCONN288_ADR50017P130CC(CHIPS)':
 'DQS1_B_T': CDS_PINID='DQS1_B_T';
NODE_NAME     J22 115
 '@S9S_MB_2U_LIB.S9S_MB_2U(SCH_1):PAGE103_I178@PURE_QUANTA.SCONN288_ADR50017P087CC(CHIPS)':
 'DQS1_B_T': CDS_PINID='DQS1_B_T';
NET_NAME
'M_C_CPU1_SB_DQS_DP<2>'
 '@S9S_MB_2U_LIB.S9S_MB_2U(SCH_1):M_C_CPU1_SB_DQS_DP'<2>:
 C_SIGNAL='@s9s_mb_2u_lib.s9s_mb_2u(sch_1):m_c_cpu1_sb_dqs_dp(2)';
NODE_NAME     U1 U21
 '@S9S_MB_2U_LIB.S9S_MB_2U(SCH_1):PAGE53_I91@PURE_QUANTA.SOCKET4677_AZIF0045P001C01CS(CHIPS)':
 'DDR2_SB_DQS_DP2': CDS_PINID='DDR2_SB_DQS_DP2';
NODE_NAME     J21 126
 '@S9S_MB_2U_LIB.S9S_MB_2U(SCH_1):PAGE102_I178@PURE_QUANTA.SCONN288_ADR50017P130CC(CHIPS)':
 'DQS2_B_T': CDS_PINID='DQS2_B_T';
NODE_NAME     J22 126
 '@S9S_MB_2U_LIB.S9S_MB_2U(SCH_1):PAGE103_I178@PURE_QUANTA.SCONN288_ADR50017P087CC(CHIPS)':
 'DQS2_B_T': CDS_PINID='DQS2_B_T';
NET_NAME
'M_C_CPU1_SB_DQS_DP<3>'
 '@S9S_MB_2U_LIB.S9S_MB_2U(SCH_1):M_C_CPU1_SB_DQS_DP'<3>:
 C_SIGNAL='@s9s_mb_2u_lib.s9s_mb_2u(sch_1):m_c_cpu1_sb_dqs_dp(3)';
NODE_NAME     U1 AD18
 '@S9S_MB_2U_LIB.S9S_MB_2U(SCH_1):PAGE53_I91@PURE_QUANTA.SOCKET4677_AZIF0045P001C01CS(CHIPS)':
 'DDR2_SB_DQS_DP3': CDS_PINID='DDR2_SB_DQS_DP3';
NODE_NAME     J21 137
 '@S9S_MB_2U_LIB.S9S_MB_2U(SCH_1):PAGE102_I178@PURE_QUANTA.SCONN288_ADR50017P130CC(CHIPS)':
 'DQS3_B_T': CDS_PINID='DQS3_B_T';
NODE_NAME     J22 137
 '@S9S_MB_2U_LIB.S9S_MB_2U(SCH_1):PAGE103_I178@PURE_QUANTA.SCONN288_ADR50017P087CC(CHIPS)':
 'DQS3_B_T': CDS_PINID='DQS3_B_T';
NET_NAME
'M_C_CPU1_SB_DQS_DP<4>'
 '@S9S_MB_2U_LIB.S9S_MB_2U(SCH_1):M_C_CPU1_SB_DQS_DP'<4>:
 C_SIGNAL='@s9s_mb_2u_lib.s9s_mb_2u(sch_1):m_c_cpu1_sb_dqs_dp(4)';
NODE_NAME     U1 AA33
 '@S9S_MB_2U_LIB.S9S_MB_2U(SCH_1):PAGE53_I91@PURE_QUANTA.SOCKET4677_AZIF0045P001C01CS(CHIPS)':
 'DDR2_SB_DQS_DP4': CDS_PINID='DDR2_SB_DQS_DP4';
NODE_NAME     J21 239
 '@S9S_MB_2U_LIB.S9S_MB_2U(SCH_1):PAGE102_I178@PURE_QUANTA.SCONN288_ADR50017P130CC(CHIPS)':
 'DQS4_B_T': CDS_PINID='DQS4_B_T';
NODE_NAME     J22 239
 '@S9S_MB_2U_LIB.S9S_MB_2U(SCH_1):PAGE103_I178@PURE_QUANTA.SCONN288_ADR50017P087CC(CHIPS)':
 'DQS4_B_T': CDS_PINID='DQS4_B_T';
NET_NAME
'M_C_CPU1_SB_DQS_DP<5>'
 '@S9S_MB_2U_LIB.S9S_MB_2U(SCH_1):M_C_CPU1_SB_DQS_DP'<5>:
 C_SIGNAL='@s9s_mb_2u_lib.s9s_mb_2u(sch_1):m_c_cpu1_sb_dqs_dp(5)';
NODE_NAME     U1 AH36
 '@S9S_MB_2U_LIB.S9S_MB_2U(SCH_1):PAGE53_I91@PURE_QUANTA.SOCKET4677_AZIF0045P001C01CS(CHIPS)':
 'DDR2_SB_DQS_DP5': CDS_PINID='DDR2_SB_DQS_DP5';
NODE_NAME     J21 250
 '@S9S_MB_2U_LIB.S9S_MB_2U(SCH_1):PAGE102_I178@PURE_QUANTA.SCONN288_ADR50017P130CC(CHIPS)':
 'DQS5_B_T||TDQS5_B_T': CDS_PINID='\dqs5_b_t||tdqs5_b_t\';
NODE_NAME     J22 250
 '@S9S_MB_2U_LIB.S9S_MB_2U(SCH_1):PAGE103_I178@PURE_QUANTA.SCONN288_ADR50017P087CC(CHIPS)':
 'DQS5_B_T||TDQS5_B_T': CDS_PINID='\dqs5_b_t||tdqs5_b_t\';
NET_NAME
'M_C_CPU1_SB_DQS_DP<6>'
 '@S9S_MB_2U_LIB.S9S_MB_2U(SCH_1):M_C_CPU1_SB_DQS_DP'<6>:
 C_SIGNAL='@s9s_mb_2u_lib.s9s_mb_2u(sch_1):m_c_cpu1_sb_dqs_dp(6)';
NODE_NAME     U1 AH30
 '@S9S_MB_2U_LIB.S9S_MB_2U(SCH_1):PAGE53_I91@PURE_QUANTA.SOCKET4677_AZIF0045P001C01CS(CHIPS)':
 'DDR2_SB_DQS_DP6': CDS_PINID='DDR2_SB_DQS_DP6';
NODE_NAME     J21 261
 '@S9S_MB_2U_LIB.S9S_MB_2U(SCH_1):PAGE102_I178@PURE_QUANTA.SCONN288_ADR50017P130CC(CHIPS)':
 'DQS6_B_T||TDQS6_B_T': CDS_PINID='\dqs6_b_t||tdqs6_b_t\';
NODE_NAME     J22 261
 '@S9S_MB_2U_LIB.S9S_MB_2U(SCH_1):PAGE103_I178@PURE_QUANTA.SCONN288_ADR50017P087CC(CHIPS)':
 'DQS6_B_T||TDQS6_B_T': CDS_PINID='\dqs6_b_t||tdqs6_b_t\';
NET_NAME
'M_C_CPU1_SB_DQS_DP<7>'
 '@S9S_MB_2U_LIB.S9S_MB_2U(SCH_1):M_C_CPU1_SB_DQS_DP'<7>:
 C_SIGNAL='@s9s_mb_2u_lib.s9s_mb_2u(sch_1):m_c_cpu1_sb_dqs_dp(7)';
NODE_NAME     U1 AA21
 '@S9S_MB_2U_LIB.S9S_MB_2U(SCH_1):PAGE53_I91@PURE_QUANTA.SOCKET4677_AZIF0045P001C01CS(CHIPS)':
 'DDR2_SB_DQS_DP7': CDS_PINID='DDR2_SB_DQS_DP7';
NODE_NAME     J21 272
 '@S9S_MB_2U_LIB.S9S_MB_2U(SCH_1):PAGE102_I178@PURE_QUANTA.SCONN288_ADR50017P130CC(CHIPS)':
 'DQS7_B_T||TDQS7_B_T': CDS_PINID='\dqs7_b_t||tdqs7_b_t\';
NODE_NAME     J22 272
 '@S9S_MB_2U_LIB.S9S_MB_2U(SCH_1):PAGE103_I178@PURE_QUANTA.SCONN288_ADR50017P087CC(CHIPS)':
 'DQS7_B_T||TDQS7_B_T': CDS_PINID='\dqs7_b_t||tdqs7_b_t\';
NET_NAME
'M_C_CPU1_SB_DQS_DP<8>'
 '@S9S_MB_2U_LIB.S9S_MB_2U(SCH_1):M_C_CPU1_SB_DQS_DP'<8>:
 C_SIGNAL='@s9s_mb_2u_lib.s9s_mb_2u(sch_1):m_c_cpu1_sb_dqs_dp(8)';
NODE_NAME     U1 AH18
 '@S9S_MB_2U_LIB.S9S_MB_2U(SCH_1):PAGE53_I91@PURE_QUANTA.SOCKET4677_AZIF0045P001C01CS(CHIPS)':
 'DDR2_SB_DQS_DP8': CDS_PINID='DDR2_SB_DQS_DP8';
NODE_NAME     J21 283
 '@S9S_MB_2U_LIB.S9S_MB_2U(SCH_1):PAGE102_I178@PURE_QUANTA.SCONN288_ADR50017P130CC(CHIPS)':
 'DQS8_B_T||TDQS8_B_T': CDS_PINID='\dqs8_b_t||tdqs8_b_t\';
NODE_NAME     J22 283
 '@S9S_MB_2U_LIB.S9S_MB_2U(SCH_1):PAGE103_I178@PURE_QUANTA.SCONN288_ADR50017P087CC(CHIPS)':
 'DQS8_B_T||TDQS8_B_T': CDS_PINID='\dqs8_b_t||tdqs8_b_t\';
NET_NAME
'M_C_CPU1_SB_DQS_DP<9>'
 '@S9S_MB_2U_LIB.S9S_MB_2U(SCH_1):M_C_CPU1_SB_DQS_DP'<9>:
 C_SIGNAL='@s9s_mb_2u_lib.s9s_mb_2u(sch_1):m_c_cpu1_sb_dqs_dp(9)';
NODE_NAME     U1 U33
 '@S9S_MB_2U_LIB.S9S_MB_2U(SCH_1):PAGE53_I91@PURE_QUANTA.SOCKET4677_AZIF0045P001C01CS(CHIPS)':
 'DDR2_SB_DQS_DP9': CDS_PINID='DDR2_SB_DQS_DP9';
NODE_NAME     J21 93
 '@S9S_MB_2U_LIB.S9S_MB_2U(SCH_1):PAGE102_I178@PURE_QUANTA.SCONN288_ADR50017P130CC(CHIPS)':
 'DQS9_B_T||TDQS9_B_T||DBI4_B_N': CDS_PINID='\dqs9_b_t||tdqs9_b_t||dbi4_b_n\';
NODE_NAME     J22 93
 '@S9S_MB_2U_LIB.S9S_MB_2U(SCH_1):PAGE103_I178@PURE_QUANTA.SCONN288_ADR50017P087CC(CHIPS)':
 'DQS9_B_T||TDQS9_B_T||DBI4_B_N': CDS_PINID='\dqs9_b_t||tdqs9_b_t||dbi4_b_n\';
NET_NAME
'M_C_CPU1_SB_PAR'
 '@S9S_MB_2U_LIB.S9S_MB_2U(SCH_1):M_C_CPU1_SB_PAR':
 C_SIGNAL='@s9s_mb_2u_lib.s9s_mb_2u(sch_1):m_c_cpu1_sb_par';
NODE_NAME     U1 AA39
 '@S9S_MB_2U_LIB.S9S_MB_2U(SCH_1):PAGE53_I91@PURE_QUANTA.SOCKET4677_AZIF0045P001C01CS(CHIPS)':
 'DDR2_SB_PAR': CDS_PINID='DDR2_SB_PAR';
NODE_NAME     J21 227
 '@S9S_MB_2U_LIB.S9S_MB_2U(SCH_1):PAGE102_I13@PURE_QUANTA.SCONN288_ADR50017P130CC(CHIPS)':
 'PAR_B': CDS_PINID='PAR_B';
NODE_NAME     J22 227
 '@S9S_MB_2U_LIB.S9S_MB_2U(SCH_1):PAGE103_I51@PURE_QUANTA.SCONN288_ADR50017P087CC(CHIPS)':
 'PAR_B': CDS_PINID='PAR_B';
NET_NAME
'M_C_CPU1_SB_RSP<0>'
 '@S9S_MB_2U_LIB.S9S_MB_2U(SCH_1):M_C_CPU1_SB_RSP'<0>:
 C_SIGNAL='@s9s_mb_2u_lib.s9s_mb_2u(sch_1):m_c_cpu1_sb_rsp(0)';
NODE_NAME     U1 AG48
 '@S9S_MB_2U_LIB.S9S_MB_2U(SCH_1):PAGE53_I91@PURE_QUANTA.SOCKET4677_AZIF0045P001C01CS(CHIPS)':
 'DDR2_B_RSP0': CDS_PINID='DDR2_B_RSP0';
NODE_NAME     J21 87
 '@S9S_MB_2U_LIB.S9S_MB_2U(SCH_1):PAGE102_I13@PURE_QUANTA.SCONN288_ADR50017P130CC(CHIPS)':
 'LBS||RSP_B_N': CDS_PINID='\lbs||rsp_b_n\';
NET_NAME
'M_C_CPU1_SB_RSP<1>'
 '@S9S_MB_2U_LIB.S9S_MB_2U(SCH_1):M_C_CPU1_SB_RSP'<1>:
 C_SIGNAL='@s9s_mb_2u_lib.s9s_mb_2u(sch_1):m_c_cpu1_sb_rsp(1)';
NODE_NAME     U1 AF47
 '@S9S_MB_2U_LIB.S9S_MB_2U(SCH_1):PAGE53_I91@PURE_QUANTA.SOCKET4677_AZIF0045P001C01CS(CHIPS)':
 'DDR2_B_RSP1': CDS_PINID='DDR2_B_RSP1';
NODE_NAME     J22 87
 '@S9S_MB_2U_LIB.S9S_MB_2U(SCH_1):PAGE103_I51@PURE_QUANTA.SCONN288_ADR50017P087CC(CHIPS)':
 'LBS||RSP_B_N': CDS_PINID='\lbs||rsp_b_n\';
NET_NAME
'M_D_CPU0_ALERT_N'
 '@S9S_MB_2U_LIB.S9S_MB_2U(SCH_1):M_D_CPU0_ALERT_N':
 C_SIGNAL='@s9s_mb_2u_lib.s9s_mb_2u(sch_1):m_d_cpu0_alert_n';
NODE_NAME     U2 AV47
 '@S9S_MB_2U_LIB.S9S_MB_2U(SCH_1):PAGE23_I169@PURE_QUANTA.SOCKET4677_AZIF0045P001C01CS(CHIPS)':
 'DDR3_ALERT_N': CDS_PINID='DDR3_ALERT_N';
NODE_NAME     J7 62
 '@S9S_MB_2U_LIB.S9S_MB_2U(SCH_1):PAGE88_I12@PURE_QUANTA.SCONN288_ADR50017P130CC(CHIPS)':
 'ALERT_N': CDS_PINID='ALERT_N';
NODE_NAME     J8 62
 '@S9S_MB_2U_LIB.S9S_MB_2U(SCH_1):PAGE89_I50@PURE_QUANTA.SCONN288_ADR50017P087CC(CHIPS)':
 'ALERT_N': CDS_PINID='ALERT_N';
NET_NAME
'M_D_CPU0_CLK_DN<0>'
 '@S9S_MB_2U_LIB.S9S_MB_2U(SCH_1):M_D_CPU0_CLK_DN'<0>:
 C_SIGNAL='@s9s_mb_2u_lib.s9s_mb_2u(sch_1):m_d_cpu0_clk_dn(0)';
NODE_NAME     U2 AJ45
 '@S9S_MB_2U_LIB.S9S_MB_2U(SCH_1):PAGE23_I169@PURE_QUANTA.SOCKET4677_AZIF0045P001C01CS(CHIPS)':
 'DDR3_CLK_DN0': CDS_PINID='DDR3_CLK_DN0';
NODE_NAME     J7 218
 '@S9S_MB_2U_LIB.S9S_MB_2U(SCH_1):PAGE88_I12@PURE_QUANTA.SCONN288_ADR50017P130CC(CHIPS)':
 'CK_C': CDS_PINID='CK_C';
NET_NAME
'M_D_CPU0_CLK_DN<1>'
 '@S9S_MB_2U_LIB.S9S_MB_2U(SCH_1):M_D_CPU0_CLK_DN'<1>:
 C_SIGNAL='@s9s_mb_2u_lib.s9s_mb_2u(sch_1):m_d_cpu0_clk_dn(1)';
NODE_NAME     U2 AN45
 '@S9S_MB_2U_LIB.S9S_MB_2U(SCH_1):PAGE23_I169@PURE_QUANTA.SOCKET4677_AZIF0045P001C01CS(CHIPS)':
 'DDR3_CLK_DN1': CDS_PINID='DDR3_CLK_DN1';
NODE_NAME     J8 218
 '@S9S_MB_2U_LIB.S9S_MB_2U(SCH_1):PAGE89_I50@PURE_QUANTA.SCONN288_ADR50017P087CC(CHIPS)':
 'CK_C': CDS_PINID='CK_C';
NET_NAME
'M_D_CPU0_CLK_DP<0>'
 '@S9S_MB_2U_LIB.S9S_MB_2U(SCH_1):M_D_CPU0_CLK_DP'<0>:
 C_SIGNAL='@s9s_mb_2u_lib.s9s_mb_2u(sch_1):m_d_cpu0_clk_dp(0)';
NODE_NAME     U2 AL45
 '@S9S_MB_2U_LIB.S9S_MB_2U(SCH_1):PAGE23_I169@PURE_QUANTA.SOCKET4677_AZIF0045P001C01CS(CHIPS)':
 'DDR3_CLK_DP0': CDS_PINID='DDR3_CLK_DP0';
NODE_NAME     J7 217
 '@S9S_MB_2U_LIB.S9S_MB_2U(SCH_1):PAGE88_I12@PURE_QUANTA.SCONN288_ADR50017P130CC(CHIPS)':
 'CK_T': CDS_PINID='CK_T';
NET_NAME
'M_D_CPU0_CLK_DP<1>'
 '@S9S_MB_2U_LIB.S9S_MB_2U(SCH_1):M_D_CPU0_CLK_DP'<1>:
 C_SIGNAL='@s9s_mb_2u_lib.s9s_mb_2u(sch_1):m_d_cpu0_clk_dp(1)';
NODE_NAME     U2 AR45
 '@S9S_MB_2U_LIB.S9S_MB_2U(SCH_1):PAGE23_I169@PURE_QUANTA.SOCKET4677_AZIF0045P001C01CS(CHIPS)':
 'DDR3_CLK_DP1': CDS_PINID='DDR3_CLK_DP1';
NODE_NAME     J8 217
 '@S9S_MB_2U_LIB.S9S_MB_2U(SCH_1):PAGE89_I50@PURE_QUANTA.SCONN288_ADR50017P087CC(CHIPS)':
 'CK_T': CDS_PINID='CK_T';
NET_NAME
'M_D_CPU0_SA_CA<0>'
 '@S9S_MB_2U_LIB.S9S_MB_2U(SCH_1):M_D_CPU0_SA_CA'<0>:
 C_SIGNAL='@s9s_mb_2u_lib.s9s_mb_2u(sch_1):m_d_cpu0_sa_ca(0)';
NODE_NAME     U2 AJ52
 '@S9S_MB_2U_LIB.S9S_MB_2U(SCH_1):PAGE23_I169@PURE_QUANTA.SOCKET4677_AZIF0045P001C01CS(CHIPS)':
 'DDR3_SA_CA0': CDS_PINID='DDR3_SA_CA0';
NODE_NAME     J7 66
 '@S9S_MB_2U_LIB.S9S_MB_2U(SCH_1):PAGE88_I12@PURE_QUANTA.SCONN288_ADR50017P130CC(CHIPS)':
 'CA0_A': CDS_PINID='CA0_A';
NODE_NAME     J8 66
 '@S9S_MB_2U_LIB.S9S_MB_2U(SCH_1):PAGE89_I50@PURE_QUANTA.SCONN288_ADR50017P087CC(CHIPS)':
 'CA0_A': CDS_PINID='CA0_A';
NET_NAME
'M_D_CPU0_SA_CA<1>'
 '@S9S_MB_2U_LIB.S9S_MB_2U(SCH_1):M_D_CPU0_SA_CA'<1>:
 C_SIGNAL='@s9s_mb_2u_lib.s9s_mb_2u(sch_1):m_d_cpu0_sa_ca(1)';
NODE_NAME     U2 AR52
 '@S9S_MB_2U_LIB.S9S_MB_2U(SCH_1):PAGE23_I169@PURE_QUANTA.SOCKET4677_AZIF0045P001C01CS(CHIPS)':
 'DDR3_SA_CA1': CDS_PINID='DDR3_SA_CA1';
NODE_NAME     J7 211
 '@S9S_MB_2U_LIB.S9S_MB_2U(SCH_1):PAGE88_I12@PURE_QUANTA.SCONN288_ADR50017P130CC(CHIPS)':
 'CA1_A': CDS_PINID='CA1_A';
NODE_NAME     J8 211
 '@S9S_MB_2U_LIB.S9S_MB_2U(SCH_1):PAGE89_I50@PURE_QUANTA.SCONN288_ADR50017P087CC(CHIPS)':
 'CA1_A': CDS_PINID='CA1_A';
NET_NAME
'M_D_CPU0_SA_CA<2>'
 '@S9S_MB_2U_LIB.S9S_MB_2U(SCH_1):M_D_CPU0_SA_CA'<2>:
 C_SIGNAL='@s9s_mb_2u_lib.s9s_mb_2u(sch_1):m_d_cpu0_sa_ca(2)';
NODE_NAME     U2 AK51
 '@S9S_MB_2U_LIB.S9S_MB_2U(SCH_1):PAGE23_I169@PURE_QUANTA.SOCKET4677_AZIF0045P001C01CS(CHIPS)':
 'DDR3_SA_CA2': CDS_PINID='DDR3_SA_CA2';
NODE_NAME     J7 68
 '@S9S_MB_2U_LIB.S9S_MB_2U(SCH_1):PAGE88_I12@PURE_QUANTA.SCONN288_ADR50017P130CC(CHIPS)':
 'CA2_A': CDS_PINID='CA2_A';
NODE_NAME     J8 68
 '@S9S_MB_2U_LIB.S9S_MB_2U(SCH_1):PAGE89_I50@PURE_QUANTA.SCONN288_ADR50017P087CC(CHIPS)':
 'CA2_A': CDS_PINID='CA2_A';
NET_NAME
'M_D_CPU0_SA_CA<3>'
 '@S9S_MB_2U_LIB.S9S_MB_2U(SCH_1):M_D_CPU0_SA_CA'<3>:
 C_SIGNAL='@s9s_mb_2u_lib.s9s_mb_2u(sch_1):m_d_cpu0_sa_ca(3)';
NODE_NAME     U2 AP51
 '@S9S_MB_2U_LIB.S9S_MB_2U(SCH_1):PAGE23_I169@PURE_QUANTA.SOCKET4677_AZIF0045P001C01CS(CHIPS)':
 'DDR3_SA_CA3': CDS_PINID='DDR3_SA_CA3';
NODE_NAME     J7 213
 '@S9S_MB_2U_LIB.S9S_MB_2U(SCH_1):PAGE88_I12@PURE_QUANTA.SCONN288_ADR50017P130CC(CHIPS)':
 'CA3_A': CDS_PINID='CA3_A';
NODE_NAME     J8 213
 '@S9S_MB_2U_LIB.S9S_MB_2U(SCH_1):PAGE89_I50@PURE_QUANTA.SCONN288_ADR50017P087CC(CHIPS)':
 'CA3_A': CDS_PINID='CA3_A';
NET_NAME
'M_D_CPU0_SA_CA<4>'
 '@S9S_MB_2U_LIB.S9S_MB_2U(SCH_1):M_D_CPU0_SA_CA'<4>:
 C_SIGNAL='@s9s_mb_2u_lib.s9s_mb_2u(sch_1):m_d_cpu0_sa_ca(4)';
NODE_NAME     U2 AL50
 '@S9S_MB_2U_LIB.S9S_MB_2U(SCH_1):PAGE23_I169@PURE_QUANTA.SOCKET4677_AZIF0045P001C01CS(CHIPS)':
 'DDR3_SA_CA4': CDS_PINID='DDR3_SA_CA4';
NODE_NAME     J7 70
 '@S9S_MB_2U_LIB.S9S_MB_2U(SCH_1):PAGE88_I12@PURE_QUANTA.SCONN288_ADR50017P130CC(CHIPS)':
 'CA4_A': CDS_PINID='CA4_A';
NODE_NAME     J8 70
 '@S9S_MB_2U_LIB.S9S_MB_2U(SCH_1):PAGE89_I50@PURE_QUANTA.SCONN288_ADR50017P087CC(CHIPS)':
 'CA4_A': CDS_PINID='CA4_A';
NET_NAME
'M_D_CPU0_SA_CA<5>'
 '@S9S_MB_2U_LIB.S9S_MB_2U(SCH_1):M_D_CPU0_SA_CA'<5>:
 C_SIGNAL='@s9s_mb_2u_lib.s9s_mb_2u(sch_1):m_d_cpu0_sa_ca(5)';
NODE_NAME     U2 AN50
 '@S9S_MB_2U_LIB.S9S_MB_2U(SCH_1):PAGE23_I169@PURE_QUANTA.SOCKET4677_AZIF0045P001C01CS(CHIPS)':
 'DDR3_SA_CA5': CDS_PINID='DDR3_SA_CA5';
NODE_NAME     J7 215
 '@S9S_MB_2U_LIB.S9S_MB_2U(SCH_1):PAGE88_I12@PURE_QUANTA.SCONN288_ADR50017P130CC(CHIPS)':
 'CA5_A': CDS_PINID='CA5_A';
NODE_NAME     J8 215
 '@S9S_MB_2U_LIB.S9S_MB_2U(SCH_1):PAGE89_I50@PURE_QUANTA.SCONN288_ADR50017P087CC(CHIPS)':
 'CA5_A': CDS_PINID='CA5_A';
NET_NAME
'M_D_CPU0_SA_CA<6>'
 '@S9S_MB_2U_LIB.S9S_MB_2U(SCH_1):M_D_CPU0_SA_CA'<6>:
 C_SIGNAL='@s9s_mb_2u_lib.s9s_mb_2u(sch_1):m_d_cpu0_sa_ca(6)';
NODE_NAME     U2 AN43
 '@S9S_MB_2U_LIB.S9S_MB_2U(SCH_1):PAGE23_I169@PURE_QUANTA.SOCKET4677_AZIF0045P001C01CS(CHIPS)':
 'DDR3_SA_CA6': CDS_PINID='DDR3_SA_CA6';
NODE_NAME     J7 72
 '@S9S_MB_2U_LIB.S9S_MB_2U(SCH_1):PAGE88_I12@PURE_QUANTA.SCONN288_ADR50017P130CC(CHIPS)':
 'CA6_A': CDS_PINID='CA6_A';
NODE_NAME     J8 72
 '@S9S_MB_2U_LIB.S9S_MB_2U(SCH_1):PAGE89_I50@PURE_QUANTA.SCONN288_ADR50017P087CC(CHIPS)':
 'CA6_A': CDS_PINID='CA6_A';
NET_NAME
'M_D_CPU0_SA_CB<0>'
 '@S9S_MB_2U_LIB.S9S_MB_2U(SCH_1):M_D_CPU0_SA_CB'<0>:
 C_SIGNAL='@s9s_mb_2u_lib.s9s_mb_2u(sch_1):m_d_cpu0_sa_cb(0)';
NODE_NAME     U2 AL60
 '@S9S_MB_2U_LIB.S9S_MB_2U(SCH_1):PAGE23_I169@PURE_QUANTA.SOCKET4677_AZIF0045P001C01CS(CHIPS)':
 'DDR3_SA_ECC0': CDS_PINID='DDR3_SA_ECC0';
NODE_NAME     J7 51
 '@S9S_MB_2U_LIB.S9S_MB_2U(SCH_1):PAGE88_I12@PURE_QUANTA.SCONN288_ADR50017P130CC(CHIPS)':
 'CB0_A': CDS_PINID='CB0_A';
NODE_NAME     J8 51
 '@S9S_MB_2U_LIB.S9S_MB_2U(SCH_1):PAGE89_I50@PURE_QUANTA.SCONN288_ADR50017P087CC(CHIPS)':
 'CB0_A': CDS_PINID='CB0_A';
NET_NAME
'M_D_CPU0_SA_CB<1>'
 '@S9S_MB_2U_LIB.S9S_MB_2U(SCH_1):M_D_CPU0_SA_CB'<1>:
 C_SIGNAL='@s9s_mb_2u_lib.s9s_mb_2u(sch_1):m_d_cpu0_sa_cb(1)';
NODE_NAME     U2 AK59
 '@S9S_MB_2U_LIB.S9S_MB_2U(SCH_1):PAGE23_I169@PURE_QUANTA.SOCKET4677_AZIF0045P001C01CS(CHIPS)':
 'DDR3_SA_ECC1': CDS_PINID='DDR3_SA_ECC1';
NODE_NAME     J7 53
 '@S9S_MB_2U_LIB.S9S_MB_2U(SCH_1):PAGE88_I12@PURE_QUANTA.SCONN288_ADR50017P130CC(CHIPS)':
 'CB1_A': CDS_PINID='CB1_A';
NODE_NAME     J8 53
 '@S9S_MB_2U_LIB.S9S_MB_2U(SCH_1):PAGE89_I50@PURE_QUANTA.SCONN288_ADR50017P087CC(CHIPS)':
 'CB1_A': CDS_PINID='CB1_A';
NET_NAME
'M_D_CPU0_SA_CB<2>'
 '@S9S_MB_2U_LIB.S9S_MB_2U(SCH_1):M_D_CPU0_SA_CB'<2>:
 C_SIGNAL='@s9s_mb_2u_lib.s9s_mb_2u(sch_1):m_d_cpu0_sa_cb(2)';
NODE_NAME     U2 AN60
 '@S9S_MB_2U_LIB.S9S_MB_2U(SCH_1):PAGE23_I169@PURE_QUANTA.SOCKET4677_AZIF0045P001C01CS(CHIPS)':
 'DDR3_SA_ECC2': CDS_PINID='DDR3_SA_ECC2';
NODE_NAME     J7 196
 '@S9S_MB_2U_LIB.S9S_MB_2U(SCH_1):PAGE88_I12@PURE_QUANTA.SCONN288_ADR50017P130CC(CHIPS)':
 'CB2_A': CDS_PINID='CB2_A';
NODE_NAME     J8 196
 '@S9S_MB_2U_LIB.S9S_MB_2U(SCH_1):PAGE89_I50@PURE_QUANTA.SCONN288_ADR50017P087CC(CHIPS)':
 'CB2_A': CDS_PINID='CB2_A';
NET_NAME
'M_D_CPU0_SA_CB<3>'
 '@S9S_MB_2U_LIB.S9S_MB_2U(SCH_1):M_D_CPU0_SA_CB'<3>:
 C_SIGNAL='@s9s_mb_2u_lib.s9s_mb_2u(sch_1):m_d_cpu0_sa_cb(3)';
NODE_NAME     U2 AP59
 '@S9S_MB_2U_LIB.S9S_MB_2U(SCH_1):PAGE23_I169@PURE_QUANTA.SOCKET4677_AZIF0045P001C01CS(CHIPS)':
 'DDR3_SA_ECC3': CDS_PINID='DDR3_SA_ECC3';
NODE_NAME     J7 198
 '@S9S_MB_2U_LIB.S9S_MB_2U(SCH_1):PAGE88_I12@PURE_QUANTA.SCONN288_ADR50017P130CC(CHIPS)':
 'CB3_A': CDS_PINID='CB3_A';
NODE_NAME     J8 198
 '@S9S_MB_2U_LIB.S9S_MB_2U(SCH_1):PAGE89_I50@PURE_QUANTA.SCONN288_ADR50017P087CC(CHIPS)':
 'CB3_A': CDS_PINID='CB3_A';
NET_NAME
'M_D_CPU0_SA_CB<4>'
 '@S9S_MB_2U_LIB.S9S_MB_2U(SCH_1):M_D_CPU0_SA_CB'<4>:
 C_SIGNAL='@s9s_mb_2u_lib.s9s_mb_2u(sch_1):m_d_cpu0_sa_cb(4)';
NODE_NAME     U2 AK57
 '@S9S_MB_2U_LIB.S9S_MB_2U(SCH_1):PAGE23_I169@PURE_QUANTA.SOCKET4677_AZIF0045P001C01CS(CHIPS)':
 'DDR3_SA_ECC4': CDS_PINID='DDR3_SA_ECC4';
NODE_NAME     J7 58
 '@S9S_MB_2U_LIB.S9S_MB_2U(SCH_1):PAGE88_I12@PURE_QUANTA.SCONN288_ADR50017P130CC(CHIPS)':
 'CB4_A': CDS_PINID='CB4_A';
NODE_NAME     J8 58
 '@S9S_MB_2U_LIB.S9S_MB_2U(SCH_1):PAGE89_I50@PURE_QUANTA.SCONN288_ADR50017P087CC(CHIPS)':
 'CB4_A': CDS_PINID='CB4_A';
NET_NAME
'M_D_CPU0_SA_CB<5>'
 '@S9S_MB_2U_LIB.S9S_MB_2U(SCH_1):M_D_CPU0_SA_CB'<5>:
 C_SIGNAL='@s9s_mb_2u_lib.s9s_mb_2u(sch_1):m_d_cpu0_sa_cb(5)';
NODE_NAME     U2 AL56
 '@S9S_MB_2U_LIB.S9S_MB_2U(SCH_1):PAGE23_I169@PURE_QUANTA.SOCKET4677_AZIF0045P001C01CS(CHIPS)':
 'DDR3_SA_ECC5': CDS_PINID='DDR3_SA_ECC5';
NODE_NAME     J7 60
 '@S9S_MB_2U_LIB.S9S_MB_2U(SCH_1):PAGE88_I12@PURE_QUANTA.SCONN288_ADR50017P130CC(CHIPS)':
 'CB5_A': CDS_PINID='CB5_A';
NODE_NAME     J8 60
 '@S9S_MB_2U_LIB.S9S_MB_2U(SCH_1):PAGE89_I50@PURE_QUANTA.SCONN288_ADR50017P087CC(CHIPS)':
 'CB5_A': CDS_PINID='CB5_A';
NET_NAME
'M_D_CPU0_SA_CB<6>'
 '@S9S_MB_2U_LIB.S9S_MB_2U(SCH_1):M_D_CPU0_SA_CB'<6>:
 C_SIGNAL='@s9s_mb_2u_lib.s9s_mb_2u(sch_1):m_d_cpu0_sa_cb(6)';
NODE_NAME     U2 AP57
 '@S9S_MB_2U_LIB.S9S_MB_2U(SCH_1):PAGE23_I169@PURE_QUANTA.SOCKET4677_AZIF0045P001C01CS(CHIPS)':
 'DDR3_SA_ECC6': CDS_PINID='DDR3_SA_ECC6';
NODE_NAME     J7 203
 '@S9S_MB_2U_LIB.S9S_MB_2U(SCH_1):PAGE88_I12@PURE_QUANTA.SCONN288_ADR50017P130CC(CHIPS)':
 'CB6_A': CDS_PINID='CB6_A';
NODE_NAME     J8 203
 '@S9S_MB_2U_LIB.S9S_MB_2U(SCH_1):PAGE89_I50@PURE_QUANTA.SCONN288_ADR50017P087CC(CHIPS)':
 'CB6_A': CDS_PINID='CB6_A';
NET_NAME
'M_D_CPU0_SA_CB<7>'
 '@S9S_MB_2U_LIB.S9S_MB_2U(SCH_1):M_D_CPU0_SA_CB'<7>:
 C_SIGNAL='@s9s_mb_2u_lib.s9s_mb_2u(sch_1):m_d_cpu0_sa_cb(7)';
NODE_NAME     U2 AN56
 '@S9S_MB_2U_LIB.S9S_MB_2U(SCH_1):PAGE23_I169@PURE_QUANTA.SOCKET4677_AZIF0045P001C01CS(CHIPS)':
 'DDR3_SA_ECC7': CDS_PINID='DDR3_SA_ECC7';
NODE_NAME     J7 205
 '@S9S_MB_2U_LIB.S9S_MB_2U(SCH_1):PAGE88_I12@PURE_QUANTA.SCONN288_ADR50017P130CC(CHIPS)':
 'CB7_A': CDS_PINID='CB7_A';
NODE_NAME     J8 205
 '@S9S_MB_2U_LIB.S9S_MB_2U(SCH_1):PAGE89_I50@PURE_QUANTA.SCONN288_ADR50017P087CC(CHIPS)':
 'CB7_A': CDS_PINID='CB7_A';
NET_NAME
'M_D_CPU0_SA_CS_N<0>'
 '@S9S_MB_2U_LIB.S9S_MB_2U(SCH_1):M_D_CPU0_SA_CS_N'<0>:
 C_SIGNAL='@s9s_mb_2u_lib.s9s_mb_2u(sch_1):m_d_cpu0_sa_cs_n(0)';
NODE_NAME     U2 AL54
 '@S9S_MB_2U_LIB.S9S_MB_2U(SCH_1):PAGE23_I169@PURE_QUANTA.SOCKET4677_AZIF0045P001C01CS(CHIPS)':
 'DDR3_SA_CS_N0': CDS_PINID='DDR3_SA_CS_N0';
NODE_NAME     J7 64
 '@S9S_MB_2U_LIB.S9S_MB_2U(SCH_1):PAGE88_I12@PURE_QUANTA.SCONN288_ADR50017P130CC(CHIPS)':
 'CS0_A_N': CDS_PINID='CS0_A_N';
NET_NAME
'M_D_CPU0_SA_CS_N<1>'
 '@S9S_MB_2U_LIB.S9S_MB_2U(SCH_1):M_D_CPU0_SA_CS_N'<1>:
 C_SIGNAL='@s9s_mb_2u_lib.s9s_mb_2u(sch_1):m_d_cpu0_sa_cs_n(1)';
NODE_NAME     U2 AK53
 '@S9S_MB_2U_LIB.S9S_MB_2U(SCH_1):PAGE23_I169@PURE_QUANTA.SOCKET4677_AZIF0045P001C01CS(CHIPS)':
 'DDR3_SA_CS_N1': CDS_PINID='DDR3_SA_CS_N1';
NODE_NAME     J7 209
 '@S9S_MB_2U_LIB.S9S_MB_2U(SCH_1):PAGE88_I12@PURE_QUANTA.SCONN288_ADR50017P130CC(CHIPS)':
 'CS1_A_N': CDS_PINID='CS1_A_N';
NET_NAME
'M_D_CPU0_SA_CS_N<2>'
 '@S9S_MB_2U_LIB.S9S_MB_2U(SCH_1):M_D_CPU0_SA_CS_N'<2>:
 C_SIGNAL='@s9s_mb_2u_lib.s9s_mb_2u(sch_1):m_d_cpu0_sa_cs_n(2)';
NODE_NAME     U2 AN54
 '@S9S_MB_2U_LIB.S9S_MB_2U(SCH_1):PAGE23_I169@PURE_QUANTA.SOCKET4677_AZIF0045P001C01CS(CHIPS)':
 'DDR3_SA_CS_N2': CDS_PINID='DDR3_SA_CS_N2';
NODE_NAME     J8 64
 '@S9S_MB_2U_LIB.S9S_MB_2U(SCH_1):PAGE89_I50@PURE_QUANTA.SCONN288_ADR50017P087CC(CHIPS)':
 'CS0_A_N': CDS_PINID='CS0_A_N';
NET_NAME
'M_D_CPU0_SA_CS_N<3>'
 '@S9S_MB_2U_LIB.S9S_MB_2U(SCH_1):M_D_CPU0_SA_CS_N'<3>:
 C_SIGNAL='@s9s_mb_2u_lib.s9s_mb_2u(sch_1):m_d_cpu0_sa_cs_n(3)';
NODE_NAME     U2 AP53
 '@S9S_MB_2U_LIB.S9S_MB_2U(SCH_1):PAGE23_I169@PURE_QUANTA.SOCKET4677_AZIF0045P001C01CS(CHIPS)':
 'DDR3_SA_CS_N3': CDS_PINID='DDR3_SA_CS_N3';
NODE_NAME     J8 209
 '@S9S_MB_2U_LIB.S9S_MB_2U(SCH_1):PAGE89_I50@PURE_QUANTA.SCONN288_ADR50017P087CC(CHIPS)':
 'CS1_A_N': CDS_PINID='CS1_A_N';
NET_NAME
'M_D_CPU0_SA_DQ<0>'
 '@S9S_MB_2U_LIB.S9S_MB_2U(SCH_1):M_D_CPU0_SA_DQ'<0>:
 C_SIGNAL='@s9s_mb_2u_lib.s9s_mb_2u(sch_1):m_d_cpu0_sa_dq(0)';
NODE_NAME     U2 AD75
 '@S9S_MB_2U_LIB.S9S_MB_2U(SCH_1):PAGE23_I169@PURE_QUANTA.SOCKET4677_AZIF0045P001C01CS(CHIPS)':
 'DDR3_SA_DQ0': CDS_PINID='DDR3_SA_DQ0';
NODE_NAME     J7 7
 '@S9S_MB_2U_LIB.S9S_MB_2U(SCH_1):PAGE88_I12@PURE_QUANTA.SCONN288_ADR50017P130CC(CHIPS)':
 'DQ0_A': CDS_PINID='DQ0_A';
NODE_NAME     J8 7
 '@S9S_MB_2U_LIB.S9S_MB_2U(SCH_1):PAGE89_I50@PURE_QUANTA.SCONN288_ADR50017P087CC(CHIPS)':
 'DQ0_A': CDS_PINID='DQ0_A';
NET_NAME
'M_D_CPU0_SA_DQ<10>'
 '@S9S_MB_2U_LIB.S9S_MB_2U(SCH_1):M_D_CPU0_SA_DQ'<10>:
 C_SIGNAL='@s9s_mb_2u_lib.s9s_mb_2u(sch_1):m_d_cpu0_sa_dq(10)';
NODE_NAME     U2 AN78
 '@S9S_MB_2U_LIB.S9S_MB_2U(SCH_1):PAGE23_I169@PURE_QUANTA.SOCKET4677_AZIF0045P001C01CS(CHIPS)':
 'DDR3_SA_DQ10': CDS_PINID='DDR3_SA_DQ10';
NODE_NAME     J7 163
 '@S9S_MB_2U_LIB.S9S_MB_2U(SCH_1):PAGE88_I12@PURE_QUANTA.SCONN288_ADR50017P130CC(CHIPS)':
 'DQ10_A': CDS_PINID='DQ10_A';
NODE_NAME     J8 163
 '@S9S_MB_2U_LIB.S9S_MB_2U(SCH_1):PAGE89_I50@PURE_QUANTA.SCONN288_ADR50017P087CC(CHIPS)':
 'DQ10_A': CDS_PINID='DQ10_A';
NET_NAME
'M_D_CPU0_SA_DQ<11>'
 '@S9S_MB_2U_LIB.S9S_MB_2U(SCH_1):M_D_CPU0_SA_DQ'<11>:
 C_SIGNAL='@s9s_mb_2u_lib.s9s_mb_2u(sch_1):m_d_cpu0_sa_dq(11)';
NODE_NAME     U2 AP77
 '@S9S_MB_2U_LIB.S9S_MB_2U(SCH_1):PAGE23_I169@PURE_QUANTA.SOCKET4677_AZIF0045P001C01CS(CHIPS)':
 'DDR3_SA_DQ11': CDS_PINID='DDR3_SA_DQ11';
NODE_NAME     J7 165
 '@S9S_MB_2U_LIB.S9S_MB_2U(SCH_1):PAGE88_I12@PURE_QUANTA.SCONN288_ADR50017P130CC(CHIPS)':
 'DQ11_A': CDS_PINID='DQ11_A';
NODE_NAME     J8 165
 '@S9S_MB_2U_LIB.S9S_MB_2U(SCH_1):PAGE89_I50@PURE_QUANTA.SCONN288_ADR50017P087CC(CHIPS)':
 'DQ11_A': CDS_PINID='DQ11_A';
NET_NAME
'M_D_CPU0_SA_DQ<12>'
 '@S9S_MB_2U_LIB.S9S_MB_2U(SCH_1):M_D_CPU0_SA_DQ'<12>:
 C_SIGNAL='@s9s_mb_2u_lib.s9s_mb_2u(sch_1):m_d_cpu0_sa_dq(12)';
NODE_NAME     U2 AK75
 '@S9S_MB_2U_LIB.S9S_MB_2U(SCH_1):PAGE23_I169@PURE_QUANTA.SOCKET4677_AZIF0045P001C01CS(CHIPS)':
 'DDR3_SA_DQ12': CDS_PINID='DDR3_SA_DQ12';
NODE_NAME     J7 25
 '@S9S_MB_2U_LIB.S9S_MB_2U(SCH_1):PAGE88_I12@PURE_QUANTA.SCONN288_ADR50017P130CC(CHIPS)':
 'DQ12_A': CDS_PINID='DQ12_A';
NODE_NAME     J8 25
 '@S9S_MB_2U_LIB.S9S_MB_2U(SCH_1):PAGE89_I50@PURE_QUANTA.SCONN288_ADR50017P087CC(CHIPS)':
 'DQ12_A': CDS_PINID='DQ12_A';
NET_NAME
'M_D_CPU0_SA_DQ<13>'
 '@S9S_MB_2U_LIB.S9S_MB_2U(SCH_1):M_D_CPU0_SA_DQ'<13>:
 C_SIGNAL='@s9s_mb_2u_lib.s9s_mb_2u(sch_1):m_d_cpu0_sa_dq(13)';
NODE_NAME     U2 AL74
 '@S9S_MB_2U_LIB.S9S_MB_2U(SCH_1):PAGE23_I169@PURE_QUANTA.SOCKET4677_AZIF0045P001C01CS(CHIPS)':
 'DDR3_SA_DQ13': CDS_PINID='DDR3_SA_DQ13';
NODE_NAME     J7 27
 '@S9S_MB_2U_LIB.S9S_MB_2U(SCH_1):PAGE88_I12@PURE_QUANTA.SCONN288_ADR50017P130CC(CHIPS)':
 'DQ13_A': CDS_PINID='DQ13_A';
NODE_NAME     J8 27
 '@S9S_MB_2U_LIB.S9S_MB_2U(SCH_1):PAGE89_I50@PURE_QUANTA.SCONN288_ADR50017P087CC(CHIPS)':
 'DQ13_A': CDS_PINID='DQ13_A';
NET_NAME
'M_D_CPU0_SA_DQ<14>'
 '@S9S_MB_2U_LIB.S9S_MB_2U(SCH_1):M_D_CPU0_SA_DQ'<14>:
 C_SIGNAL='@s9s_mb_2u_lib.s9s_mb_2u(sch_1):m_d_cpu0_sa_dq(14)';
NODE_NAME     U2 AP75
 '@S9S_MB_2U_LIB.S9S_MB_2U(SCH_1):PAGE23_I169@PURE_QUANTA.SOCKET4677_AZIF0045P001C01CS(CHIPS)':
 'DDR3_SA_DQ14': CDS_PINID='DDR3_SA_DQ14';
NODE_NAME     J7 170
 '@S9S_MB_2U_LIB.S9S_MB_2U(SCH_1):PAGE88_I12@PURE_QUANTA.SCONN288_ADR50017P130CC(CHIPS)':
 'DQ14_A': CDS_PINID='DQ14_A';
NODE_NAME     J8 170
 '@S9S_MB_2U_LIB.S9S_MB_2U(SCH_1):PAGE89_I50@PURE_QUANTA.SCONN288_ADR50017P087CC(CHIPS)':
 'DQ14_A': CDS_PINID='DQ14_A';
NET_NAME
'M_D_CPU0_SA_DQ<15>'
 '@S9S_MB_2U_LIB.S9S_MB_2U(SCH_1):M_D_CPU0_SA_DQ'<15>:
 C_SIGNAL='@s9s_mb_2u_lib.s9s_mb_2u(sch_1):m_d_cpu0_sa_dq(15)';
NODE_NAME     U2 AN74
 '@S9S_MB_2U_LIB.S9S_MB_2U(SCH_1):PAGE23_I169@PURE_QUANTA.SOCKET4677_AZIF0045P001C01CS(CHIPS)':
 'DDR3_SA_DQ15': CDS_PINID='DDR3_SA_DQ15';
NODE_NAME     J7 172
 '@S9S_MB_2U_LIB.S9S_MB_2U(SCH_1):PAGE88_I12@PURE_QUANTA.SCONN288_ADR50017P130CC(CHIPS)':
 'DQ15_A': CDS_PINID='DQ15_A';
NODE_NAME     J8 172
 '@S9S_MB_2U_LIB.S9S_MB_2U(SCH_1):PAGE89_I50@PURE_QUANTA.SCONN288_ADR50017P087CC(CHIPS)':
 'DQ15_A': CDS_PINID='DQ15_A';
NET_NAME
'M_D_CPU0_SA_DQ<16>'
 '@S9S_MB_2U_LIB.S9S_MB_2U(SCH_1):M_D_CPU0_SA_DQ'<16>:
 C_SIGNAL='@s9s_mb_2u_lib.s9s_mb_2u(sch_1):m_d_cpu0_sa_dq(16)';
NODE_NAME     U2 AL72
 '@S9S_MB_2U_LIB.S9S_MB_2U(SCH_1):PAGE23_I169@PURE_QUANTA.SOCKET4677_AZIF0045P001C01CS(CHIPS)':
 'DDR3_SA_DQ16': CDS_PINID='DDR3_SA_DQ16';
NODE_NAME     J7 29
 '@S9S_MB_2U_LIB.S9S_MB_2U(SCH_1):PAGE88_I12@PURE_QUANTA.SCONN288_ADR50017P130CC(CHIPS)':
 'DQ16_A': CDS_PINID='DQ16_A';
NODE_NAME     J8 29
 '@S9S_MB_2U_LIB.S9S_MB_2U(SCH_1):PAGE89_I50@PURE_QUANTA.SCONN288_ADR50017P087CC(CHIPS)':
 'DQ16_A': CDS_PINID='DQ16_A';
NET_NAME
'M_D_CPU0_SA_DQ<17>'
 '@S9S_MB_2U_LIB.S9S_MB_2U(SCH_1):M_D_CPU0_SA_DQ'<17>:
 C_SIGNAL='@s9s_mb_2u_lib.s9s_mb_2u(sch_1):m_d_cpu0_sa_dq(17)';
NODE_NAME     U2 AK71
 '@S9S_MB_2U_LIB.S9S_MB_2U(SCH_1):PAGE23_I169@PURE_QUANTA.SOCKET4677_AZIF0045P001C01CS(CHIPS)':
 'DDR3_SA_DQ17': CDS_PINID='DDR3_SA_DQ17';
NODE_NAME     J7 31
 '@S9S_MB_2U_LIB.S9S_MB_2U(SCH_1):PAGE88_I12@PURE_QUANTA.SCONN288_ADR50017P130CC(CHIPS)':
 'DQ17_A': CDS_PINID='DQ17_A';
NODE_NAME     J8 31
 '@S9S_MB_2U_LIB.S9S_MB_2U(SCH_1):PAGE89_I50@PURE_QUANTA.SCONN288_ADR50017P087CC(CHIPS)':
 'DQ17_A': CDS_PINID='DQ17_A';
NET_NAME
'M_D_CPU0_SA_DQ<18>'
 '@S9S_MB_2U_LIB.S9S_MB_2U(SCH_1):M_D_CPU0_SA_DQ'<18>:
 C_SIGNAL='@s9s_mb_2u_lib.s9s_mb_2u(sch_1):m_d_cpu0_sa_dq(18)';
NODE_NAME     U2 AN72
 '@S9S_MB_2U_LIB.S9S_MB_2U(SCH_1):PAGE23_I169@PURE_QUANTA.SOCKET4677_AZIF0045P001C01CS(CHIPS)':
 'DDR3_SA_DQ18': CDS_PINID='DDR3_SA_DQ18';
NODE_NAME     J7 174
 '@S9S_MB_2U_LIB.S9S_MB_2U(SCH_1):PAGE88_I12@PURE_QUANTA.SCONN288_ADR50017P130CC(CHIPS)':
 'DQ18_A': CDS_PINID='DQ18_A';
NODE_NAME     J8 174
 '@S9S_MB_2U_LIB.S9S_MB_2U(SCH_1):PAGE89_I50@PURE_QUANTA.SCONN288_ADR50017P087CC(CHIPS)':
 'DQ18_A': CDS_PINID='DQ18_A';
NET_NAME
'M_D_CPU0_SA_DQ<19>'
 '@S9S_MB_2U_LIB.S9S_MB_2U(SCH_1):M_D_CPU0_SA_DQ'<19>:
 C_SIGNAL='@s9s_mb_2u_lib.s9s_mb_2u(sch_1):m_d_cpu0_sa_dq(19)';
NODE_NAME     U2 AP71
 '@S9S_MB_2U_LIB.S9S_MB_2U(SCH_1):PAGE23_I169@PURE_QUANTA.SOCKET4677_AZIF0045P001C01CS(CHIPS)':
 'DDR3_SA_DQ19': CDS_PINID='DDR3_SA_DQ19';
NODE_NAME     J7 176
 '@S9S_MB_2U_LIB.S9S_MB_2U(SCH_1):PAGE88_I12@PURE_QUANTA.SCONN288_ADR50017P130CC(CHIPS)':
 'DQ19_A': CDS_PINID='DQ19_A';
NODE_NAME     J8 176
 '@S9S_MB_2U_LIB.S9S_MB_2U(SCH_1):PAGE89_I50@PURE_QUANTA.SCONN288_ADR50017P087CC(CHIPS)':
 'DQ19_A': CDS_PINID='DQ19_A';
NET_NAME
'M_D_CPU0_SA_DQ<1>'
 '@S9S_MB_2U_LIB.S9S_MB_2U(SCH_1):M_D_CPU0_SA_DQ'<1>:
 C_SIGNAL='@s9s_mb_2u_lib.s9s_mb_2u(sch_1):m_d_cpu0_sa_dq(1)';
NODE_NAME     U2 AC74
 '@S9S_MB_2U_LIB.S9S_MB_2U(SCH_1):PAGE23_I169@PURE_QUANTA.SOCKET4677_AZIF0045P001C01CS(CHIPS)':
 'DDR3_SA_DQ1': CDS_PINID='DDR3_SA_DQ1';
NODE_NAME     J7 9
 '@S9S_MB_2U_LIB.S9S_MB_2U(SCH_1):PAGE88_I12@PURE_QUANTA.SCONN288_ADR50017P130CC(CHIPS)':
 'DQ1_A': CDS_PINID='DQ1_A';
NODE_NAME     J8 9
 '@S9S_MB_2U_LIB.S9S_MB_2U(SCH_1):PAGE89_I50@PURE_QUANTA.SCONN288_ADR50017P087CC(CHIPS)':
 'DQ1_A': CDS_PINID='DQ1_A';
NET_NAME
'M_D_CPU0_SA_DQ<20>'
 '@S9S_MB_2U_LIB.S9S_MB_2U(SCH_1):M_D_CPU0_SA_DQ'<20>:
 C_SIGNAL='@s9s_mb_2u_lib.s9s_mb_2u(sch_1):m_d_cpu0_sa_dq(20)';
NODE_NAME     U2 AK69
 '@S9S_MB_2U_LIB.S9S_MB_2U(SCH_1):PAGE23_I169@PURE_QUANTA.SOCKET4677_AZIF0045P001C01CS(CHIPS)':
 'DDR3_SA_DQ20': CDS_PINID='DDR3_SA_DQ20';
NODE_NAME     J7 36
 '@S9S_MB_2U_LIB.S9S_MB_2U(SCH_1):PAGE88_I12@PURE_QUANTA.SCONN288_ADR50017P130CC(CHIPS)':
 'DQ20_A': CDS_PINID='DQ20_A';
NODE_NAME     J8 36
 '@S9S_MB_2U_LIB.S9S_MB_2U(SCH_1):PAGE89_I50@PURE_QUANTA.SCONN288_ADR50017P087CC(CHIPS)':
 'DQ20_A': CDS_PINID='DQ20_A';
NET_NAME
'M_D_CPU0_SA_DQ<21>'
 '@S9S_MB_2U_LIB.S9S_MB_2U(SCH_1):M_D_CPU0_SA_DQ'<21>:
 C_SIGNAL='@s9s_mb_2u_lib.s9s_mb_2u(sch_1):m_d_cpu0_sa_dq(21)';
NODE_NAME     U2 AL68
 '@S9S_MB_2U_LIB.S9S_MB_2U(SCH_1):PAGE23_I169@PURE_QUANTA.SOCKET4677_AZIF0045P001C01CS(CHIPS)':
 'DDR3_SA_DQ21': CDS_PINID='DDR3_SA_DQ21';
NODE_NAME     J7 38
 '@S9S_MB_2U_LIB.S9S_MB_2U(SCH_1):PAGE88_I12@PURE_QUANTA.SCONN288_ADR50017P130CC(CHIPS)':
 'DQ21_A': CDS_PINID='DQ21_A';
NODE_NAME     J8 38
 '@S9S_MB_2U_LIB.S9S_MB_2U(SCH_1):PAGE89_I50@PURE_QUANTA.SCONN288_ADR50017P087CC(CHIPS)':
 'DQ21_A': CDS_PINID='DQ21_A';
NET_NAME
'M_D_CPU0_SA_DQ<22>'
 '@S9S_MB_2U_LIB.S9S_MB_2U(SCH_1):M_D_CPU0_SA_DQ'<22>:
 C_SIGNAL='@s9s_mb_2u_lib.s9s_mb_2u(sch_1):m_d_cpu0_sa_dq(22)';
NODE_NAME     U2 AP69
 '@S9S_MB_2U_LIB.S9S_MB_2U(SCH_1):PAGE23_I169@PURE_QUANTA.SOCKET4677_AZIF0045P001C01CS(CHIPS)':
 'DDR3_SA_DQ22': CDS_PINID='DDR3_SA_DQ22';
NODE_NAME     J7 181
 '@S9S_MB_2U_LIB.S9S_MB_2U(SCH_1):PAGE88_I12@PURE_QUANTA.SCONN288_ADR50017P130CC(CHIPS)':
 'DQ22_A': CDS_PINID='DQ22_A';
NODE_NAME     J8 181
 '@S9S_MB_2U_LIB.S9S_MB_2U(SCH_1):PAGE89_I50@PURE_QUANTA.SCONN288_ADR50017P087CC(CHIPS)':
 'DQ22_A': CDS_PINID='DQ22_A';
NET_NAME
'M_D_CPU0_SA_DQ<23>'
 '@S9S_MB_2U_LIB.S9S_MB_2U(SCH_1):M_D_CPU0_SA_DQ'<23>:
 C_SIGNAL='@s9s_mb_2u_lib.s9s_mb_2u(sch_1):m_d_cpu0_sa_dq(23)';
NODE_NAME     U2 AN68
 '@S9S_MB_2U_LIB.S9S_MB_2U(SCH_1):PAGE23_I169@PURE_QUANTA.SOCKET4677_AZIF0045P001C01CS(CHIPS)':
 'DDR3_SA_DQ23': CDS_PINID='DDR3_SA_DQ23';
NODE_NAME     J7 183
 '@S9S_MB_2U_LIB.S9S_MB_2U(SCH_1):PAGE88_I12@PURE_QUANTA.SCONN288_ADR50017P130CC(CHIPS)':
 'DQ23_A': CDS_PINID='DQ23_A';
NODE_NAME     J8 183
 '@S9S_MB_2U_LIB.S9S_MB_2U(SCH_1):PAGE89_I50@PURE_QUANTA.SCONN288_ADR50017P087CC(CHIPS)':
 'DQ23_A': CDS_PINID='DQ23_A';
NET_NAME
'M_D_CPU0_SA_DQ<24>'
 '@S9S_MB_2U_LIB.S9S_MB_2U(SCH_1):M_D_CPU0_SA_DQ'<24>:
 C_SIGNAL='@s9s_mb_2u_lib.s9s_mb_2u(sch_1):m_d_cpu0_sa_dq(24)';
NODE_NAME     U2 AL66
 '@S9S_MB_2U_LIB.S9S_MB_2U(SCH_1):PAGE23_I169@PURE_QUANTA.SOCKET4677_AZIF0045P001C01CS(CHIPS)':
 'DDR3_SA_DQ24': CDS_PINID='DDR3_SA_DQ24';
NODE_NAME     J7 40
 '@S9S_MB_2U_LIB.S9S_MB_2U(SCH_1):PAGE88_I12@PURE_QUANTA.SCONN288_ADR50017P130CC(CHIPS)':
 'DQ24_A': CDS_PINID='DQ24_A';
NODE_NAME     J8 40
 '@S9S_MB_2U_LIB.S9S_MB_2U(SCH_1):PAGE89_I50@PURE_QUANTA.SCONN288_ADR50017P087CC(CHIPS)':
 'DQ24_A': CDS_PINID='DQ24_A';
NET_NAME
'M_D_CPU0_SA_DQ<25>'
 '@S9S_MB_2U_LIB.S9S_MB_2U(SCH_1):M_D_CPU0_SA_DQ'<25>:
 C_SIGNAL='@s9s_mb_2u_lib.s9s_mb_2u(sch_1):m_d_cpu0_sa_dq(25)';
NODE_NAME     U2 AK65
 '@S9S_MB_2U_LIB.S9S_MB_2U(SCH_1):PAGE23_I169@PURE_QUANTA.SOCKET4677_AZIF0045P001C01CS(CHIPS)':
 'DDR3_SA_DQ25': CDS_PINID='DDR3_SA_DQ25';
NODE_NAME     J7 42
 '@S9S_MB_2U_LIB.S9S_MB_2U(SCH_1):PAGE88_I12@PURE_QUANTA.SCONN288_ADR50017P130CC(CHIPS)':
 'DQ25_A': CDS_PINID='DQ25_A';
NODE_NAME     J8 42
 '@S9S_MB_2U_LIB.S9S_MB_2U(SCH_1):PAGE89_I50@PURE_QUANTA.SCONN288_ADR50017P087CC(CHIPS)':
 'DQ25_A': CDS_PINID='DQ25_A';
NET_NAME
'M_D_CPU0_SA_DQ<26>'
 '@S9S_MB_2U_LIB.S9S_MB_2U(SCH_1):M_D_CPU0_SA_DQ'<26>:
 C_SIGNAL='@s9s_mb_2u_lib.s9s_mb_2u(sch_1):m_d_cpu0_sa_dq(26)';
NODE_NAME     U2 AN66
 '@S9S_MB_2U_LIB.S9S_MB_2U(SCH_1):PAGE23_I169@PURE_QUANTA.SOCKET4677_AZIF0045P001C01CS(CHIPS)':
 'DDR3_SA_DQ26': CDS_PINID='DDR3_SA_DQ26';
NODE_NAME     J7 185
 '@S9S_MB_2U_LIB.S9S_MB_2U(SCH_1):PAGE88_I12@PURE_QUANTA.SCONN288_ADR50017P130CC(CHIPS)':
 'DQ26_A': CDS_PINID='DQ26_A';
NODE_NAME     J8 185
 '@S9S_MB_2U_LIB.S9S_MB_2U(SCH_1):PAGE89_I50@PURE_QUANTA.SCONN288_ADR50017P087CC(CHIPS)':
 'DQ26_A': CDS_PINID='DQ26_A';
NET_NAME
'M_D_CPU0_SA_DQ<27>'
 '@S9S_MB_2U_LIB.S9S_MB_2U(SCH_1):M_D_CPU0_SA_DQ'<27>:
 C_SIGNAL='@s9s_mb_2u_lib.s9s_mb_2u(sch_1):m_d_cpu0_sa_dq(27)';
NODE_NAME     U2 AP65
 '@S9S_MB_2U_LIB.S9S_MB_2U(SCH_1):PAGE23_I169@PURE_QUANTA.SOCKET4677_AZIF0045P001C01CS(CHIPS)':
 'DDR3_SA_DQ27': CDS_PINID='DDR3_SA_DQ27';
NODE_NAME     J7 187
 '@S9S_MB_2U_LIB.S9S_MB_2U(SCH_1):PAGE88_I12@PURE_QUANTA.SCONN288_ADR50017P130CC(CHIPS)':
 'DQ27_A': CDS_PINID='DQ27_A';
NODE_NAME     J8 187
 '@S9S_MB_2U_LIB.S9S_MB_2U(SCH_1):PAGE89_I50@PURE_QUANTA.SCONN288_ADR50017P087CC(CHIPS)':
 'DQ27_A': CDS_PINID='DQ27_A';
NET_NAME
'M_D_CPU0_SA_DQ<28>'
 '@S9S_MB_2U_LIB.S9S_MB_2U(SCH_1):M_D_CPU0_SA_DQ'<28>:
 C_SIGNAL='@s9s_mb_2u_lib.s9s_mb_2u(sch_1):m_d_cpu0_sa_dq(28)';
NODE_NAME     U2 AK63
 '@S9S_MB_2U_LIB.S9S_MB_2U(SCH_1):PAGE23_I169@PURE_QUANTA.SOCKET4677_AZIF0045P001C01CS(CHIPS)':
 'DDR3_SA_DQ28': CDS_PINID='DDR3_SA_DQ28';
NODE_NAME     J7 47
 '@S9S_MB_2U_LIB.S9S_MB_2U(SCH_1):PAGE88_I12@PURE_QUANTA.SCONN288_ADR50017P130CC(CHIPS)':
 'DQ28_A': CDS_PINID='DQ28_A';
NODE_NAME     J8 47
 '@S9S_MB_2U_LIB.S9S_MB_2U(SCH_1):PAGE89_I50@PURE_QUANTA.SCONN288_ADR50017P087CC(CHIPS)':
 'DQ28_A': CDS_PINID='DQ28_A';
NET_NAME
'M_D_CPU0_SA_DQ<29>'
 '@S9S_MB_2U_LIB.S9S_MB_2U(SCH_1):M_D_CPU0_SA_DQ'<29>:
 C_SIGNAL='@s9s_mb_2u_lib.s9s_mb_2u(sch_1):m_d_cpu0_sa_dq(29)';
NODE_NAME     U2 AL62
 '@S9S_MB_2U_LIB.S9S_MB_2U(SCH_1):PAGE23_I169@PURE_QUANTA.SOCKET4677_AZIF0045P001C01CS(CHIPS)':
 'DDR3_SA_DQ29': CDS_PINID='DDR3_SA_DQ29';
NODE_NAME     J7 49
 '@S9S_MB_2U_LIB.S9S_MB_2U(SCH_1):PAGE88_I12@PURE_QUANTA.SCONN288_ADR50017P130CC(CHIPS)':
 'DQ29_A': CDS_PINID='DQ29_A';
NODE_NAME     J8 49
 '@S9S_MB_2U_LIB.S9S_MB_2U(SCH_1):PAGE89_I50@PURE_QUANTA.SCONN288_ADR50017P087CC(CHIPS)':
 'DQ29_A': CDS_PINID='DQ29_A';
NET_NAME
'M_D_CPU0_SA_DQ<2>'
 '@S9S_MB_2U_LIB.S9S_MB_2U(SCH_1):M_D_CPU0_SA_DQ'<2>:
 C_SIGNAL='@s9s_mb_2u_lib.s9s_mb_2u(sch_1):m_d_cpu0_sa_dq(2)';
NODE_NAME     U2 AF75
 '@S9S_MB_2U_LIB.S9S_MB_2U(SCH_1):PAGE23_I169@PURE_QUANTA.SOCKET4677_AZIF0045P001C01CS(CHIPS)':
 'DDR3_SA_DQ2': CDS_PINID='DDR3_SA_DQ2';
NODE_NAME     J7 152
 '@S9S_MB_2U_LIB.S9S_MB_2U(SCH_1):PAGE88_I12@PURE_QUANTA.SCONN288_ADR50017P130CC(CHIPS)':
 'DQ2_A': CDS_PINID='DQ2_A';
NODE_NAME     J8 152
 '@S9S_MB_2U_LIB.S9S_MB_2U(SCH_1):PAGE89_I50@PURE_QUANTA.SCONN288_ADR50017P087CC(CHIPS)':
 'DQ2_A': CDS_PINID='DQ2_A';
NET_NAME
'M_D_CPU0_SA_DQ<30>'
 '@S9S_MB_2U_LIB.S9S_MB_2U(SCH_1):M_D_CPU0_SA_DQ'<30>:
 C_SIGNAL='@s9s_mb_2u_lib.s9s_mb_2u(sch_1):m_d_cpu0_sa_dq(30)';
NODE_NAME     U2 AP63
 '@S9S_MB_2U_LIB.S9S_MB_2U(SCH_1):PAGE23_I169@PURE_QUANTA.SOCKET4677_AZIF0045P001C01CS(CHIPS)':
 'DDR3_SA_DQ30': CDS_PINID='DDR3_SA_DQ30';
NODE_NAME     J7 192
 '@S9S_MB_2U_LIB.S9S_MB_2U(SCH_1):PAGE88_I12@PURE_QUANTA.SCONN288_ADR50017P130CC(CHIPS)':
 'DQ30_A': CDS_PINID='DQ30_A';
NODE_NAME     J8 192
 '@S9S_MB_2U_LIB.S9S_MB_2U(SCH_1):PAGE89_I50@PURE_QUANTA.SCONN288_ADR50017P087CC(CHIPS)':
 'DQ30_A': CDS_PINID='DQ30_A';
NET_NAME
'M_D_CPU0_SA_DQ<31>'
 '@S9S_MB_2U_LIB.S9S_MB_2U(SCH_1):M_D_CPU0_SA_DQ'<31>:
 C_SIGNAL='@s9s_mb_2u_lib.s9s_mb_2u(sch_1):m_d_cpu0_sa_dq(31)';
NODE_NAME     U2 AN62
 '@S9S_MB_2U_LIB.S9S_MB_2U(SCH_1):PAGE23_I169@PURE_QUANTA.SOCKET4677_AZIF0045P001C01CS(CHIPS)':
 'DDR3_SA_DQ31': CDS_PINID='DDR3_SA_DQ31';
NODE_NAME     J7 194
 '@S9S_MB_2U_LIB.S9S_MB_2U(SCH_1):PAGE88_I12@PURE_QUANTA.SCONN288_ADR50017P130CC(CHIPS)':
 'DQ31_A': CDS_PINID='DQ31_A';
NODE_NAME     J8 194
 '@S9S_MB_2U_LIB.S9S_MB_2U(SCH_1):PAGE89_I50@PURE_QUANTA.SCONN288_ADR50017P087CC(CHIPS)':
 'DQ31_A': CDS_PINID='DQ31_A';
NET_NAME
'M_D_CPU0_SA_DQ<3>'
 '@S9S_MB_2U_LIB.S9S_MB_2U(SCH_1):M_D_CPU0_SA_DQ'<3>:
 C_SIGNAL='@s9s_mb_2u_lib.s9s_mb_2u(sch_1):m_d_cpu0_sa_dq(3)';
NODE_NAME     U2 AG74
 '@S9S_MB_2U_LIB.S9S_MB_2U(SCH_1):PAGE23_I169@PURE_QUANTA.SOCKET4677_AZIF0045P001C01CS(CHIPS)':
 'DDR3_SA_DQ3': CDS_PINID='DDR3_SA_DQ3';
NODE_NAME     J7 154
 '@S9S_MB_2U_LIB.S9S_MB_2U(SCH_1):PAGE88_I12@PURE_QUANTA.SCONN288_ADR50017P130CC(CHIPS)':
 'DQ3_A': CDS_PINID='DQ3_A';
NODE_NAME     J8 154
 '@S9S_MB_2U_LIB.S9S_MB_2U(SCH_1):PAGE89_I50@PURE_QUANTA.SCONN288_ADR50017P087CC(CHIPS)':
 'DQ3_A': CDS_PINID='DQ3_A';
NET_NAME
'M_D_CPU0_SA_DQ<4>'
 '@S9S_MB_2U_LIB.S9S_MB_2U(SCH_1):M_D_CPU0_SA_DQ'<4>:
 C_SIGNAL='@s9s_mb_2u_lib.s9s_mb_2u(sch_1):m_d_cpu0_sa_dq(4)';
NODE_NAME     U2 AC72
 '@S9S_MB_2U_LIB.S9S_MB_2U(SCH_1):PAGE23_I169@PURE_QUANTA.SOCKET4677_AZIF0045P001C01CS(CHIPS)':
 'DDR3_SA_DQ4': CDS_PINID='DDR3_SA_DQ4';
NODE_NAME     J7 14
 '@S9S_MB_2U_LIB.S9S_MB_2U(SCH_1):PAGE88_I12@PURE_QUANTA.SCONN288_ADR50017P130CC(CHIPS)':
 'DQ4_A': CDS_PINID='DQ4_A';
NODE_NAME     J8 14
 '@S9S_MB_2U_LIB.S9S_MB_2U(SCH_1):PAGE89_I50@PURE_QUANTA.SCONN288_ADR50017P087CC(CHIPS)':
 'DQ4_A': CDS_PINID='DQ4_A';
NET_NAME
'M_D_CPU0_SA_DQ<5>'
 '@S9S_MB_2U_LIB.S9S_MB_2U(SCH_1):M_D_CPU0_SA_DQ'<5>:
 C_SIGNAL='@s9s_mb_2u_lib.s9s_mb_2u(sch_1):m_d_cpu0_sa_dq(5)';
NODE_NAME     U2 AD71
 '@S9S_MB_2U_LIB.S9S_MB_2U(SCH_1):PAGE23_I169@PURE_QUANTA.SOCKET4677_AZIF0045P001C01CS(CHIPS)':
 'DDR3_SA_DQ5': CDS_PINID='DDR3_SA_DQ5';
NODE_NAME     J7 16
 '@S9S_MB_2U_LIB.S9S_MB_2U(SCH_1):PAGE88_I12@PURE_QUANTA.SCONN288_ADR50017P130CC(CHIPS)':
 'DQ5_A': CDS_PINID='DQ5_A';
NODE_NAME     J8 16
 '@S9S_MB_2U_LIB.S9S_MB_2U(SCH_1):PAGE89_I50@PURE_QUANTA.SCONN288_ADR50017P087CC(CHIPS)':
 'DQ5_A': CDS_PINID='DQ5_A';
NET_NAME
'M_D_CPU0_SA_DQ<6>'
 '@S9S_MB_2U_LIB.S9S_MB_2U(SCH_1):M_D_CPU0_SA_DQ'<6>:
 C_SIGNAL='@s9s_mb_2u_lib.s9s_mb_2u(sch_1):m_d_cpu0_sa_dq(6)';
NODE_NAME     U2 AG72
 '@S9S_MB_2U_LIB.S9S_MB_2U(SCH_1):PAGE23_I169@PURE_QUANTA.SOCKET4677_AZIF0045P001C01CS(CHIPS)':
 'DDR3_SA_DQ6': CDS_PINID='DDR3_SA_DQ6';
NODE_NAME     J7 159
 '@S9S_MB_2U_LIB.S9S_MB_2U(SCH_1):PAGE88_I12@PURE_QUANTA.SCONN288_ADR50017P130CC(CHIPS)':
 'DQ6_A': CDS_PINID='DQ6_A';
NODE_NAME     J8 159
 '@S9S_MB_2U_LIB.S9S_MB_2U(SCH_1):PAGE89_I50@PURE_QUANTA.SCONN288_ADR50017P087CC(CHIPS)':
 'DQ6_A': CDS_PINID='DQ6_A';
NET_NAME
'M_D_CPU0_SA_DQ<7>'
 '@S9S_MB_2U_LIB.S9S_MB_2U(SCH_1):M_D_CPU0_SA_DQ'<7>:
 C_SIGNAL='@s9s_mb_2u_lib.s9s_mb_2u(sch_1):m_d_cpu0_sa_dq(7)';
NODE_NAME     U2 AF71
 '@S9S_MB_2U_LIB.S9S_MB_2U(SCH_1):PAGE23_I169@PURE_QUANTA.SOCKET4677_AZIF0045P001C01CS(CHIPS)':
 'DDR3_SA_DQ7': CDS_PINID='DDR3_SA_DQ7';
NODE_NAME     J7 161
 '@S9S_MB_2U_LIB.S9S_MB_2U(SCH_1):PAGE88_I12@PURE_QUANTA.SCONN288_ADR50017P130CC(CHIPS)':
 'DQ7_A': CDS_PINID='DQ7_A';
NODE_NAME     J8 161
 '@S9S_MB_2U_LIB.S9S_MB_2U(SCH_1):PAGE89_I50@PURE_QUANTA.SCONN288_ADR50017P087CC(CHIPS)':
 'DQ7_A': CDS_PINID='DQ7_A';
NET_NAME
'M_D_CPU0_SA_DQ<8>'
 '@S9S_MB_2U_LIB.S9S_MB_2U(SCH_1):M_D_CPU0_SA_DQ'<8>:
 C_SIGNAL='@s9s_mb_2u_lib.s9s_mb_2u(sch_1):m_d_cpu0_sa_dq(8)';
NODE_NAME     U2 AL78
 '@S9S_MB_2U_LIB.S9S_MB_2U(SCH_1):PAGE23_I169@PURE_QUANTA.SOCKET4677_AZIF0045P001C01CS(CHIPS)':
 'DDR3_SA_DQ8': CDS_PINID='DDR3_SA_DQ8';
NODE_NAME     J7 18
 '@S9S_MB_2U_LIB.S9S_MB_2U(SCH_1):PAGE88_I12@PURE_QUANTA.SCONN288_ADR50017P130CC(CHIPS)':
 'DQ8_A': CDS_PINID='DQ8_A';
NODE_NAME     J8 18
 '@S9S_MB_2U_LIB.S9S_MB_2U(SCH_1):PAGE89_I50@PURE_QUANTA.SCONN288_ADR50017P087CC(CHIPS)':
 'DQ8_A': CDS_PINID='DQ8_A';
NET_NAME
'M_D_CPU0_SA_DQ<9>'
 '@S9S_MB_2U_LIB.S9S_MB_2U(SCH_1):M_D_CPU0_SA_DQ'<9>:
 C_SIGNAL='@s9s_mb_2u_lib.s9s_mb_2u(sch_1):m_d_cpu0_sa_dq(9)';
NODE_NAME     U2 AK77
 '@S9S_MB_2U_LIB.S9S_MB_2U(SCH_1):PAGE23_I169@PURE_QUANTA.SOCKET4677_AZIF0045P001C01CS(CHIPS)':
 'DDR3_SA_DQ9': CDS_PINID='DDR3_SA_DQ9';
NODE_NAME     J7 20
 '@S9S_MB_2U_LIB.S9S_MB_2U(SCH_1):PAGE88_I12@PURE_QUANTA.SCONN288_ADR50017P130CC(CHIPS)':
 'DQ9_A': CDS_PINID='DQ9_A';
NODE_NAME     J8 20
 '@S9S_MB_2U_LIB.S9S_MB_2U(SCH_1):PAGE89_I50@PURE_QUANTA.SCONN288_ADR50017P087CC(CHIPS)':
 'DQ9_A': CDS_PINID='DQ9_A';
NET_NAME
'M_D_CPU0_SA_DQS_DN<0>'
 '@S9S_MB_2U_LIB.S9S_MB_2U(SCH_1):M_D_CPU0_SA_DQS_DN'<0>:
 C_SIGNAL='@s9s_mb_2u_lib.s9s_mb_2u(sch_1):m_d_cpu0_sa_dqs_dn(0)';
NODE_NAME     U2 AB73
 '@S9S_MB_2U_LIB.S9S_MB_2U(SCH_1):PAGE23_I169@PURE_QUANTA.SOCKET4677_AZIF0045P001C01CS(CHIPS)':
 'DDR3_SA_DQS_DN0': CDS_PINID='DDR3_SA_DQS_DN0';
NODE_NAME     J7 12
 '@S9S_MB_2U_LIB.S9S_MB_2U(SCH_1):PAGE88_I178@PURE_QUANTA.SCONN288_ADR50017P130CC(CHIPS)':
 'DQS0_A_C': CDS_PINID='DQS0_A_C';
NODE_NAME     J8 12
 '@S9S_MB_2U_LIB.S9S_MB_2U(SCH_1):PAGE89_I178@PURE_QUANTA.SCONN288_ADR50017P087CC(CHIPS)':
 'DQS0_A_C': CDS_PINID='DQS0_A_C';
NET_NAME
'M_D_CPU0_SA_DQS_DN<1>'
 '@S9S_MB_2U_LIB.S9S_MB_2U(SCH_1):M_D_CPU0_SA_DQS_DN'<1>:
 C_SIGNAL='@s9s_mb_2u_lib.s9s_mb_2u(sch_1):m_d_cpu0_sa_dqs_dn(1)';
NODE_NAME     U2 AJ76
 '@S9S_MB_2U_LIB.S9S_MB_2U(SCH_1):PAGE23_I169@PURE_QUANTA.SOCKET4677_AZIF0045P001C01CS(CHIPS)':
 'DDR3_SA_DQS_DN1': CDS_PINID='DDR3_SA_DQS_DN1';
NODE_NAME     J7 23
 '@S9S_MB_2U_LIB.S9S_MB_2U(SCH_1):PAGE88_I178@PURE_QUANTA.SCONN288_ADR50017P130CC(CHIPS)':
 'DQS1_A_C': CDS_PINID='DQS1_A_C';
NODE_NAME     J8 23
 '@S9S_MB_2U_LIB.S9S_MB_2U(SCH_1):PAGE89_I178@PURE_QUANTA.SCONN288_ADR50017P087CC(CHIPS)':
 'DQS1_A_C': CDS_PINID='DQS1_A_C';
NET_NAME
'M_D_CPU0_SA_DQS_DN<2>'
 '@S9S_MB_2U_LIB.S9S_MB_2U(SCH_1):M_D_CPU0_SA_DQS_DN'<2>:
 C_SIGNAL='@s9s_mb_2u_lib.s9s_mb_2u(sch_1):m_d_cpu0_sa_dqs_dn(2)';
NODE_NAME     U2 AJ70
 '@S9S_MB_2U_LIB.S9S_MB_2U(SCH_1):PAGE23_I169@PURE_QUANTA.SOCKET4677_AZIF0045P001C01CS(CHIPS)':
 'DDR3_SA_DQS_DN2': CDS_PINID='DDR3_SA_DQS_DN2';
NODE_NAME     J7 34
 '@S9S_MB_2U_LIB.S9S_MB_2U(SCH_1):PAGE88_I178@PURE_QUANTA.SCONN288_ADR50017P130CC(CHIPS)':
 'DQS2_A_C': CDS_PINID='DQS2_A_C';
NODE_NAME     J8 34
 '@S9S_MB_2U_LIB.S9S_MB_2U(SCH_1):PAGE89_I178@PURE_QUANTA.SCONN288_ADR50017P087CC(CHIPS)':
 'DQS2_A_C': CDS_PINID='DQS2_A_C';
NET_NAME
'M_D_CPU0_SA_DQS_DN<3>'
 '@S9S_MB_2U_LIB.S9S_MB_2U(SCH_1):M_D_CPU0_SA_DQS_DN'<3>:
 C_SIGNAL='@s9s_mb_2u_lib.s9s_mb_2u(sch_1):m_d_cpu0_sa_dqs_dn(3)';
NODE_NAME     U2 AJ64
 '@S9S_MB_2U_LIB.S9S_MB_2U(SCH_1):PAGE23_I169@PURE_QUANTA.SOCKET4677_AZIF0045P001C01CS(CHIPS)':
 'DDR3_SA_DQS_DN3': CDS_PINID='DDR3_SA_DQS_DN3';
NODE_NAME     J7 45
 '@S9S_MB_2U_LIB.S9S_MB_2U(SCH_1):PAGE88_I178@PURE_QUANTA.SCONN288_ADR50017P130CC(CHIPS)':
 'DQS3_A_C': CDS_PINID='DQS3_A_C';
NODE_NAME     J8 45
 '@S9S_MB_2U_LIB.S9S_MB_2U(SCH_1):PAGE89_I178@PURE_QUANTA.SCONN288_ADR50017P087CC(CHIPS)':
 'DQS3_A_C': CDS_PINID='DQS3_A_C';
NET_NAME
'M_D_CPU0_SA_DQS_DN<4>'
 '@S9S_MB_2U_LIB.S9S_MB_2U(SCH_1):M_D_CPU0_SA_DQS_DN'<4>:
 C_SIGNAL='@s9s_mb_2u_lib.s9s_mb_2u(sch_1):m_d_cpu0_sa_dqs_dn(4)';
NODE_NAME     U2 AJ58
 '@S9S_MB_2U_LIB.S9S_MB_2U(SCH_1):PAGE23_I169@PURE_QUANTA.SOCKET4677_AZIF0045P001C01CS(CHIPS)':
 'DDR3_SA_DQS_DN4': CDS_PINID='DDR3_SA_DQS_DN4';
NODE_NAME     J7 56
 '@S9S_MB_2U_LIB.S9S_MB_2U(SCH_1):PAGE88_I178@PURE_QUANTA.SCONN288_ADR50017P130CC(CHIPS)':
 'DQS4_A_C': CDS_PINID='DQS4_A_C';
NODE_NAME     J8 56
 '@S9S_MB_2U_LIB.S9S_MB_2U(SCH_1):PAGE89_I178@PURE_QUANTA.SCONN288_ADR50017P087CC(CHIPS)':
 'DQS4_A_C': CDS_PINID='DQS4_A_C';
NET_NAME
'M_D_CPU0_SA_DQS_DN<5>'
 '@S9S_MB_2U_LIB.S9S_MB_2U(SCH_1):M_D_CPU0_SA_DQS_DN'<5>:
 C_SIGNAL='@s9s_mb_2u_lib.s9s_mb_2u(sch_1):m_d_cpu0_sa_dqs_dn(5)';
NODE_NAME     U2 AH73
 '@S9S_MB_2U_LIB.S9S_MB_2U(SCH_1):PAGE23_I169@PURE_QUANTA.SOCKET4677_AZIF0045P001C01CS(CHIPS)':
 'DDR3_SA_DQS_DN5': CDS_PINID='DDR3_SA_DQS_DN5';
NODE_NAME     J7 156
 '@S9S_MB_2U_LIB.S9S_MB_2U(SCH_1):PAGE88_I178@PURE_QUANTA.SCONN288_ADR50017P130CC(CHIPS)':
 'DQS5_A_C||TDQS5_A_C||DQS5_A_T||TDQS5_A_T': CDS_PINID='\dqs5_a_c||tdqs5_a_c||dqs5_a_t||tdqs5_a_t\';
NODE_NAME     J8 156
 '@S9S_MB_2U_LIB.S9S_MB_2U(SCH_1):PAGE89_I178@PURE_QUANTA.SCONN288_ADR50017P087CC(CHIPS)':
 'DQS5_A_C||TDQS5_A_C||DQS5_A_T||TDQS5_A_T': CDS_PINID='\dqs5_a_c||tdqs5_a_c||dqs5_a_t||tdqs5_a_t\';
NET_NAME
'M_D_CPU0_SA_DQS_DN<6>'
 '@S9S_MB_2U_LIB.S9S_MB_2U(SCH_1):M_D_CPU0_SA_DQS_DN'<6>:
 C_SIGNAL='@s9s_mb_2u_lib.s9s_mb_2u(sch_1):m_d_cpu0_sa_dqs_dn(6)';
NODE_NAME     U2 AN76
 '@S9S_MB_2U_LIB.S9S_MB_2U(SCH_1):PAGE23_I169@PURE_QUANTA.SOCKET4677_AZIF0045P001C01CS(CHIPS)':
 'DDR3_SA_DQS_DN6': CDS_PINID='DDR3_SA_DQS_DN6';
NODE_NAME     J7 167
 '@S9S_MB_2U_LIB.S9S_MB_2U(SCH_1):PAGE88_I178@PURE_QUANTA.SCONN288_ADR50017P130CC(CHIPS)':
 'DQS6_A_C||TDQS6_A_C||DQS6_A_T||TDQS6_A_T': CDS_PINID='\dqs6_a_c||tdqs6_a_c||dqs6_a_t||tdqs6_a_t\';
NODE_NAME     J8 167
 '@S9S_MB_2U_LIB.S9S_MB_2U(SCH_1):PAGE89_I178@PURE_QUANTA.SCONN288_ADR50017P087CC(CHIPS)':
 'DQS6_A_C||TDQS6_A_C||DQS6_A_T||TDQS6_A_T': CDS_PINID='\dqs6_a_c||tdqs6_a_c||dqs6_a_t||tdqs6_a_t\';
NET_NAME
'M_D_CPU0_SA_DQS_DN<7>'
 '@S9S_MB_2U_LIB.S9S_MB_2U(SCH_1):M_D_CPU0_SA_DQS_DN'<7>:
 C_SIGNAL='@s9s_mb_2u_lib.s9s_mb_2u(sch_1):m_d_cpu0_sa_dqs_dn(7)';
NODE_NAME     U2 AN70
 '@S9S_MB_2U_LIB.S9S_MB_2U(SCH_1):PAGE23_I169@PURE_QUANTA.SOCKET4677_AZIF0045P001C01CS(CHIPS)':
 'DDR3_SA_DQS_DN7': CDS_PINID='DDR3_SA_DQS_DN7';
NODE_NAME     J7 178
 '@S9S_MB_2U_LIB.S9S_MB_2U(SCH_1):PAGE88_I178@PURE_QUANTA.SCONN288_ADR50017P130CC(CHIPS)':
 'DQS7_A_C||TDQS7_A_C': CDS_PINID='\dqs7_a_c||tdqs7_a_c\';
NODE_NAME     J8 178
 '@S9S_MB_2U_LIB.S9S_MB_2U(SCH_1):PAGE89_I178@PURE_QUANTA.SCONN288_ADR50017P087CC(CHIPS)':
 'DQS7_A_C||TDQS7_A_C': CDS_PINID='\dqs7_a_c||tdqs7_a_c\';
NET_NAME
'M_D_CPU0_SA_DQS_DN<8>'
 '@S9S_MB_2U_LIB.S9S_MB_2U(SCH_1):M_D_CPU0_SA_DQS_DN'<8>:
 C_SIGNAL='@s9s_mb_2u_lib.s9s_mb_2u(sch_1):m_d_cpu0_sa_dqs_dn(8)';
NODE_NAME     U2 AN64
 '@S9S_MB_2U_LIB.S9S_MB_2U(SCH_1):PAGE23_I169@PURE_QUANTA.SOCKET4677_AZIF0045P001C01CS(CHIPS)':
 'DDR3_SA_DQS_DN8': CDS_PINID='DDR3_SA_DQS_DN8';
NODE_NAME     J7 189
 '@S9S_MB_2U_LIB.S9S_MB_2U(SCH_1):PAGE88_I178@PURE_QUANTA.SCONN288_ADR50017P130CC(CHIPS)':
 'DQS8_A_C||TDQS8_A_C': CDS_PINID='\dqs8_a_c||tdqs8_a_c\';
NODE_NAME     J8 189
 '@S9S_MB_2U_LIB.S9S_MB_2U(SCH_1):PAGE89_I178@PURE_QUANTA.SCONN288_ADR50017P087CC(CHIPS)':
 'DQS8_A_C||TDQS8_A_C': CDS_PINID='\dqs8_a_c||tdqs8_a_c\';
NET_NAME
'M_D_CPU0_SA_DQS_DN<9>'
 '@S9S_MB_2U_LIB.S9S_MB_2U(SCH_1):M_D_CPU0_SA_DQS_DN'<9>:
 C_SIGNAL='@s9s_mb_2u_lib.s9s_mb_2u(sch_1):m_d_cpu0_sa_dqs_dn(9)';
NODE_NAME     U2 AN58
 '@S9S_MB_2U_LIB.S9S_MB_2U(SCH_1):PAGE23_I169@PURE_QUANTA.SOCKET4677_AZIF0045P001C01CS(CHIPS)':
 'DDR3_SA_DQS_DN9': CDS_PINID='DDR3_SA_DQS_DN9';
NODE_NAME     J7 200
 '@S9S_MB_2U_LIB.S9S_MB_2U(SCH_1):PAGE88_I178@PURE_QUANTA.SCONN288_ADR50017P130CC(CHIPS)':
 'DQS9_A_C||TDQS9_A_C': CDS_PINID='\dqs9_a_c||tdqs9_a_c\';
NODE_NAME     J8 200
 '@S9S_MB_2U_LIB.S9S_MB_2U(SCH_1):PAGE89_I178@PURE_QUANTA.SCONN288_ADR50017P087CC(CHIPS)':
 'DQS9_A_C||TDQS9_A_C': CDS_PINID='\dqs9_a_c||tdqs9_a_c\';
NET_NAME
'M_D_CPU0_SA_DQS_DP<0>'
 '@S9S_MB_2U_LIB.S9S_MB_2U(SCH_1):M_D_CPU0_SA_DQS_DP'<0>:
 C_SIGNAL='@s9s_mb_2u_lib.s9s_mb_2u(sch_1):m_d_cpu0_sa_dqs_dp(0)';
NODE_NAME     U2 AD73
 '@S9S_MB_2U_LIB.S9S_MB_2U(SCH_1):PAGE23_I169@PURE_QUANTA.SOCKET4677_AZIF0045P001C01CS(CHIPS)':
 'DDR3_SA_DQS_DP0': CDS_PINID='DDR3_SA_DQS_DP0';
NODE_NAME     J7 11
 '@S9S_MB_2U_LIB.S9S_MB_2U(SCH_1):PAGE88_I178@PURE_QUANTA.SCONN288_ADR50017P130CC(CHIPS)':
 'DQS0_A_T': CDS_PINID='DQS0_A_T';
NODE_NAME     J8 11
 '@S9S_MB_2U_LIB.S9S_MB_2U(SCH_1):PAGE89_I178@PURE_QUANTA.SCONN288_ADR50017P087CC(CHIPS)':
 'DQS0_A_T': CDS_PINID='DQS0_A_T';
NET_NAME
'M_D_CPU0_SA_DQS_DP<1>'
 '@S9S_MB_2U_LIB.S9S_MB_2U(SCH_1):M_D_CPU0_SA_DQS_DP'<1>:
 C_SIGNAL='@s9s_mb_2u_lib.s9s_mb_2u(sch_1):m_d_cpu0_sa_dqs_dp(1)';
NODE_NAME     U2 AL76
 '@S9S_MB_2U_LIB.S9S_MB_2U(SCH_1):PAGE23_I169@PURE_QUANTA.SOCKET4677_AZIF0045P001C01CS(CHIPS)':
 'DDR3_SA_DQS_DP1': CDS_PINID='DDR3_SA_DQS_DP1';
NODE_NAME     J7 22
 '@S9S_MB_2U_LIB.S9S_MB_2U(SCH_1):PAGE88_I178@PURE_QUANTA.SCONN288_ADR50017P130CC(CHIPS)':
 'DQS1_A_T': CDS_PINID='DQS1_A_T';
NODE_NAME     J8 22
 '@S9S_MB_2U_LIB.S9S_MB_2U(SCH_1):PAGE89_I178@PURE_QUANTA.SCONN288_ADR50017P087CC(CHIPS)':
 'DQS1_A_T': CDS_PINID='DQS1_A_T';
NET_NAME
'M_D_CPU0_SA_DQS_DP<2>'
 '@S9S_MB_2U_LIB.S9S_MB_2U(SCH_1):M_D_CPU0_SA_DQS_DP'<2>:
 C_SIGNAL='@s9s_mb_2u_lib.s9s_mb_2u(sch_1):m_d_cpu0_sa_dqs_dp(2)';
NODE_NAME     U2 AL70
 '@S9S_MB_2U_LIB.S9S_MB_2U(SCH_1):PAGE23_I169@PURE_QUANTA.SOCKET4677_AZIF0045P001C01CS(CHIPS)':
 'DDR3_SA_DQS_DP2': CDS_PINID='DDR3_SA_DQS_DP2';
NODE_NAME     J7 33
 '@S9S_MB_2U_LIB.S9S_MB_2U(SCH_1):PAGE88_I178@PURE_QUANTA.SCONN288_ADR50017P130CC(CHIPS)':
 'DQS2_A_T': CDS_PINID='DQS2_A_T';
NODE_NAME     J8 33
 '@S9S_MB_2U_LIB.S9S_MB_2U(SCH_1):PAGE89_I178@PURE_QUANTA.SCONN288_ADR50017P087CC(CHIPS)':
 'DQS2_A_T': CDS_PINID='DQS2_A_T';
NET_NAME
'M_D_CPU0_SA_DQS_DP<3>'
 '@S9S_MB_2U_LIB.S9S_MB_2U(SCH_1):M_D_CPU0_SA_DQS_DP'<3>:
 C_SIGNAL='@s9s_mb_2u_lib.s9s_mb_2u(sch_1):m_d_cpu0_sa_dqs_dp(3)';
NODE_NAME     U2 AL64
 '@S9S_MB_2U_LIB.S9S_MB_2U(SCH_1):PAGE23_I169@PURE_QUANTA.SOCKET4677_AZIF0045P001C01CS(CHIPS)':
 'DDR3_SA_DQS_DP3': CDS_PINID='DDR3_SA_DQS_DP3';
NODE_NAME     J7 44
 '@S9S_MB_2U_LIB.S9S_MB_2U(SCH_1):PAGE88_I178@PURE_QUANTA.SCONN288_ADR50017P130CC(CHIPS)':
 'DQS3_A_T': CDS_PINID='DQS3_A_T';
NODE_NAME     J8 44
 '@S9S_MB_2U_LIB.S9S_MB_2U(SCH_1):PAGE89_I178@PURE_QUANTA.SCONN288_ADR50017P087CC(CHIPS)':
 'DQS3_A_T': CDS_PINID='DQS3_A_T';
NET_NAME
'M_D_CPU0_SA_DQS_DP<4>'
 '@S9S_MB_2U_LIB.S9S_MB_2U(SCH_1):M_D_CPU0_SA_DQS_DP'<4>:
 C_SIGNAL='@s9s_mb_2u_lib.s9s_mb_2u(sch_1):m_d_cpu0_sa_dqs_dp(4)';
NODE_NAME     U2 AL58
 '@S9S_MB_2U_LIB.S9S_MB_2U(SCH_1):PAGE23_I169@PURE_QUANTA.SOCKET4677_AZIF0045P001C01CS(CHIPS)':
 'DDR3_SA_DQS_DP4': CDS_PINID='DDR3_SA_DQS_DP4';
NODE_NAME     J7 55
 '@S9S_MB_2U_LIB.S9S_MB_2U(SCH_1):PAGE88_I178@PURE_QUANTA.SCONN288_ADR50017P130CC(CHIPS)':
 'DQS4_A_T': CDS_PINID='DQS4_A_T';
NODE_NAME     J8 55
 '@S9S_MB_2U_LIB.S9S_MB_2U(SCH_1):PAGE89_I178@PURE_QUANTA.SCONN288_ADR50017P087CC(CHIPS)':
 'DQS4_A_T': CDS_PINID='DQS4_A_T';
NET_NAME
'M_D_CPU0_SA_DQS_DP<5>'
 '@S9S_MB_2U_LIB.S9S_MB_2U(SCH_1):M_D_CPU0_SA_DQS_DP'<5>:
 C_SIGNAL='@s9s_mb_2u_lib.s9s_mb_2u(sch_1):m_d_cpu0_sa_dqs_dp(5)';
NODE_NAME     U2 AF73
 '@S9S_MB_2U_LIB.S9S_MB_2U(SCH_1):PAGE23_I169@PURE_QUANTA.SOCKET4677_AZIF0045P001C01CS(CHIPS)':
 'DDR3_SA_DQS_DP5': CDS_PINID='DDR3_SA_DQS_DP5';
NODE_NAME     J7 157
 '@S9S_MB_2U_LIB.S9S_MB_2U(SCH_1):PAGE88_I178@PURE_QUANTA.SCONN288_ADR50017P130CC(CHIPS)':
 'DQS5_A_T||TDQS5_A_T': CDS_PINID='\dqs5_a_t||tdqs5_a_t\';
NODE_NAME     J8 157
 '@S9S_MB_2U_LIB.S9S_MB_2U(SCH_1):PAGE89_I178@PURE_QUANTA.SCONN288_ADR50017P087CC(CHIPS)':
 'DQS5_A_T||TDQS5_A_T': CDS_PINID='\dqs5_a_t||tdqs5_a_t\';
NET_NAME
'M_D_CPU0_SA_DQS_DP<6>'
 '@S9S_MB_2U_LIB.S9S_MB_2U(SCH_1):M_D_CPU0_SA_DQS_DP'<6>:
 C_SIGNAL='@s9s_mb_2u_lib.s9s_mb_2u(sch_1):m_d_cpu0_sa_dqs_dp(6)';
NODE_NAME     U2 AR76
 '@S9S_MB_2U_LIB.S9S_MB_2U(SCH_1):PAGE23_I169@PURE_QUANTA.SOCKET4677_AZIF0045P001C01CS(CHIPS)':
 'DDR3_SA_DQS_DP6': CDS_PINID='DDR3_SA_DQS_DP6';
NODE_NAME     J7 168
 '@S9S_MB_2U_LIB.S9S_MB_2U(SCH_1):PAGE88_I178@PURE_QUANTA.SCONN288_ADR50017P130CC(CHIPS)':
 'DQS6_A_T||TDQS6_A_T': CDS_PINID='\dqs6_a_t||tdqs6_a_t\';
NODE_NAME     J8 168
 '@S9S_MB_2U_LIB.S9S_MB_2U(SCH_1):PAGE89_I178@PURE_QUANTA.SCONN288_ADR50017P087CC(CHIPS)':
 'DQS6_A_T||TDQS6_A_T': CDS_PINID='\dqs6_a_t||tdqs6_a_t\';
NET_NAME
'M_D_CPU0_SA_DQS_DP<7>'
 '@S9S_MB_2U_LIB.S9S_MB_2U(SCH_1):M_D_CPU0_SA_DQS_DP'<7>:
 C_SIGNAL='@s9s_mb_2u_lib.s9s_mb_2u(sch_1):m_d_cpu0_sa_dqs_dp(7)';
NODE_NAME     U2 AR70
 '@S9S_MB_2U_LIB.S9S_MB_2U(SCH_1):PAGE23_I169@PURE_QUANTA.SOCKET4677_AZIF0045P001C01CS(CHIPS)':
 'DDR3_SA_DQS_DP7': CDS_PINID='DDR3_SA_DQS_DP7';
NODE_NAME     J7 179
 '@S9S_MB_2U_LIB.S9S_MB_2U(SCH_1):PAGE88_I178@PURE_QUANTA.SCONN288_ADR50017P130CC(CHIPS)':
 'DQS7_A_T||TDQS7_A_T': CDS_PINID='\dqs7_a_t||tdqs7_a_t\';
NODE_NAME     J8 179
 '@S9S_MB_2U_LIB.S9S_MB_2U(SCH_1):PAGE89_I178@PURE_QUANTA.SCONN288_ADR50017P087CC(CHIPS)':
 'DQS7_A_T||TDQS7_A_T': CDS_PINID='\dqs7_a_t||tdqs7_a_t\';
NET_NAME
'M_D_CPU0_SA_DQS_DP<8>'
 '@S9S_MB_2U_LIB.S9S_MB_2U(SCH_1):M_D_CPU0_SA_DQS_DP'<8>:
 C_SIGNAL='@s9s_mb_2u_lib.s9s_mb_2u(sch_1):m_d_cpu0_sa_dqs_dp(8)';
NODE_NAME     U2 AR64
 '@S9S_MB_2U_LIB.S9S_MB_2U(SCH_1):PAGE23_I169@PURE_QUANTA.SOCKET4677_AZIF0045P001C01CS(CHIPS)':
 'DDR3_SA_DQS_DP8': CDS_PINID='DDR3_SA_DQS_DP8';
NODE_NAME     J7 190
 '@S9S_MB_2U_LIB.S9S_MB_2U(SCH_1):PAGE88_I178@PURE_QUANTA.SCONN288_ADR50017P130CC(CHIPS)':
 'DQS8_A_T||TDQS8_A_T': CDS_PINID='\dqs8_a_t||tdqs8_a_t\';
NODE_NAME     J8 190
 '@S9S_MB_2U_LIB.S9S_MB_2U(SCH_1):PAGE89_I178@PURE_QUANTA.SCONN288_ADR50017P087CC(CHIPS)':
 'DQS8_A_T||TDQS8_A_T': CDS_PINID='\dqs8_a_t||tdqs8_a_t\';
NET_NAME
'M_D_CPU0_SA_DQS_DP<9>'
 '@S9S_MB_2U_LIB.S9S_MB_2U(SCH_1):M_D_CPU0_SA_DQS_DP'<9>:
 C_SIGNAL='@s9s_mb_2u_lib.s9s_mb_2u(sch_1):m_d_cpu0_sa_dqs_dp(9)';
NODE_NAME     U2 AR58
 '@S9S_MB_2U_LIB.S9S_MB_2U(SCH_1):PAGE23_I169@PURE_QUANTA.SOCKET4677_AZIF0045P001C01CS(CHIPS)':
 'DDR3_SA_DQS_DP9': CDS_PINID='DDR3_SA_DQS_DP9';
NODE_NAME     J7 201
 '@S9S_MB_2U_LIB.S9S_MB_2U(SCH_1):PAGE88_I178@PURE_QUANTA.SCONN288_ADR50017P130CC(CHIPS)':
 'DQS9_A_T||TDQS9_A_T': CDS_PINID='\dqs9_a_t||tdqs9_a_t\';
NODE_NAME     J8 201
 '@S9S_MB_2U_LIB.S9S_MB_2U(SCH_1):PAGE89_I178@PURE_QUANTA.SCONN288_ADR50017P087CC(CHIPS)':
 'DQS9_A_T||TDQS9_A_T': CDS_PINID='\dqs9_a_t||tdqs9_a_t\';
NET_NAME
'M_D_CPU0_SA_PAR'
 '@S9S_MB_2U_LIB.S9S_MB_2U(SCH_1):M_D_CPU0_SA_PAR':
 C_SIGNAL='@s9s_mb_2u_lib.s9s_mb_2u(sch_1):m_d_cpu0_sa_par';
NODE_NAME     U2 AP44
 '@S9S_MB_2U_LIB.S9S_MB_2U(SCH_1):PAGE23_I169@PURE_QUANTA.SOCKET4677_AZIF0045P001C01CS(CHIPS)':
 'DDR3_SA_PAR': CDS_PINID='DDR3_SA_PAR';
NODE_NAME     J7 74
 '@S9S_MB_2U_LIB.S9S_MB_2U(SCH_1):PAGE88_I12@PURE_QUANTA.SCONN288_ADR50017P130CC(CHIPS)':
 'PAR_A': CDS_PINID='PAR_A';
NODE_NAME     J8 74
 '@S9S_MB_2U_LIB.S9S_MB_2U(SCH_1):PAGE89_I50@PURE_QUANTA.SCONN288_ADR50017P087CC(CHIPS)':
 'PAR_A': CDS_PINID='PAR_A';
NET_NAME
'M_D_CPU0_SA_RSP<0>'
 '@S9S_MB_2U_LIB.S9S_MB_2U(SCH_1):M_D_CPU0_SA_RSP'<0>:
 C_SIGNAL='@s9s_mb_2u_lib.s9s_mb_2u(sch_1):m_d_cpu0_sa_rsp(0)';
NODE_NAME     U2 AD51
 '@S9S_MB_2U_LIB.S9S_MB_2U(SCH_1):PAGE23_I169@PURE_QUANTA.SOCKET4677_AZIF0045P001C01CS(CHIPS)':
 'DDR3_A_RSP0': CDS_PINID='DDR3_A_RSP0';
NODE_NAME     J7 86
 '@S9S_MB_2U_LIB.S9S_MB_2U(SCH_1):PAGE88_I12@PURE_QUANTA.SCONN288_ADR50017P130CC(CHIPS)':
 'LBD||RSP_A_N': CDS_PINID='\lbd||rsp_a_n\';
NET_NAME
'M_D_CPU0_SA_RSP<1>'
 '@S9S_MB_2U_LIB.S9S_MB_2U(SCH_1):M_D_CPU0_SA_RSP'<1>:
 C_SIGNAL='@s9s_mb_2u_lib.s9s_mb_2u(sch_1):m_d_cpu0_sa_rsp(1)';
NODE_NAME     U2 AC50
 '@S9S_MB_2U_LIB.S9S_MB_2U(SCH_1):PAGE23_I169@PURE_QUANTA.SOCKET4677_AZIF0045P001C01CS(CHIPS)':
 'DDR3_A_RSP1': CDS_PINID='DDR3_A_RSP1';
NODE_NAME     J8 86
 '@S9S_MB_2U_LIB.S9S_MB_2U(SCH_1):PAGE89_I50@PURE_QUANTA.SCONN288_ADR50017P087CC(CHIPS)':
 'LBD||RSP_A_N': CDS_PINID='\lbd||rsp_a_n\';
NET_NAME
'M_D_CPU0_SB_CA<0>'
 '@S9S_MB_2U_LIB.S9S_MB_2U(SCH_1):M_D_CPU0_SB_CA'<0>:
 C_SIGNAL='@s9s_mb_2u_lib.s9s_mb_2u(sch_1):m_d_cpu0_sb_ca(0)';
NODE_NAME     U2 AK44
 '@S9S_MB_2U_LIB.S9S_MB_2U(SCH_1):PAGE23_I169@PURE_QUANTA.SOCKET4677_AZIF0045P001C01CS(CHIPS)':
 'DDR3_SB_CA0': CDS_PINID='DDR3_SB_CA0';
NODE_NAME     J7 76
 '@S9S_MB_2U_LIB.S9S_MB_2U(SCH_1):PAGE88_I12@PURE_QUANTA.SCONN288_ADR50017P130CC(CHIPS)':
 'CA0_B': CDS_PINID='CA0_B';
NODE_NAME     J8 76
 '@S9S_MB_2U_LIB.S9S_MB_2U(SCH_1):PAGE89_I50@PURE_QUANTA.SCONN288_ADR50017P087CC(CHIPS)':
 'CA0_B': CDS_PINID='CA0_B';
NET_NAME
'M_D_CPU0_SB_CA<1>'
 '@S9S_MB_2U_LIB.S9S_MB_2U(SCH_1):M_D_CPU0_SB_CA'<1>:
 C_SIGNAL='@s9s_mb_2u_lib.s9s_mb_2u(sch_1):m_d_cpu0_sb_ca(1)';
NODE_NAME     U2 AL43
 '@S9S_MB_2U_LIB.S9S_MB_2U(SCH_1):PAGE23_I169@PURE_QUANTA.SOCKET4677_AZIF0045P001C01CS(CHIPS)':
 'DDR3_SB_CA1': CDS_PINID='DDR3_SB_CA1';
NODE_NAME     J7 221
 '@S9S_MB_2U_LIB.S9S_MB_2U(SCH_1):PAGE88_I12@PURE_QUANTA.SCONN288_ADR50017P130CC(CHIPS)':
 'CA1_B': CDS_PINID='CA1_B';
NODE_NAME     J8 221
 '@S9S_MB_2U_LIB.S9S_MB_2U(SCH_1):PAGE89_I50@PURE_QUANTA.SCONN288_ADR50017P087CC(CHIPS)':
 'CA1_B': CDS_PINID='CA1_B';
NET_NAME
'M_D_CPU0_SB_CA<2>'
 '@S9S_MB_2U_LIB.S9S_MB_2U(SCH_1):M_D_CPU0_SB_CA'<2>:
 C_SIGNAL='@s9s_mb_2u_lib.s9s_mb_2u(sch_1):m_d_cpu0_sb_ca(2)';
NODE_NAME     U2 AD44
 '@S9S_MB_2U_LIB.S9S_MB_2U(SCH_1):PAGE23_I169@PURE_QUANTA.SOCKET4677_AZIF0045P001C01CS(CHIPS)':
 'DDR3_SB_CA2': CDS_PINID='DDR3_SB_CA2';
NODE_NAME     J7 78
 '@S9S_MB_2U_LIB.S9S_MB_2U(SCH_1):PAGE88_I12@PURE_QUANTA.SCONN288_ADR50017P130CC(CHIPS)':
 'CA2_B': CDS_PINID='CA2_B';
NODE_NAME     J8 78
 '@S9S_MB_2U_LIB.S9S_MB_2U(SCH_1):PAGE89_I50@PURE_QUANTA.SCONN288_ADR50017P087CC(CHIPS)':
 'CA2_B': CDS_PINID='CA2_B';
NET_NAME
'M_D_CPU0_SB_CA<3>'
 '@S9S_MB_2U_LIB.S9S_MB_2U(SCH_1):M_D_CPU0_SB_CA'<3>:
 C_SIGNAL='@s9s_mb_2u_lib.s9s_mb_2u(sch_1):m_d_cpu0_sb_ca(3)';
NODE_NAME     U2 AF44
 '@S9S_MB_2U_LIB.S9S_MB_2U(SCH_1):PAGE23_I169@PURE_QUANTA.SOCKET4677_AZIF0045P001C01CS(CHIPS)':
 'DDR3_SB_CA3': CDS_PINID='DDR3_SB_CA3';
NODE_NAME     J7 223
 '@S9S_MB_2U_LIB.S9S_MB_2U(SCH_1):PAGE88_I12@PURE_QUANTA.SCONN288_ADR50017P130CC(CHIPS)':
 'CA3_B': CDS_PINID='CA3_B';
NODE_NAME     J8 223
 '@S9S_MB_2U_LIB.S9S_MB_2U(SCH_1):PAGE89_I50@PURE_QUANTA.SCONN288_ADR50017P087CC(CHIPS)':
 'CA3_B': CDS_PINID='CA3_B';
NET_NAME
'M_D_CPU0_SB_CA<4>'
 '@S9S_MB_2U_LIB.S9S_MB_2U(SCH_1):M_D_CPU0_SB_CA'<4>:
 C_SIGNAL='@s9s_mb_2u_lib.s9s_mb_2u(sch_1):m_d_cpu0_sb_ca(4)';
NODE_NAME     U2 AC43
 '@S9S_MB_2U_LIB.S9S_MB_2U(SCH_1):PAGE23_I169@PURE_QUANTA.SOCKET4677_AZIF0045P001C01CS(CHIPS)':
 'DDR3_SB_CA4': CDS_PINID='DDR3_SB_CA4';
NODE_NAME     J7 80
 '@S9S_MB_2U_LIB.S9S_MB_2U(SCH_1):PAGE88_I12@PURE_QUANTA.SCONN288_ADR50017P130CC(CHIPS)':
 'CA4_B': CDS_PINID='CA4_B';
NODE_NAME     J8 80
 '@S9S_MB_2U_LIB.S9S_MB_2U(SCH_1):PAGE89_I50@PURE_QUANTA.SCONN288_ADR50017P087CC(CHIPS)':
 'CA4_B': CDS_PINID='CA4_B';
NET_NAME
'M_D_CPU0_SB_CA<5>'
 '@S9S_MB_2U_LIB.S9S_MB_2U(SCH_1):M_D_CPU0_SB_CA'<5>:
 C_SIGNAL='@s9s_mb_2u_lib.s9s_mb_2u(sch_1):m_d_cpu0_sb_ca(5)';
NODE_NAME     U2 AG43
 '@S9S_MB_2U_LIB.S9S_MB_2U(SCH_1):PAGE23_I169@PURE_QUANTA.SOCKET4677_AZIF0045P001C01CS(CHIPS)':
 'DDR3_SB_CA5': CDS_PINID='DDR3_SB_CA5';
NODE_NAME     J7 225
 '@S9S_MB_2U_LIB.S9S_MB_2U(SCH_1):PAGE88_I12@PURE_QUANTA.SCONN288_ADR50017P130CC(CHIPS)':
 'CA5_B': CDS_PINID='CA5_B';
NODE_NAME     J8 225
 '@S9S_MB_2U_LIB.S9S_MB_2U(SCH_1):PAGE89_I50@PURE_QUANTA.SCONN288_ADR50017P087CC(CHIPS)':
 'CA5_B': CDS_PINID='CA5_B';
NET_NAME
'M_D_CPU0_SB_CA<6>'
 '@S9S_MB_2U_LIB.S9S_MB_2U(SCH_1):M_D_CPU0_SB_CA'<6>:
 C_SIGNAL='@s9s_mb_2u_lib.s9s_mb_2u(sch_1):m_d_cpu0_sb_ca(6)';
NODE_NAME     U2 AB42
 '@S9S_MB_2U_LIB.S9S_MB_2U(SCH_1):PAGE23_I169@PURE_QUANTA.SOCKET4677_AZIF0045P001C01CS(CHIPS)':
 'DDR3_SB_CA6': CDS_PINID='DDR3_SB_CA6';
NODE_NAME     J7 82
 '@S9S_MB_2U_LIB.S9S_MB_2U(SCH_1):PAGE88_I12@PURE_QUANTA.SCONN288_ADR50017P130CC(CHIPS)':
 'CA6_B': CDS_PINID='CA6_B';
NODE_NAME     J8 82
 '@S9S_MB_2U_LIB.S9S_MB_2U(SCH_1):PAGE89_I50@PURE_QUANTA.SCONN288_ADR50017P087CC(CHIPS)':
 'CA6_B': CDS_PINID='CA6_B';
NET_NAME
'M_D_CPU0_SB_CB<0>'
 '@S9S_MB_2U_LIB.S9S_MB_2U(SCH_1):M_D_CPU0_SB_CB'<0>:
 C_SIGNAL='@s9s_mb_2u_lib.s9s_mb_2u(sch_1):m_d_cpu0_sb_cb(0)';
NODE_NAME     U2 AK38
 '@S9S_MB_2U_LIB.S9S_MB_2U(SCH_1):PAGE23_I169@PURE_QUANTA.SOCKET4677_AZIF0045P001C01CS(CHIPS)':
 'DDR3_SB_ECC0': CDS_PINID='DDR3_SB_ECC0';
NODE_NAME     J7 96
 '@S9S_MB_2U_LIB.S9S_MB_2U(SCH_1):PAGE88_I12@PURE_QUANTA.SCONN288_ADR50017P130CC(CHIPS)':
 'CB0_B': CDS_PINID='CB0_B';
NODE_NAME     J8 96
 '@S9S_MB_2U_LIB.S9S_MB_2U(SCH_1):PAGE89_I50@PURE_QUANTA.SCONN288_ADR50017P087CC(CHIPS)':
 'CB0_B': CDS_PINID='CB0_B';
NET_NAME
'M_D_CPU0_SB_CB<1>'
 '@S9S_MB_2U_LIB.S9S_MB_2U(SCH_1):M_D_CPU0_SB_CB'<1>:
 C_SIGNAL='@s9s_mb_2u_lib.s9s_mb_2u(sch_1):m_d_cpu0_sb_cb(1)';
NODE_NAME     U2 AL37
 '@S9S_MB_2U_LIB.S9S_MB_2U(SCH_1):PAGE23_I169@PURE_QUANTA.SOCKET4677_AZIF0045P001C01CS(CHIPS)':
 'DDR3_SB_ECC1': CDS_PINID='DDR3_SB_ECC1';
NODE_NAME     J7 98
 '@S9S_MB_2U_LIB.S9S_MB_2U(SCH_1):PAGE88_I12@PURE_QUANTA.SCONN288_ADR50017P130CC(CHIPS)':
 'CB1_B': CDS_PINID='CB1_B';
NODE_NAME     J8 98
 '@S9S_MB_2U_LIB.S9S_MB_2U(SCH_1):PAGE89_I50@PURE_QUANTA.SCONN288_ADR50017P087CC(CHIPS)':
 'CB1_B': CDS_PINID='CB1_B';
NET_NAME
'M_D_CPU0_SB_CB<2>'
 '@S9S_MB_2U_LIB.S9S_MB_2U(SCH_1):M_D_CPU0_SB_CB'<2>:
 C_SIGNAL='@s9s_mb_2u_lib.s9s_mb_2u(sch_1):m_d_cpu0_sb_cb(2)';
NODE_NAME     U2 AP38
 '@S9S_MB_2U_LIB.S9S_MB_2U(SCH_1):PAGE23_I169@PURE_QUANTA.SOCKET4677_AZIF0045P001C01CS(CHIPS)':
 'DDR3_SB_ECC2': CDS_PINID='DDR3_SB_ECC2';
NODE_NAME     J7 241
 '@S9S_MB_2U_LIB.S9S_MB_2U(SCH_1):PAGE88_I12@PURE_QUANTA.SCONN288_ADR50017P130CC(CHIPS)':
 'CB2_B': CDS_PINID='CB2_B';
NODE_NAME     J8 241
 '@S9S_MB_2U_LIB.S9S_MB_2U(SCH_1):PAGE89_I50@PURE_QUANTA.SCONN288_ADR50017P087CC(CHIPS)':
 'CB2_B': CDS_PINID='CB2_B';
NET_NAME
'M_D_CPU0_SB_CB<3>'
 '@S9S_MB_2U_LIB.S9S_MB_2U(SCH_1):M_D_CPU0_SB_CB'<3>:
 C_SIGNAL='@s9s_mb_2u_lib.s9s_mb_2u(sch_1):m_d_cpu0_sb_cb(3)';
NODE_NAME     U2 AN37
 '@S9S_MB_2U_LIB.S9S_MB_2U(SCH_1):PAGE23_I169@PURE_QUANTA.SOCKET4677_AZIF0045P001C01CS(CHIPS)':
 'DDR3_SB_ECC3': CDS_PINID='DDR3_SB_ECC3';
NODE_NAME     J7 243
 '@S9S_MB_2U_LIB.S9S_MB_2U(SCH_1):PAGE88_I12@PURE_QUANTA.SCONN288_ADR50017P130CC(CHIPS)':
 'CB3_B': CDS_PINID='CB3_B';
NODE_NAME     J8 243
 '@S9S_MB_2U_LIB.S9S_MB_2U(SCH_1):PAGE89_I50@PURE_QUANTA.SCONN288_ADR50017P087CC(CHIPS)':
 'CB3_B': CDS_PINID='CB3_B';
NET_NAME
'M_D_CPU0_SB_CB<4>'
 '@S9S_MB_2U_LIB.S9S_MB_2U(SCH_1):M_D_CPU0_SB_CB'<4>:
 C_SIGNAL='@s9s_mb_2u_lib.s9s_mb_2u(sch_1):m_d_cpu0_sb_cb(4)';
NODE_NAME     U2 AL41
 '@S9S_MB_2U_LIB.S9S_MB_2U(SCH_1):PAGE23_I169@PURE_QUANTA.SOCKET4677_AZIF0045P001C01CS(CHIPS)':
 'DDR3_SB_ECC4': CDS_PINID='DDR3_SB_ECC4';
NODE_NAME     J7 89
 '@S9S_MB_2U_LIB.S9S_MB_2U(SCH_1):PAGE88_I12@PURE_QUANTA.SCONN288_ADR50017P130CC(CHIPS)':
 'CB4_B': CDS_PINID='CB4_B';
NODE_NAME     J8 89
 '@S9S_MB_2U_LIB.S9S_MB_2U(SCH_1):PAGE89_I50@PURE_QUANTA.SCONN288_ADR50017P087CC(CHIPS)':
 'CB4_B': CDS_PINID='CB4_B';
NET_NAME
'M_D_CPU0_SB_CB<5>'
 '@S9S_MB_2U_LIB.S9S_MB_2U(SCH_1):M_D_CPU0_SB_CB'<5>:
 C_SIGNAL='@s9s_mb_2u_lib.s9s_mb_2u(sch_1):m_d_cpu0_sb_cb(5)';
NODE_NAME     U2 AK40
 '@S9S_MB_2U_LIB.S9S_MB_2U(SCH_1):PAGE23_I169@PURE_QUANTA.SOCKET4677_AZIF0045P001C01CS(CHIPS)':
 'DDR3_SB_ECC5': CDS_PINID='DDR3_SB_ECC5';
NODE_NAME     J7 91
 '@S9S_MB_2U_LIB.S9S_MB_2U(SCH_1):PAGE88_I12@PURE_QUANTA.SCONN288_ADR50017P130CC(CHIPS)':
 'CB5_B': CDS_PINID='CB5_B';
NODE_NAME     J8 91
 '@S9S_MB_2U_LIB.S9S_MB_2U(SCH_1):PAGE89_I50@PURE_QUANTA.SCONN288_ADR50017P087CC(CHIPS)':
 'CB5_B': CDS_PINID='CB5_B';
NET_NAME
'M_D_CPU0_SB_CB<6>'
 '@S9S_MB_2U_LIB.S9S_MB_2U(SCH_1):M_D_CPU0_SB_CB'<6>:
 C_SIGNAL='@s9s_mb_2u_lib.s9s_mb_2u(sch_1):m_d_cpu0_sb_cb(6)';
NODE_NAME     U2 AN41
 '@S9S_MB_2U_LIB.S9S_MB_2U(SCH_1):PAGE23_I169@PURE_QUANTA.SOCKET4677_AZIF0045P001C01CS(CHIPS)':
 'DDR3_SB_ECC6': CDS_PINID='DDR3_SB_ECC6';
NODE_NAME     J7 234
 '@S9S_MB_2U_LIB.S9S_MB_2U(SCH_1):PAGE88_I12@PURE_QUANTA.SCONN288_ADR50017P130CC(CHIPS)':
 'CB6_B': CDS_PINID='CB6_B';
NODE_NAME     J8 234
 '@S9S_MB_2U_LIB.S9S_MB_2U(SCH_1):PAGE89_I50@PURE_QUANTA.SCONN288_ADR50017P087CC(CHIPS)':
 'CB6_B': CDS_PINID='CB6_B';
NET_NAME
'M_D_CPU0_SB_CB<7>'
 '@S9S_MB_2U_LIB.S9S_MB_2U(SCH_1):M_D_CPU0_SB_CB'<7>:
 C_SIGNAL='@s9s_mb_2u_lib.s9s_mb_2u(sch_1):m_d_cpu0_sb_cb(7)';
NODE_NAME     U2 AP40
 '@S9S_MB_2U_LIB.S9S_MB_2U(SCH_1):PAGE23_I169@PURE_QUANTA.SOCKET4677_AZIF0045P001C01CS(CHIPS)':
 'DDR3_SB_ECC7': CDS_PINID='DDR3_SB_ECC7';
NODE_NAME     J7 236
 '@S9S_MB_2U_LIB.S9S_MB_2U(SCH_1):PAGE88_I12@PURE_QUANTA.SCONN288_ADR50017P130CC(CHIPS)':
 'CB7_B': CDS_PINID='CB7_B';
NODE_NAME     J8 236
 '@S9S_MB_2U_LIB.S9S_MB_2U(SCH_1):PAGE89_I50@PURE_QUANTA.SCONN288_ADR50017P087CC(CHIPS)':
 'CB7_B': CDS_PINID='CB7_B';
NET_NAME
'M_D_CPU0_SB_CS_N<0>'
 '@S9S_MB_2U_LIB.S9S_MB_2U(SCH_1):M_D_CPU0_SB_CS_N'<0>:
 C_SIGNAL='@s9s_mb_2u_lib.s9s_mb_2u(sch_1):m_d_cpu0_sb_cs_n(0)';
NODE_NAME     U2 AC41
 '@S9S_MB_2U_LIB.S9S_MB_2U(SCH_1):PAGE23_I169@PURE_QUANTA.SOCKET4677_AZIF0045P001C01CS(CHIPS)':
 'DDR3_SB_CS_N0': CDS_PINID='DDR3_SB_CS_N0';
NODE_NAME     J7 84
 '@S9S_MB_2U_LIB.S9S_MB_2U(SCH_1):PAGE88_I12@PURE_QUANTA.SCONN288_ADR50017P130CC(CHIPS)':
 'CS0_B_N': CDS_PINID='CS0_B_N';
NET_NAME
'M_D_CPU0_SB_CS_N<1>'
 '@S9S_MB_2U_LIB.S9S_MB_2U(SCH_1):M_D_CPU0_SB_CS_N'<1>:
 C_SIGNAL='@s9s_mb_2u_lib.s9s_mb_2u(sch_1):m_d_cpu0_sb_cs_n(1)';
NODE_NAME     U2 AG41
 '@S9S_MB_2U_LIB.S9S_MB_2U(SCH_1):PAGE23_I169@PURE_QUANTA.SOCKET4677_AZIF0045P001C01CS(CHIPS)':
 'DDR3_SB_CS_N1': CDS_PINID='DDR3_SB_CS_N1';
NODE_NAME     J7 229
 '@S9S_MB_2U_LIB.S9S_MB_2U(SCH_1):PAGE88_I12@PURE_QUANTA.SCONN288_ADR50017P130CC(CHIPS)':
 'CS1_B_N': CDS_PINID='CS1_B_N';
NET_NAME
'M_D_CPU0_SB_CS_N<2>'
 '@S9S_MB_2U_LIB.S9S_MB_2U(SCH_1):M_D_CPU0_SB_CS_N'<2>:
 C_SIGNAL='@s9s_mb_2u_lib.s9s_mb_2u(sch_1):m_d_cpu0_sb_cs_n(2)';
NODE_NAME     U2 AF40
 '@S9S_MB_2U_LIB.S9S_MB_2U(SCH_1):PAGE23_I169@PURE_QUANTA.SOCKET4677_AZIF0045P001C01CS(CHIPS)':
 'DDR3_SB_CS_N2': CDS_PINID='DDR3_SB_CS_N2';
NODE_NAME     J8 84
 '@S9S_MB_2U_LIB.S9S_MB_2U(SCH_1):PAGE89_I50@PURE_QUANTA.SCONN288_ADR50017P087CC(CHIPS)':
 'CS0_B_N': CDS_PINID='CS0_B_N';
NET_NAME
'M_D_CPU0_SB_CS_N<3>'
 '@S9S_MB_2U_LIB.S9S_MB_2U(SCH_1):M_D_CPU0_SB_CS_N'<3>:
 C_SIGNAL='@s9s_mb_2u_lib.s9s_mb_2u(sch_1):m_d_cpu0_sb_cs_n(3)';
NODE_NAME     U2 AD40
 '@S9S_MB_2U_LIB.S9S_MB_2U(SCH_1):PAGE23_I169@PURE_QUANTA.SOCKET4677_AZIF0045P001C01CS(CHIPS)':
 'DDR3_SB_CS_N3': CDS_PINID='DDR3_SB_CS_N3';
NODE_NAME     J8 229
 '@S9S_MB_2U_LIB.S9S_MB_2U(SCH_1):PAGE89_I50@PURE_QUANTA.SCONN288_ADR50017P087CC(CHIPS)':
 'CS1_B_N': CDS_PINID='CS1_B_N';
NET_NAME
'M_D_CPU0_SB_DQ<0>'
 '@S9S_MB_2U_LIB.S9S_MB_2U(SCH_1):M_D_CPU0_SB_DQ'<0>:
 C_SIGNAL='@s9s_mb_2u_lib.s9s_mb_2u(sch_1):m_d_cpu0_sb_dq(0)';
NODE_NAME     U2 AL35
 '@S9S_MB_2U_LIB.S9S_MB_2U(SCH_1):PAGE23_I169@PURE_QUANTA.SOCKET4677_AZIF0045P001C01CS(CHIPS)':
 'DDR3_SB_DQ0': CDS_PINID='DDR3_SB_DQ0';
NODE_NAME     J7 100
 '@S9S_MB_2U_LIB.S9S_MB_2U(SCH_1):PAGE88_I12@PURE_QUANTA.SCONN288_ADR50017P130CC(CHIPS)':
 'DQ0_B': CDS_PINID='DQ0_B';
NODE_NAME     J8 100
 '@S9S_MB_2U_LIB.S9S_MB_2U(SCH_1):PAGE89_I50@PURE_QUANTA.SCONN288_ADR50017P087CC(CHIPS)':
 'DQ0_B': CDS_PINID='DQ0_B';
NET_NAME
'M_D_CPU0_SB_DQ<10>'
 '@S9S_MB_2U_LIB.S9S_MB_2U(SCH_1):M_D_CPU0_SB_DQ'<10>:
 C_SIGNAL='@s9s_mb_2u_lib.s9s_mb_2u(sch_1):m_d_cpu0_sb_dq(10)';
NODE_NAME     U2 AN29
 '@S9S_MB_2U_LIB.S9S_MB_2U(SCH_1):PAGE23_I169@PURE_QUANTA.SOCKET4677_AZIF0045P001C01CS(CHIPS)':
 'DDR3_SB_DQ10': CDS_PINID='DDR3_SB_DQ10';
NODE_NAME     J7 256
 '@S9S_MB_2U_LIB.S9S_MB_2U(SCH_1):PAGE88_I12@PURE_QUANTA.SCONN288_ADR50017P130CC(CHIPS)':
 'DQ10_B': CDS_PINID='DQ10_B';
NODE_NAME     J8 256
 '@S9S_MB_2U_LIB.S9S_MB_2U(SCH_1):PAGE89_I50@PURE_QUANTA.SCONN288_ADR50017P087CC(CHIPS)':
 'DQ10_B': CDS_PINID='DQ10_B';
NET_NAME
'M_D_CPU0_SB_DQ<11>'
 '@S9S_MB_2U_LIB.S9S_MB_2U(SCH_1):M_D_CPU0_SB_DQ'<11>:
 C_SIGNAL='@s9s_mb_2u_lib.s9s_mb_2u(sch_1):m_d_cpu0_sb_dq(11)';
NODE_NAME     U2 AP28
 '@S9S_MB_2U_LIB.S9S_MB_2U(SCH_1):PAGE23_I169@PURE_QUANTA.SOCKET4677_AZIF0045P001C01CS(CHIPS)':
 'DDR3_SB_DQ11': CDS_PINID='DDR3_SB_DQ11';
NODE_NAME     J7 258
 '@S9S_MB_2U_LIB.S9S_MB_2U(SCH_1):PAGE88_I12@PURE_QUANTA.SCONN288_ADR50017P130CC(CHIPS)':
 'DQ11_B': CDS_PINID='DQ11_B';
NODE_NAME     J8 258
 '@S9S_MB_2U_LIB.S9S_MB_2U(SCH_1):PAGE89_I50@PURE_QUANTA.SCONN288_ADR50017P087CC(CHIPS)':
 'DQ11_B': CDS_PINID='DQ11_B';
NET_NAME
'M_D_CPU0_SB_DQ<12>'
 '@S9S_MB_2U_LIB.S9S_MB_2U(SCH_1):M_D_CPU0_SB_DQ'<12>:
 C_SIGNAL='@s9s_mb_2u_lib.s9s_mb_2u(sch_1):m_d_cpu0_sb_dq(12)';
NODE_NAME     U2 AK26
 '@S9S_MB_2U_LIB.S9S_MB_2U(SCH_1):PAGE23_I169@PURE_QUANTA.SOCKET4677_AZIF0045P001C01CS(CHIPS)':
 'DDR3_SB_DQ12': CDS_PINID='DDR3_SB_DQ12';
NODE_NAME     J7 118
 '@S9S_MB_2U_LIB.S9S_MB_2U(SCH_1):PAGE88_I12@PURE_QUANTA.SCONN288_ADR50017P130CC(CHIPS)':
 'DQ12_B': CDS_PINID='DQ12_B';
NODE_NAME     J8 118
 '@S9S_MB_2U_LIB.S9S_MB_2U(SCH_1):PAGE89_I50@PURE_QUANTA.SCONN288_ADR50017P087CC(CHIPS)':
 'DQ12_B': CDS_PINID='DQ12_B';
NET_NAME
'M_D_CPU0_SB_DQ<13>'
 '@S9S_MB_2U_LIB.S9S_MB_2U(SCH_1):M_D_CPU0_SB_DQ'<13>:
 C_SIGNAL='@s9s_mb_2u_lib.s9s_mb_2u(sch_1):m_d_cpu0_sb_dq(13)';
NODE_NAME     U2 AL25
 '@S9S_MB_2U_LIB.S9S_MB_2U(SCH_1):PAGE23_I169@PURE_QUANTA.SOCKET4677_AZIF0045P001C01CS(CHIPS)':
 'DDR3_SB_DQ13': CDS_PINID='DDR3_SB_DQ13';
NODE_NAME     J7 120
 '@S9S_MB_2U_LIB.S9S_MB_2U(SCH_1):PAGE88_I12@PURE_QUANTA.SCONN288_ADR50017P130CC(CHIPS)':
 'DQ13_B': CDS_PINID='DQ13_B';
NODE_NAME     J8 120
 '@S9S_MB_2U_LIB.S9S_MB_2U(SCH_1):PAGE89_I50@PURE_QUANTA.SCONN288_ADR50017P087CC(CHIPS)':
 'DQ13_B': CDS_PINID='DQ13_B';
NET_NAME
'M_D_CPU0_SB_DQ<14>'
 '@S9S_MB_2U_LIB.S9S_MB_2U(SCH_1):M_D_CPU0_SB_DQ'<14>:
 C_SIGNAL='@s9s_mb_2u_lib.s9s_mb_2u(sch_1):m_d_cpu0_sb_dq(14)';
NODE_NAME     U2 AP26
 '@S9S_MB_2U_LIB.S9S_MB_2U(SCH_1):PAGE23_I169@PURE_QUANTA.SOCKET4677_AZIF0045P001C01CS(CHIPS)':
 'DDR3_SB_DQ14': CDS_PINID='DDR3_SB_DQ14';
NODE_NAME     J7 263
 '@S9S_MB_2U_LIB.S9S_MB_2U(SCH_1):PAGE88_I12@PURE_QUANTA.SCONN288_ADR50017P130CC(CHIPS)':
 'DQ14_B': CDS_PINID='DQ14_B';
NODE_NAME     J8 263
 '@S9S_MB_2U_LIB.S9S_MB_2U(SCH_1):PAGE89_I50@PURE_QUANTA.SCONN288_ADR50017P087CC(CHIPS)':
 'DQ14_B': CDS_PINID='DQ14_B';
NET_NAME
'M_D_CPU0_SB_DQ<15>'
 '@S9S_MB_2U_LIB.S9S_MB_2U(SCH_1):M_D_CPU0_SB_DQ'<15>:
 C_SIGNAL='@s9s_mb_2u_lib.s9s_mb_2u(sch_1):m_d_cpu0_sb_dq(15)';
NODE_NAME     U2 AN25
 '@S9S_MB_2U_LIB.S9S_MB_2U(SCH_1):PAGE23_I169@PURE_QUANTA.SOCKET4677_AZIF0045P001C01CS(CHIPS)':
 'DDR3_SB_DQ15': CDS_PINID='DDR3_SB_DQ15';
NODE_NAME     J7 265
 '@S9S_MB_2U_LIB.S9S_MB_2U(SCH_1):PAGE88_I12@PURE_QUANTA.SCONN288_ADR50017P130CC(CHIPS)':
 'DQ15_B': CDS_PINID='DQ15_B';
NODE_NAME     J8 265
 '@S9S_MB_2U_LIB.S9S_MB_2U(SCH_1):PAGE89_I50@PURE_QUANTA.SCONN288_ADR50017P087CC(CHIPS)':
 'DQ15_B': CDS_PINID='DQ15_B';
NET_NAME
'M_D_CPU0_SB_DQ<16>'
 '@S9S_MB_2U_LIB.S9S_MB_2U(SCH_1):M_D_CPU0_SB_DQ'<16>:
 C_SIGNAL='@s9s_mb_2u_lib.s9s_mb_2u(sch_1):m_d_cpu0_sb_dq(16)';
NODE_NAME     U2 AD26
 '@S9S_MB_2U_LIB.S9S_MB_2U(SCH_1):PAGE23_I169@PURE_QUANTA.SOCKET4677_AZIF0045P001C01CS(CHIPS)':
 'DDR3_SB_DQ16': CDS_PINID='DDR3_SB_DQ16';
NODE_NAME     J7 122
 '@S9S_MB_2U_LIB.S9S_MB_2U(SCH_1):PAGE88_I12@PURE_QUANTA.SCONN288_ADR50017P130CC(CHIPS)':
 'DQ16_B': CDS_PINID='DQ16_B';
NODE_NAME     J8 122
 '@S9S_MB_2U_LIB.S9S_MB_2U(SCH_1):PAGE89_I50@PURE_QUANTA.SCONN288_ADR50017P087CC(CHIPS)':
 'DQ16_B': CDS_PINID='DQ16_B';
NET_NAME
'M_D_CPU0_SB_DQ<17>'
 '@S9S_MB_2U_LIB.S9S_MB_2U(SCH_1):M_D_CPU0_SB_DQ'<17>:
 C_SIGNAL='@s9s_mb_2u_lib.s9s_mb_2u(sch_1):m_d_cpu0_sb_dq(17)';
NODE_NAME     U2 AC25
 '@S9S_MB_2U_LIB.S9S_MB_2U(SCH_1):PAGE23_I169@PURE_QUANTA.SOCKET4677_AZIF0045P001C01CS(CHIPS)':
 'DDR3_SB_DQ17': CDS_PINID='DDR3_SB_DQ17';
NODE_NAME     J7 124
 '@S9S_MB_2U_LIB.S9S_MB_2U(SCH_1):PAGE88_I12@PURE_QUANTA.SCONN288_ADR50017P130CC(CHIPS)':
 'DQ17_B': CDS_PINID='DQ17_B';
NODE_NAME     J8 124
 '@S9S_MB_2U_LIB.S9S_MB_2U(SCH_1):PAGE89_I50@PURE_QUANTA.SCONN288_ADR50017P087CC(CHIPS)':
 'DQ17_B': CDS_PINID='DQ17_B';
NET_NAME
'M_D_CPU0_SB_DQ<18>'
 '@S9S_MB_2U_LIB.S9S_MB_2U(SCH_1):M_D_CPU0_SB_DQ'<18>:
 C_SIGNAL='@s9s_mb_2u_lib.s9s_mb_2u(sch_1):m_d_cpu0_sb_dq(18)';
NODE_NAME     U2 AF26
 '@S9S_MB_2U_LIB.S9S_MB_2U(SCH_1):PAGE23_I169@PURE_QUANTA.SOCKET4677_AZIF0045P001C01CS(CHIPS)':
 'DDR3_SB_DQ18': CDS_PINID='DDR3_SB_DQ18';
NODE_NAME     J7 267
 '@S9S_MB_2U_LIB.S9S_MB_2U(SCH_1):PAGE88_I12@PURE_QUANTA.SCONN288_ADR50017P130CC(CHIPS)':
 'DQ18_B': CDS_PINID='DQ18_B';
NODE_NAME     J8 267
 '@S9S_MB_2U_LIB.S9S_MB_2U(SCH_1):PAGE89_I50@PURE_QUANTA.SCONN288_ADR50017P087CC(CHIPS)':
 'DQ18_B': CDS_PINID='DQ18_B';
NET_NAME
'M_D_CPU0_SB_DQ<19>'
 '@S9S_MB_2U_LIB.S9S_MB_2U(SCH_1):M_D_CPU0_SB_DQ'<19>:
 C_SIGNAL='@s9s_mb_2u_lib.s9s_mb_2u(sch_1):m_d_cpu0_sb_dq(19)';
NODE_NAME     U2 AG25
 '@S9S_MB_2U_LIB.S9S_MB_2U(SCH_1):PAGE23_I169@PURE_QUANTA.SOCKET4677_AZIF0045P001C01CS(CHIPS)':
 'DDR3_SB_DQ19': CDS_PINID='DDR3_SB_DQ19';
NODE_NAME     J7 269
 '@S9S_MB_2U_LIB.S9S_MB_2U(SCH_1):PAGE88_I12@PURE_QUANTA.SCONN288_ADR50017P130CC(CHIPS)':
 'DQ19_B': CDS_PINID='DQ19_B';
NODE_NAME     J8 269
 '@S9S_MB_2U_LIB.S9S_MB_2U(SCH_1):PAGE89_I50@PURE_QUANTA.SCONN288_ADR50017P087CC(CHIPS)':
 'DQ19_B': CDS_PINID='DQ19_B';
NET_NAME
'M_D_CPU0_SB_DQ<1>'
 '@S9S_MB_2U_LIB.S9S_MB_2U(SCH_1):M_D_CPU0_SB_DQ'<1>:
 C_SIGNAL='@s9s_mb_2u_lib.s9s_mb_2u(sch_1):m_d_cpu0_sb_dq(1)';
NODE_NAME     U2 AK34
 '@S9S_MB_2U_LIB.S9S_MB_2U(SCH_1):PAGE23_I169@PURE_QUANTA.SOCKET4677_AZIF0045P001C01CS(CHIPS)':
 'DDR3_SB_DQ1': CDS_PINID='DDR3_SB_DQ1';
NODE_NAME     J7 102
 '@S9S_MB_2U_LIB.S9S_MB_2U(SCH_1):PAGE88_I12@PURE_QUANTA.SCONN288_ADR50017P130CC(CHIPS)':
 'DQ1_B': CDS_PINID='DQ1_B';
NODE_NAME     J8 102
 '@S9S_MB_2U_LIB.S9S_MB_2U(SCH_1):PAGE89_I50@PURE_QUANTA.SCONN288_ADR50017P087CC(CHIPS)':
 'DQ1_B': CDS_PINID='DQ1_B';
NET_NAME
'M_D_CPU0_SB_DQ<20>'
 '@S9S_MB_2U_LIB.S9S_MB_2U(SCH_1):M_D_CPU0_SB_DQ'<20>:
 C_SIGNAL='@s9s_mb_2u_lib.s9s_mb_2u(sch_1):m_d_cpu0_sb_dq(20)';
NODE_NAME     U2 AC23
 '@S9S_MB_2U_LIB.S9S_MB_2U(SCH_1):PAGE23_I169@PURE_QUANTA.SOCKET4677_AZIF0045P001C01CS(CHIPS)':
 'DDR3_SB_DQ20': CDS_PINID='DDR3_SB_DQ20';
NODE_NAME     J7 129
 '@S9S_MB_2U_LIB.S9S_MB_2U(SCH_1):PAGE88_I12@PURE_QUANTA.SCONN288_ADR50017P130CC(CHIPS)':
 'DQ20_B': CDS_PINID='DQ20_B';
NODE_NAME     J8 129
 '@S9S_MB_2U_LIB.S9S_MB_2U(SCH_1):PAGE89_I50@PURE_QUANTA.SCONN288_ADR50017P087CC(CHIPS)':
 'DQ20_B': CDS_PINID='DQ20_B';
NET_NAME
'M_D_CPU0_SB_DQ<21>'
 '@S9S_MB_2U_LIB.S9S_MB_2U(SCH_1):M_D_CPU0_SB_DQ'<21>:
 C_SIGNAL='@s9s_mb_2u_lib.s9s_mb_2u(sch_1):m_d_cpu0_sb_dq(21)';
NODE_NAME     U2 AD22
 '@S9S_MB_2U_LIB.S9S_MB_2U(SCH_1):PAGE23_I169@PURE_QUANTA.SOCKET4677_AZIF0045P001C01CS(CHIPS)':
 'DDR3_SB_DQ21': CDS_PINID='DDR3_SB_DQ21';
NODE_NAME     J7 131
 '@S9S_MB_2U_LIB.S9S_MB_2U(SCH_1):PAGE88_I12@PURE_QUANTA.SCONN288_ADR50017P130CC(CHIPS)':
 'DQ21_B': CDS_PINID='DQ21_B';
NODE_NAME     J8 131
 '@S9S_MB_2U_LIB.S9S_MB_2U(SCH_1):PAGE89_I50@PURE_QUANTA.SCONN288_ADR50017P087CC(CHIPS)':
 'DQ21_B': CDS_PINID='DQ21_B';
NET_NAME
'M_D_CPU0_SB_DQ<22>'
 '@S9S_MB_2U_LIB.S9S_MB_2U(SCH_1):M_D_CPU0_SB_DQ'<22>:
 C_SIGNAL='@s9s_mb_2u_lib.s9s_mb_2u(sch_1):m_d_cpu0_sb_dq(22)';
NODE_NAME     U2 AG23
 '@S9S_MB_2U_LIB.S9S_MB_2U(SCH_1):PAGE23_I169@PURE_QUANTA.SOCKET4677_AZIF0045P001C01CS(CHIPS)':
 'DDR3_SB_DQ22': CDS_PINID='DDR3_SB_DQ22';
NODE_NAME     J7 274
 '@S9S_MB_2U_LIB.S9S_MB_2U(SCH_1):PAGE88_I12@PURE_QUANTA.SCONN288_ADR50017P130CC(CHIPS)':
 'DQ22_B': CDS_PINID='DQ22_B';
NODE_NAME     J8 274
 '@S9S_MB_2U_LIB.S9S_MB_2U(SCH_1):PAGE89_I50@PURE_QUANTA.SCONN288_ADR50017P087CC(CHIPS)':
 'DQ22_B': CDS_PINID='DQ22_B';
NET_NAME
'M_D_CPU0_SB_DQ<23>'
 '@S9S_MB_2U_LIB.S9S_MB_2U(SCH_1):M_D_CPU0_SB_DQ'<23>:
 C_SIGNAL='@s9s_mb_2u_lib.s9s_mb_2u(sch_1):m_d_cpu0_sb_dq(23)';
NODE_NAME     U2 AF22
 '@S9S_MB_2U_LIB.S9S_MB_2U(SCH_1):PAGE23_I169@PURE_QUANTA.SOCKET4677_AZIF0045P001C01CS(CHIPS)':
 'DDR3_SB_DQ23': CDS_PINID='DDR3_SB_DQ23';
NODE_NAME     J7 276
 '@S9S_MB_2U_LIB.S9S_MB_2U(SCH_1):PAGE88_I12@PURE_QUANTA.SCONN288_ADR50017P130CC(CHIPS)':
 'DQ23_B': CDS_PINID='DQ23_B';
NODE_NAME     J8 276
 '@S9S_MB_2U_LIB.S9S_MB_2U(SCH_1):PAGE89_I50@PURE_QUANTA.SCONN288_ADR50017P087CC(CHIPS)':
 'DQ23_B': CDS_PINID='DQ23_B';
NET_NAME
'M_D_CPU0_SB_DQ<24>'
 '@S9S_MB_2U_LIB.S9S_MB_2U(SCH_1):M_D_CPU0_SB_DQ'<24>:
 C_SIGNAL='@s9s_mb_2u_lib.s9s_mb_2u(sch_1):m_d_cpu0_sb_dq(24)';
NODE_NAME     U2 AL23
 '@S9S_MB_2U_LIB.S9S_MB_2U(SCH_1):PAGE23_I169@PURE_QUANTA.SOCKET4677_AZIF0045P001C01CS(CHIPS)':
 'DDR3_SB_DQ24': CDS_PINID='DDR3_SB_DQ24';
NODE_NAME     J7 133
 '@S9S_MB_2U_LIB.S9S_MB_2U(SCH_1):PAGE88_I12@PURE_QUANTA.SCONN288_ADR50017P130CC(CHIPS)':
 'DQ24_B': CDS_PINID='DQ24_B';
NODE_NAME     J8 133
 '@S9S_MB_2U_LIB.S9S_MB_2U(SCH_1):PAGE89_I50@PURE_QUANTA.SCONN288_ADR50017P087CC(CHIPS)':
 'DQ24_B': CDS_PINID='DQ24_B';
NET_NAME
'M_D_CPU0_SB_DQ<25>'
 '@S9S_MB_2U_LIB.S9S_MB_2U(SCH_1):M_D_CPU0_SB_DQ'<25>:
 C_SIGNAL='@s9s_mb_2u_lib.s9s_mb_2u(sch_1):m_d_cpu0_sb_dq(25)';
NODE_NAME     U2 AK22
 '@S9S_MB_2U_LIB.S9S_MB_2U(SCH_1):PAGE23_I169@PURE_QUANTA.SOCKET4677_AZIF0045P001C01CS(CHIPS)':
 'DDR3_SB_DQ25': CDS_PINID='DDR3_SB_DQ25';
NODE_NAME     J7 135
 '@S9S_MB_2U_LIB.S9S_MB_2U(SCH_1):PAGE88_I12@PURE_QUANTA.SCONN288_ADR50017P130CC(CHIPS)':
 'DQ25_B': CDS_PINID='DQ25_B';
NODE_NAME     J8 135
 '@S9S_MB_2U_LIB.S9S_MB_2U(SCH_1):PAGE89_I50@PURE_QUANTA.SCONN288_ADR50017P087CC(CHIPS)':
 'DQ25_B': CDS_PINID='DQ25_B';
NET_NAME
'M_D_CPU0_SB_DQ<26>'
 '@S9S_MB_2U_LIB.S9S_MB_2U(SCH_1):M_D_CPU0_SB_DQ'<26>:
 C_SIGNAL='@s9s_mb_2u_lib.s9s_mb_2u(sch_1):m_d_cpu0_sb_dq(26)';
NODE_NAME     U2 AN23
 '@S9S_MB_2U_LIB.S9S_MB_2U(SCH_1):PAGE23_I169@PURE_QUANTA.SOCKET4677_AZIF0045P001C01CS(CHIPS)':
 'DDR3_SB_DQ26': CDS_PINID='DDR3_SB_DQ26';
NODE_NAME     J7 278
 '@S9S_MB_2U_LIB.S9S_MB_2U(SCH_1):PAGE88_I12@PURE_QUANTA.SCONN288_ADR50017P130CC(CHIPS)':
 'DQ26_B': CDS_PINID='DQ26_B';
NODE_NAME     J8 278
 '@S9S_MB_2U_LIB.S9S_MB_2U(SCH_1):PAGE89_I50@PURE_QUANTA.SCONN288_ADR50017P087CC(CHIPS)':
 'DQ26_B': CDS_PINID='DQ26_B';
NET_NAME
'M_D_CPU0_SB_DQ<27>'
 '@S9S_MB_2U_LIB.S9S_MB_2U(SCH_1):M_D_CPU0_SB_DQ'<27>:
 C_SIGNAL='@s9s_mb_2u_lib.s9s_mb_2u(sch_1):m_d_cpu0_sb_dq(27)';
NODE_NAME     U2 AP22
 '@S9S_MB_2U_LIB.S9S_MB_2U(SCH_1):PAGE23_I169@PURE_QUANTA.SOCKET4677_AZIF0045P001C01CS(CHIPS)':
 'DDR3_SB_DQ27': CDS_PINID='DDR3_SB_DQ27';
NODE_NAME     J7 280
 '@S9S_MB_2U_LIB.S9S_MB_2U(SCH_1):PAGE88_I12@PURE_QUANTA.SCONN288_ADR50017P130CC(CHIPS)':
 'DQ27_B': CDS_PINID='DQ27_B';
NODE_NAME     J8 280
 '@S9S_MB_2U_LIB.S9S_MB_2U(SCH_1):PAGE89_I50@PURE_QUANTA.SCONN288_ADR50017P087CC(CHIPS)':
 'DQ27_B': CDS_PINID='DQ27_B';
NET_NAME
'M_D_CPU0_SB_DQ<28>'
 '@S9S_MB_2U_LIB.S9S_MB_2U(SCH_1):M_D_CPU0_SB_DQ'<28>:
 C_SIGNAL='@s9s_mb_2u_lib.s9s_mb_2u(sch_1):m_d_cpu0_sb_dq(28)';
NODE_NAME     U2 AK20
 '@S9S_MB_2U_LIB.S9S_MB_2U(SCH_1):PAGE23_I169@PURE_QUANTA.SOCKET4677_AZIF0045P001C01CS(CHIPS)':
 'DDR3_SB_DQ28': CDS_PINID='DDR3_SB_DQ28';
NODE_NAME     J7 140
 '@S9S_MB_2U_LIB.S9S_MB_2U(SCH_1):PAGE88_I12@PURE_QUANTA.SCONN288_ADR50017P130CC(CHIPS)':
 'DQ28_B': CDS_PINID='DQ28_B';
NODE_NAME     J8 140
 '@S9S_MB_2U_LIB.S9S_MB_2U(SCH_1):PAGE89_I50@PURE_QUANTA.SCONN288_ADR50017P087CC(CHIPS)':
 'DQ28_B': CDS_PINID='DQ28_B';
NET_NAME
'M_D_CPU0_SB_DQ<29>'
 '@S9S_MB_2U_LIB.S9S_MB_2U(SCH_1):M_D_CPU0_SB_DQ'<29>:
 C_SIGNAL='@s9s_mb_2u_lib.s9s_mb_2u(sch_1):m_d_cpu0_sb_dq(29)';
NODE_NAME     U2 AL19
 '@S9S_MB_2U_LIB.S9S_MB_2U(SCH_1):PAGE23_I169@PURE_QUANTA.SOCKET4677_AZIF0045P001C01CS(CHIPS)':
 'DDR3_SB_DQ29': CDS_PINID='DDR3_SB_DQ29';
NODE_NAME     J7 142
 '@S9S_MB_2U_LIB.S9S_MB_2U(SCH_1):PAGE88_I12@PURE_QUANTA.SCONN288_ADR50017P130CC(CHIPS)':
 'DQ29_B': CDS_PINID='DQ29_B';
NODE_NAME     J8 142
 '@S9S_MB_2U_LIB.S9S_MB_2U(SCH_1):PAGE89_I50@PURE_QUANTA.SCONN288_ADR50017P087CC(CHIPS)':
 'DQ29_B': CDS_PINID='DQ29_B';
NET_NAME
'M_D_CPU0_SB_DQ<2>'
 '@S9S_MB_2U_LIB.S9S_MB_2U(SCH_1):M_D_CPU0_SB_DQ'<2>:
 C_SIGNAL='@s9s_mb_2u_lib.s9s_mb_2u(sch_1):m_d_cpu0_sb_dq(2)';
NODE_NAME     U2 AN35
 '@S9S_MB_2U_LIB.S9S_MB_2U(SCH_1):PAGE23_I169@PURE_QUANTA.SOCKET4677_AZIF0045P001C01CS(CHIPS)':
 'DDR3_SB_DQ2': CDS_PINID='DDR3_SB_DQ2';
NODE_NAME     J7 245
 '@S9S_MB_2U_LIB.S9S_MB_2U(SCH_1):PAGE88_I12@PURE_QUANTA.SCONN288_ADR50017P130CC(CHIPS)':
 'DQ2_B': CDS_PINID='DQ2_B';
NODE_NAME     J8 245
 '@S9S_MB_2U_LIB.S9S_MB_2U(SCH_1):PAGE89_I50@PURE_QUANTA.SCONN288_ADR50017P087CC(CHIPS)':
 'DQ2_B': CDS_PINID='DQ2_B';
NET_NAME
'M_D_CPU0_SB_DQ<30>'
 '@S9S_MB_2U_LIB.S9S_MB_2U(SCH_1):M_D_CPU0_SB_DQ'<30>:
 C_SIGNAL='@s9s_mb_2u_lib.s9s_mb_2u(sch_1):m_d_cpu0_sb_dq(30)';
NODE_NAME     U2 AP20
 '@S9S_MB_2U_LIB.S9S_MB_2U(SCH_1):PAGE23_I169@PURE_QUANTA.SOCKET4677_AZIF0045P001C01CS(CHIPS)':
 'DDR3_SB_DQ30': CDS_PINID='DDR3_SB_DQ30';
NODE_NAME     J7 285
 '@S9S_MB_2U_LIB.S9S_MB_2U(SCH_1):PAGE88_I12@PURE_QUANTA.SCONN288_ADR50017P130CC(CHIPS)':
 'DQ30_B': CDS_PINID='DQ30_B';
NODE_NAME     J8 285
 '@S9S_MB_2U_LIB.S9S_MB_2U(SCH_1):PAGE89_I50@PURE_QUANTA.SCONN288_ADR50017P087CC(CHIPS)':
 'DQ30_B': CDS_PINID='DQ30_B';
NET_NAME
'M_D_CPU0_SB_DQ<31>'
 '@S9S_MB_2U_LIB.S9S_MB_2U(SCH_1):M_D_CPU0_SB_DQ'<31>:
 C_SIGNAL='@s9s_mb_2u_lib.s9s_mb_2u(sch_1):m_d_cpu0_sb_dq(31)';
NODE_NAME     U2 AN19
 '@S9S_MB_2U_LIB.S9S_MB_2U(SCH_1):PAGE23_I169@PURE_QUANTA.SOCKET4677_AZIF0045P001C01CS(CHIPS)':
 'DDR3_SB_DQ31': CDS_PINID='DDR3_SB_DQ31';
NODE_NAME     J7 287
 '@S9S_MB_2U_LIB.S9S_MB_2U(SCH_1):PAGE88_I12@PURE_QUANTA.SCONN288_ADR50017P130CC(CHIPS)':
 'DQ31_B': CDS_PINID='DQ31_B';
NODE_NAME     J8 287
 '@S9S_MB_2U_LIB.S9S_MB_2U(SCH_1):PAGE89_I50@PURE_QUANTA.SCONN288_ADR50017P087CC(CHIPS)':
 'DQ31_B': CDS_PINID='DQ31_B';
NET_NAME
'M_D_CPU0_SB_DQ<3>'
 '@S9S_MB_2U_LIB.S9S_MB_2U(SCH_1):M_D_CPU0_SB_DQ'<3>:
 C_SIGNAL='@s9s_mb_2u_lib.s9s_mb_2u(sch_1):m_d_cpu0_sb_dq(3)';
NODE_NAME     U2 AP34
 '@S9S_MB_2U_LIB.S9S_MB_2U(SCH_1):PAGE23_I169@PURE_QUANTA.SOCKET4677_AZIF0045P001C01CS(CHIPS)':
 'DDR3_SB_DQ3': CDS_PINID='DDR3_SB_DQ3';
NODE_NAME     J7 247
 '@S9S_MB_2U_LIB.S9S_MB_2U(SCH_1):PAGE88_I12@PURE_QUANTA.SCONN288_ADR50017P130CC(CHIPS)':
 'DQ3_B': CDS_PINID='DQ3_B';
NODE_NAME     J8 247
 '@S9S_MB_2U_LIB.S9S_MB_2U(SCH_1):PAGE89_I50@PURE_QUANTA.SCONN288_ADR50017P087CC(CHIPS)':
 'DQ3_B': CDS_PINID='DQ3_B';
NET_NAME
'M_D_CPU0_SB_DQ<4>'
 '@S9S_MB_2U_LIB.S9S_MB_2U(SCH_1):M_D_CPU0_SB_DQ'<4>:
 C_SIGNAL='@s9s_mb_2u_lib.s9s_mb_2u(sch_1):m_d_cpu0_sb_dq(4)';
NODE_NAME     U2 AK32
 '@S9S_MB_2U_LIB.S9S_MB_2U(SCH_1):PAGE23_I169@PURE_QUANTA.SOCKET4677_AZIF0045P001C01CS(CHIPS)':
 'DDR3_SB_DQ4': CDS_PINID='DDR3_SB_DQ4';
NODE_NAME     J7 107
 '@S9S_MB_2U_LIB.S9S_MB_2U(SCH_1):PAGE88_I12@PURE_QUANTA.SCONN288_ADR50017P130CC(CHIPS)':
 'DQ4_B': CDS_PINID='DQ4_B';
NODE_NAME     J8 107
 '@S9S_MB_2U_LIB.S9S_MB_2U(SCH_1):PAGE89_I50@PURE_QUANTA.SCONN288_ADR50017P087CC(CHIPS)':
 'DQ4_B': CDS_PINID='DQ4_B';
NET_NAME
'M_D_CPU0_SB_DQ<5>'
 '@S9S_MB_2U_LIB.S9S_MB_2U(SCH_1):M_D_CPU0_SB_DQ'<5>:
 C_SIGNAL='@s9s_mb_2u_lib.s9s_mb_2u(sch_1):m_d_cpu0_sb_dq(5)';
NODE_NAME     U2 AL31
 '@S9S_MB_2U_LIB.S9S_MB_2U(SCH_1):PAGE23_I169@PURE_QUANTA.SOCKET4677_AZIF0045P001C01CS(CHIPS)':
 'DDR3_SB_DQ5': CDS_PINID='DDR3_SB_DQ5';
NODE_NAME     J7 109
 '@S9S_MB_2U_LIB.S9S_MB_2U(SCH_1):PAGE88_I12@PURE_QUANTA.SCONN288_ADR50017P130CC(CHIPS)':
 'DQ5_B': CDS_PINID='DQ5_B';
NODE_NAME     J8 109
 '@S9S_MB_2U_LIB.S9S_MB_2U(SCH_1):PAGE89_I50@PURE_QUANTA.SCONN288_ADR50017P087CC(CHIPS)':
 'DQ5_B': CDS_PINID='DQ5_B';
NET_NAME
'M_D_CPU0_SB_DQ<6>'
 '@S9S_MB_2U_LIB.S9S_MB_2U(SCH_1):M_D_CPU0_SB_DQ'<6>:
 C_SIGNAL='@s9s_mb_2u_lib.s9s_mb_2u(sch_1):m_d_cpu0_sb_dq(6)';
NODE_NAME     U2 AP32
 '@S9S_MB_2U_LIB.S9S_MB_2U(SCH_1):PAGE23_I169@PURE_QUANTA.SOCKET4677_AZIF0045P001C01CS(CHIPS)':
 'DDR3_SB_DQ6': CDS_PINID='DDR3_SB_DQ6';
NODE_NAME     J7 252
 '@S9S_MB_2U_LIB.S9S_MB_2U(SCH_1):PAGE88_I12@PURE_QUANTA.SCONN288_ADR50017P130CC(CHIPS)':
 'DQ6_B': CDS_PINID='DQ6_B';
NODE_NAME     J8 252
 '@S9S_MB_2U_LIB.S9S_MB_2U(SCH_1):PAGE89_I50@PURE_QUANTA.SCONN288_ADR50017P087CC(CHIPS)':
 'DQ6_B': CDS_PINID='DQ6_B';
NET_NAME
'M_D_CPU0_SB_DQ<7>'
 '@S9S_MB_2U_LIB.S9S_MB_2U(SCH_1):M_D_CPU0_SB_DQ'<7>:
 C_SIGNAL='@s9s_mb_2u_lib.s9s_mb_2u(sch_1):m_d_cpu0_sb_dq(7)';
NODE_NAME     U2 AN31
 '@S9S_MB_2U_LIB.S9S_MB_2U(SCH_1):PAGE23_I169@PURE_QUANTA.SOCKET4677_AZIF0045P001C01CS(CHIPS)':
 'DDR3_SB_DQ7': CDS_PINID='DDR3_SB_DQ7';
NODE_NAME     J7 254
 '@S9S_MB_2U_LIB.S9S_MB_2U(SCH_1):PAGE88_I12@PURE_QUANTA.SCONN288_ADR50017P130CC(CHIPS)':
 'DQ7_B': CDS_PINID='DQ7_B';
NODE_NAME     J8 254
 '@S9S_MB_2U_LIB.S9S_MB_2U(SCH_1):PAGE89_I50@PURE_QUANTA.SCONN288_ADR50017P087CC(CHIPS)':
 'DQ7_B': CDS_PINID='DQ7_B';
NET_NAME
'M_D_CPU0_SB_DQ<8>'
 '@S9S_MB_2U_LIB.S9S_MB_2U(SCH_1):M_D_CPU0_SB_DQ'<8>:
 C_SIGNAL='@s9s_mb_2u_lib.s9s_mb_2u(sch_1):m_d_cpu0_sb_dq(8)';
NODE_NAME     U2 AL29
 '@S9S_MB_2U_LIB.S9S_MB_2U(SCH_1):PAGE23_I169@PURE_QUANTA.SOCKET4677_AZIF0045P001C01CS(CHIPS)':
 'DDR3_SB_DQ8': CDS_PINID='DDR3_SB_DQ8';
NODE_NAME     J7 111
 '@S9S_MB_2U_LIB.S9S_MB_2U(SCH_1):PAGE88_I12@PURE_QUANTA.SCONN288_ADR50017P130CC(CHIPS)':
 'DQ8_B': CDS_PINID='DQ8_B';
NODE_NAME     J8 111
 '@S9S_MB_2U_LIB.S9S_MB_2U(SCH_1):PAGE89_I50@PURE_QUANTA.SCONN288_ADR50017P087CC(CHIPS)':
 'DQ8_B': CDS_PINID='DQ8_B';
NET_NAME
'M_D_CPU0_SB_DQ<9>'
 '@S9S_MB_2U_LIB.S9S_MB_2U(SCH_1):M_D_CPU0_SB_DQ'<9>:
 C_SIGNAL='@s9s_mb_2u_lib.s9s_mb_2u(sch_1):m_d_cpu0_sb_dq(9)';
NODE_NAME     U2 AK28
 '@S9S_MB_2U_LIB.S9S_MB_2U(SCH_1):PAGE23_I169@PURE_QUANTA.SOCKET4677_AZIF0045P001C01CS(CHIPS)':
 'DDR3_SB_DQ9': CDS_PINID='DDR3_SB_DQ9';
NODE_NAME     J7 113
 '@S9S_MB_2U_LIB.S9S_MB_2U(SCH_1):PAGE88_I12@PURE_QUANTA.SCONN288_ADR50017P130CC(CHIPS)':
 'DQ9_B': CDS_PINID='DQ9_B';
NODE_NAME     J8 113
 '@S9S_MB_2U_LIB.S9S_MB_2U(SCH_1):PAGE89_I50@PURE_QUANTA.SCONN288_ADR50017P087CC(CHIPS)':
 'DQ9_B': CDS_PINID='DQ9_B';
NET_NAME
'M_D_CPU0_SB_DQS_DN<0>'
 '@S9S_MB_2U_LIB.S9S_MB_2U(SCH_1):M_D_CPU0_SB_DQS_DN'<0>:
 C_SIGNAL='@s9s_mb_2u_lib.s9s_mb_2u(sch_1):m_d_cpu0_sb_dqs_dn(0)';
NODE_NAME     U2 AJ33
 '@S9S_MB_2U_LIB.S9S_MB_2U(SCH_1):PAGE23_I169@PURE_QUANTA.SOCKET4677_AZIF0045P001C01CS(CHIPS)':
 'DDR3_SB_DQS_DN0': CDS_PINID='DDR3_SB_DQS_DN0';
NODE_NAME     J7 105
 '@S9S_MB_2U_LIB.S9S_MB_2U(SCH_1):PAGE88_I178@PURE_QUANTA.SCONN288_ADR50017P130CC(CHIPS)':
 'DQS0_B_C': CDS_PINID='DQS0_B_C';
NODE_NAME     J8 105
 '@S9S_MB_2U_LIB.S9S_MB_2U(SCH_1):PAGE89_I178@PURE_QUANTA.SCONN288_ADR50017P087CC(CHIPS)':
 'DQS0_B_C': CDS_PINID='DQS0_B_C';
NET_NAME
'M_D_CPU0_SB_DQS_DN<1>'
 '@S9S_MB_2U_LIB.S9S_MB_2U(SCH_1):M_D_CPU0_SB_DQS_DN'<1>:
 C_SIGNAL='@s9s_mb_2u_lib.s9s_mb_2u(sch_1):m_d_cpu0_sb_dqs_dn(1)';
NODE_NAME     U2 AJ27
 '@S9S_MB_2U_LIB.S9S_MB_2U(SCH_1):PAGE23_I169@PURE_QUANTA.SOCKET4677_AZIF0045P001C01CS(CHIPS)':
 'DDR3_SB_DQS_DN1': CDS_PINID='DDR3_SB_DQS_DN1';
NODE_NAME     J7 116
 '@S9S_MB_2U_LIB.S9S_MB_2U(SCH_1):PAGE88_I178@PURE_QUANTA.SCONN288_ADR50017P130CC(CHIPS)':
 'DQS1_B_C': CDS_PINID='DQS1_B_C';
NODE_NAME     J8 116
 '@S9S_MB_2U_LIB.S9S_MB_2U(SCH_1):PAGE89_I178@PURE_QUANTA.SCONN288_ADR50017P087CC(CHIPS)':
 'DQS1_B_C': CDS_PINID='DQS1_B_C';
NET_NAME
'M_D_CPU0_SB_DQS_DN<2>'
 '@S9S_MB_2U_LIB.S9S_MB_2U(SCH_1):M_D_CPU0_SB_DQS_DN'<2>:
 C_SIGNAL='@s9s_mb_2u_lib.s9s_mb_2u(sch_1):m_d_cpu0_sb_dqs_dn(2)';
NODE_NAME     U2 AB24
 '@S9S_MB_2U_LIB.S9S_MB_2U(SCH_1):PAGE23_I169@PURE_QUANTA.SOCKET4677_AZIF0045P001C01CS(CHIPS)':
 'DDR3_SB_DQS_DN2': CDS_PINID='DDR3_SB_DQS_DN2';
NODE_NAME     J7 127
 '@S9S_MB_2U_LIB.S9S_MB_2U(SCH_1):PAGE88_I178@PURE_QUANTA.SCONN288_ADR50017P130CC(CHIPS)':
 'DQS2_B_C': CDS_PINID='DQS2_B_C';
NODE_NAME     J8 127
 '@S9S_MB_2U_LIB.S9S_MB_2U(SCH_1):PAGE89_I178@PURE_QUANTA.SCONN288_ADR50017P087CC(CHIPS)':
 'DQS2_B_C': CDS_PINID='DQS2_B_C';
NET_NAME
'M_D_CPU0_SB_DQS_DN<3>'
 '@S9S_MB_2U_LIB.S9S_MB_2U(SCH_1):M_D_CPU0_SB_DQS_DN'<3>:
 C_SIGNAL='@s9s_mb_2u_lib.s9s_mb_2u(sch_1):m_d_cpu0_sb_dqs_dn(3)';
NODE_NAME     U2 AJ21
 '@S9S_MB_2U_LIB.S9S_MB_2U(SCH_1):PAGE23_I169@PURE_QUANTA.SOCKET4677_AZIF0045P001C01CS(CHIPS)':
 'DDR3_SB_DQS_DN3': CDS_PINID='DDR3_SB_DQS_DN3';
NODE_NAME     J7 138
 '@S9S_MB_2U_LIB.S9S_MB_2U(SCH_1):PAGE88_I178@PURE_QUANTA.SCONN288_ADR50017P130CC(CHIPS)':
 'DQS3_B_C': CDS_PINID='DQS3_B_C';
NODE_NAME     J8 138
 '@S9S_MB_2U_LIB.S9S_MB_2U(SCH_1):PAGE89_I178@PURE_QUANTA.SCONN288_ADR50017P087CC(CHIPS)':
 'DQS3_B_C': CDS_PINID='DQS3_B_C';
NET_NAME
'M_D_CPU0_SB_DQS_DN<4>'
 '@S9S_MB_2U_LIB.S9S_MB_2U(SCH_1):M_D_CPU0_SB_DQS_DN'<4>:
 C_SIGNAL='@s9s_mb_2u_lib.s9s_mb_2u(sch_1):m_d_cpu0_sb_dqs_dn(4)';
NODE_NAME     U2 AR39
 '@S9S_MB_2U_LIB.S9S_MB_2U(SCH_1):PAGE23_I169@PURE_QUANTA.SOCKET4677_AZIF0045P001C01CS(CHIPS)':
 'DDR3_SB_DQS_DN4': CDS_PINID='DDR3_SB_DQS_DN4';
NODE_NAME     J7 238
 '@S9S_MB_2U_LIB.S9S_MB_2U(SCH_1):PAGE88_I178@PURE_QUANTA.SCONN288_ADR50017P130CC(CHIPS)':
 'DQS4_B_C': CDS_PINID='DQS4_B_C';
NODE_NAME     J8 238
 '@S9S_MB_2U_LIB.S9S_MB_2U(SCH_1):PAGE89_I178@PURE_QUANTA.SCONN288_ADR50017P087CC(CHIPS)':
 'DQS4_B_C': CDS_PINID='DQS4_B_C';
NET_NAME
'M_D_CPU0_SB_DQS_DN<5>'
 '@S9S_MB_2U_LIB.S9S_MB_2U(SCH_1):M_D_CPU0_SB_DQS_DN'<5>:
 C_SIGNAL='@s9s_mb_2u_lib.s9s_mb_2u(sch_1):m_d_cpu0_sb_dqs_dn(5)';
NODE_NAME     U2 AN33
 '@S9S_MB_2U_LIB.S9S_MB_2U(SCH_1):PAGE23_I169@PURE_QUANTA.SOCKET4677_AZIF0045P001C01CS(CHIPS)':
 'DDR3_SB_DQS_DN5': CDS_PINID='DDR3_SB_DQS_DN5';
NODE_NAME     J7 249
 '@S9S_MB_2U_LIB.S9S_MB_2U(SCH_1):PAGE88_I178@PURE_QUANTA.SCONN288_ADR50017P130CC(CHIPS)':
 'DQS5_B_C||TDQS5_B_C': CDS_PINID='\dqs5_b_c||tdqs5_b_c\';
NODE_NAME     J8 249
 '@S9S_MB_2U_LIB.S9S_MB_2U(SCH_1):PAGE89_I178@PURE_QUANTA.SCONN288_ADR50017P087CC(CHIPS)':
 'DQS5_B_C||TDQS5_B_C': CDS_PINID='\dqs5_b_c||tdqs5_b_c\';
NET_NAME
'M_D_CPU0_SB_DQS_DN<6>'
 '@S9S_MB_2U_LIB.S9S_MB_2U(SCH_1):M_D_CPU0_SB_DQS_DN'<6>:
 C_SIGNAL='@s9s_mb_2u_lib.s9s_mb_2u(sch_1):m_d_cpu0_sb_dqs_dn(6)';
NODE_NAME     U2 AN27
 '@S9S_MB_2U_LIB.S9S_MB_2U(SCH_1):PAGE23_I169@PURE_QUANTA.SOCKET4677_AZIF0045P001C01CS(CHIPS)':
 'DDR3_SB_DQS_DN6': CDS_PINID='DDR3_SB_DQS_DN6';
NODE_NAME     J7 260
 '@S9S_MB_2U_LIB.S9S_MB_2U(SCH_1):PAGE88_I178@PURE_QUANTA.SCONN288_ADR50017P130CC(CHIPS)':
 'DQS6_B_C||TDQS6_B_C': CDS_PINID='\dqs6_b_c||tdqs6_b_c\';
NODE_NAME     J8 260
 '@S9S_MB_2U_LIB.S9S_MB_2U(SCH_1):PAGE89_I178@PURE_QUANTA.SCONN288_ADR50017P087CC(CHIPS)':
 'DQS6_B_C||TDQS6_B_C': CDS_PINID='\dqs6_b_c||tdqs6_b_c\';
NET_NAME
'M_D_CPU0_SB_DQS_DN<7>'
 '@S9S_MB_2U_LIB.S9S_MB_2U(SCH_1):M_D_CPU0_SB_DQS_DN'<7>:
 C_SIGNAL='@s9s_mb_2u_lib.s9s_mb_2u(sch_1):m_d_cpu0_sb_dqs_dn(7)';
NODE_NAME     U2 AF24
 '@S9S_MB_2U_LIB.S9S_MB_2U(SCH_1):PAGE23_I169@PURE_QUANTA.SOCKET4677_AZIF0045P001C01CS(CHIPS)':
 'DDR3_SB_DQS_DN7': CDS_PINID='DDR3_SB_DQS_DN7';
NODE_NAME     J7 271
 '@S9S_MB_2U_LIB.S9S_MB_2U(SCH_1):PAGE88_I178@PURE_QUANTA.SCONN288_ADR50017P130CC(CHIPS)':
 'DQS7_B_C||TDQS7_B_C': CDS_PINID='\dqs7_b_c||tdqs7_b_c\';
NODE_NAME     J8 271
 '@S9S_MB_2U_LIB.S9S_MB_2U(SCH_1):PAGE89_I178@PURE_QUANTA.SCONN288_ADR50017P087CC(CHIPS)':
 'DQS7_B_C||TDQS7_B_C': CDS_PINID='\dqs7_b_c||tdqs7_b_c\';
NET_NAME
'M_D_CPU0_SB_DQS_DN<8>'
 '@S9S_MB_2U_LIB.S9S_MB_2U(SCH_1):M_D_CPU0_SB_DQS_DN'<8>:
 C_SIGNAL='@s9s_mb_2u_lib.s9s_mb_2u(sch_1):m_d_cpu0_sb_dqs_dn(8)';
NODE_NAME     U2 AN21
 '@S9S_MB_2U_LIB.S9S_MB_2U(SCH_1):PAGE23_I169@PURE_QUANTA.SOCKET4677_AZIF0045P001C01CS(CHIPS)':
 'DDR3_SB_DQS_DN8': CDS_PINID='DDR3_SB_DQS_DN8';
NODE_NAME     J7 282
 '@S9S_MB_2U_LIB.S9S_MB_2U(SCH_1):PAGE88_I178@PURE_QUANTA.SCONN288_ADR50017P130CC(CHIPS)':
 'DQS8_B_C||TDQS8_B_C': CDS_PINID='\dqs8_b_c||tdqs8_b_c\';
NODE_NAME     J8 282
 '@S9S_MB_2U_LIB.S9S_MB_2U(SCH_1):PAGE89_I178@PURE_QUANTA.SCONN288_ADR50017P087CC(CHIPS)':
 'DQS8_B_C||TDQS8_B_C': CDS_PINID='\dqs8_b_c||tdqs8_b_c\';
NET_NAME
'M_D_CPU0_SB_DQS_DN<9>'
 '@S9S_MB_2U_LIB.S9S_MB_2U(SCH_1):M_D_CPU0_SB_DQS_DN'<9>:
 C_SIGNAL='@s9s_mb_2u_lib.s9s_mb_2u(sch_1):m_d_cpu0_sb_dqs_dn(9)';
NODE_NAME     U2 AJ39
 '@S9S_MB_2U_LIB.S9S_MB_2U(SCH_1):PAGE23_I169@PURE_QUANTA.SOCKET4677_AZIF0045P001C01CS(CHIPS)':
 'DDR3_SB_DQS_DN9': CDS_PINID='DDR3_SB_DQS_DN9';
NODE_NAME     J7 94
 '@S9S_MB_2U_LIB.S9S_MB_2U(SCH_1):PAGE88_I178@PURE_QUANTA.SCONN288_ADR50017P130CC(CHIPS)':
 'DQS9_B_C||TDQS9_B_C': CDS_PINID='\dqs9_b_c||tdqs9_b_c\';
NODE_NAME     J8 94
 '@S9S_MB_2U_LIB.S9S_MB_2U(SCH_1):PAGE89_I178@PURE_QUANTA.SCONN288_ADR50017P087CC(CHIPS)':
 'DQS9_B_C||TDQS9_B_C': CDS_PINID='\dqs9_b_c||tdqs9_b_c\';
NET_NAME
'M_D_CPU0_SB_DQS_DP<0>'
 '@S9S_MB_2U_LIB.S9S_MB_2U(SCH_1):M_D_CPU0_SB_DQS_DP'<0>:
 C_SIGNAL='@s9s_mb_2u_lib.s9s_mb_2u(sch_1):m_d_cpu0_sb_dqs_dp(0)';
NODE_NAME     U2 AL33
 '@S9S_MB_2U_LIB.S9S_MB_2U(SCH_1):PAGE23_I169@PURE_QUANTA.SOCKET4677_AZIF0045P001C01CS(CHIPS)':
 'DDR3_SB_DQS_DP0': CDS_PINID='DDR3_SB_DQS_DP0';
NODE_NAME     J7 104
 '@S9S_MB_2U_LIB.S9S_MB_2U(SCH_1):PAGE88_I178@PURE_QUANTA.SCONN288_ADR50017P130CC(CHIPS)':
 'DQS0_B_T': CDS_PINID='DQS0_B_T';
NODE_NAME     J8 104
 '@S9S_MB_2U_LIB.S9S_MB_2U(SCH_1):PAGE89_I178@PURE_QUANTA.SCONN288_ADR50017P087CC(CHIPS)':
 'DQS0_B_T': CDS_PINID='DQS0_B_T';
NET_NAME
'M_D_CPU0_SB_DQS_DP<1>'
 '@S9S_MB_2U_LIB.S9S_MB_2U(SCH_1):M_D_CPU0_SB_DQS_DP'<1>:
 C_SIGNAL='@s9s_mb_2u_lib.s9s_mb_2u(sch_1):m_d_cpu0_sb_dqs_dp(1)';
NODE_NAME     U2 AL27
 '@S9S_MB_2U_LIB.S9S_MB_2U(SCH_1):PAGE23_I169@PURE_QUANTA.SOCKET4677_AZIF0045P001C01CS(CHIPS)':
 'DDR3_SB_DQS_DP1': CDS_PINID='DDR3_SB_DQS_DP1';
NODE_NAME     J7 115
 '@S9S_MB_2U_LIB.S9S_MB_2U(SCH_1):PAGE88_I178@PURE_QUANTA.SCONN288_ADR50017P130CC(CHIPS)':
 'DQS1_B_T': CDS_PINID='DQS1_B_T';
NODE_NAME     J8 115
 '@S9S_MB_2U_LIB.S9S_MB_2U(SCH_1):PAGE89_I178@PURE_QUANTA.SCONN288_ADR50017P087CC(CHIPS)':
 'DQS1_B_T': CDS_PINID='DQS1_B_T';
NET_NAME
'M_D_CPU0_SB_DQS_DP<2>'
 '@S9S_MB_2U_LIB.S9S_MB_2U(SCH_1):M_D_CPU0_SB_DQS_DP'<2>:
 C_SIGNAL='@s9s_mb_2u_lib.s9s_mb_2u(sch_1):m_d_cpu0_sb_dqs_dp(2)';
NODE_NAME     U2 AD24
 '@S9S_MB_2U_LIB.S9S_MB_2U(SCH_1):PAGE23_I169@PURE_QUANTA.SOCKET4677_AZIF0045P001C01CS(CHIPS)':
 'DDR3_SB_DQS_DP2': CDS_PINID='DDR3_SB_DQS_DP2';
NODE_NAME     J7 126
 '@S9S_MB_2U_LIB.S9S_MB_2U(SCH_1):PAGE88_I178@PURE_QUANTA.SCONN288_ADR50017P130CC(CHIPS)':
 'DQS2_B_T': CDS_PINID='DQS2_B_T';
NODE_NAME     J8 126
 '@S9S_MB_2U_LIB.S9S_MB_2U(SCH_1):PAGE89_I178@PURE_QUANTA.SCONN288_ADR50017P087CC(CHIPS)':
 'DQS2_B_T': CDS_PINID='DQS2_B_T';
NET_NAME
'M_D_CPU0_SB_DQS_DP<3>'
 '@S9S_MB_2U_LIB.S9S_MB_2U(SCH_1):M_D_CPU0_SB_DQS_DP'<3>:
 C_SIGNAL='@s9s_mb_2u_lib.s9s_mb_2u(sch_1):m_d_cpu0_sb_dqs_dp(3)';
NODE_NAME     U2 AL21
 '@S9S_MB_2U_LIB.S9S_MB_2U(SCH_1):PAGE23_I169@PURE_QUANTA.SOCKET4677_AZIF0045P001C01CS(CHIPS)':
 'DDR3_SB_DQS_DP3': CDS_PINID='DDR3_SB_DQS_DP3';
NODE_NAME     J7 137
 '@S9S_MB_2U_LIB.S9S_MB_2U(SCH_1):PAGE88_I178@PURE_QUANTA.SCONN288_ADR50017P130CC(CHIPS)':
 'DQS3_B_T': CDS_PINID='DQS3_B_T';
NODE_NAME     J8 137
 '@S9S_MB_2U_LIB.S9S_MB_2U(SCH_1):PAGE89_I178@PURE_QUANTA.SCONN288_ADR50017P087CC(CHIPS)':
 'DQS3_B_T': CDS_PINID='DQS3_B_T';
NET_NAME
'M_D_CPU0_SB_DQS_DP<4>'
 '@S9S_MB_2U_LIB.S9S_MB_2U(SCH_1):M_D_CPU0_SB_DQS_DP'<4>:
 C_SIGNAL='@s9s_mb_2u_lib.s9s_mb_2u(sch_1):m_d_cpu0_sb_dqs_dp(4)';
NODE_NAME     U2 AN39
 '@S9S_MB_2U_LIB.S9S_MB_2U(SCH_1):PAGE23_I169@PURE_QUANTA.SOCKET4677_AZIF0045P001C01CS(CHIPS)':
 'DDR3_SB_DQS_DP4': CDS_PINID='DDR3_SB_DQS_DP4';
NODE_NAME     J7 239
 '@S9S_MB_2U_LIB.S9S_MB_2U(SCH_1):PAGE88_I178@PURE_QUANTA.SCONN288_ADR50017P130CC(CHIPS)':
 'DQS4_B_T': CDS_PINID='DQS4_B_T';
NODE_NAME     J8 239
 '@S9S_MB_2U_LIB.S9S_MB_2U(SCH_1):PAGE89_I178@PURE_QUANTA.SCONN288_ADR50017P087CC(CHIPS)':
 'DQS4_B_T': CDS_PINID='DQS4_B_T';
NET_NAME
'M_D_CPU0_SB_DQS_DP<5>'
 '@S9S_MB_2U_LIB.S9S_MB_2U(SCH_1):M_D_CPU0_SB_DQS_DP'<5>:
 C_SIGNAL='@s9s_mb_2u_lib.s9s_mb_2u(sch_1):m_d_cpu0_sb_dqs_dp(5)';
NODE_NAME     U2 AR33
 '@S9S_MB_2U_LIB.S9S_MB_2U(SCH_1):PAGE23_I169@PURE_QUANTA.SOCKET4677_AZIF0045P001C01CS(CHIPS)':
 'DDR3_SB_DQS_DP5': CDS_PINID='DDR3_SB_DQS_DP5';
NODE_NAME     J7 250
 '@S9S_MB_2U_LIB.S9S_MB_2U(SCH_1):PAGE88_I178@PURE_QUANTA.SCONN288_ADR50017P130CC(CHIPS)':
 'DQS5_B_T||TDQS5_B_T': CDS_PINID='\dqs5_b_t||tdqs5_b_t\';
NODE_NAME     J8 250
 '@S9S_MB_2U_LIB.S9S_MB_2U(SCH_1):PAGE89_I178@PURE_QUANTA.SCONN288_ADR50017P087CC(CHIPS)':
 'DQS5_B_T||TDQS5_B_T': CDS_PINID='\dqs5_b_t||tdqs5_b_t\';
NET_NAME
'M_D_CPU0_SB_DQS_DP<6>'
 '@S9S_MB_2U_LIB.S9S_MB_2U(SCH_1):M_D_CPU0_SB_DQS_DP'<6>:
 C_SIGNAL='@s9s_mb_2u_lib.s9s_mb_2u(sch_1):m_d_cpu0_sb_dqs_dp(6)';
NODE_NAME     U2 AR27
 '@S9S_MB_2U_LIB.S9S_MB_2U(SCH_1):PAGE23_I169@PURE_QUANTA.SOCKET4677_AZIF0045P001C01CS(CHIPS)':
 'DDR3_SB_DQS_DP6': CDS_PINID='DDR3_SB_DQS_DP6';
NODE_NAME     J7 261
 '@S9S_MB_2U_LIB.S9S_MB_2U(SCH_1):PAGE88_I178@PURE_QUANTA.SCONN288_ADR50017P130CC(CHIPS)':
 'DQS6_B_T||TDQS6_B_T': CDS_PINID='\dqs6_b_t||tdqs6_b_t\';
NODE_NAME     J8 261
 '@S9S_MB_2U_LIB.S9S_MB_2U(SCH_1):PAGE89_I178@PURE_QUANTA.SCONN288_ADR50017P087CC(CHIPS)':
 'DQS6_B_T||TDQS6_B_T': CDS_PINID='\dqs6_b_t||tdqs6_b_t\';
NET_NAME
'M_D_CPU0_SB_DQS_DP<7>'
 '@S9S_MB_2U_LIB.S9S_MB_2U(SCH_1):M_D_CPU0_SB_DQS_DP'<7>:
 C_SIGNAL='@s9s_mb_2u_lib.s9s_mb_2u(sch_1):m_d_cpu0_sb_dqs_dp(7)';
NODE_NAME     U2 AH24
 '@S9S_MB_2U_LIB.S9S_MB_2U(SCH_1):PAGE23_I169@PURE_QUANTA.SOCKET4677_AZIF0045P001C01CS(CHIPS)':
 'DDR3_SB_DQS_DP7': CDS_PINID='DDR3_SB_DQS_DP7';
NODE_NAME     J7 272
 '@S9S_MB_2U_LIB.S9S_MB_2U(SCH_1):PAGE88_I178@PURE_QUANTA.SCONN288_ADR50017P130CC(CHIPS)':
 'DQS7_B_T||TDQS7_B_T': CDS_PINID='\dqs7_b_t||tdqs7_b_t\';
NODE_NAME     J8 272
 '@S9S_MB_2U_LIB.S9S_MB_2U(SCH_1):PAGE89_I178@PURE_QUANTA.SCONN288_ADR50017P087CC(CHIPS)':
 'DQS7_B_T||TDQS7_B_T': CDS_PINID='\dqs7_b_t||tdqs7_b_t\';
NET_NAME
'M_D_CPU0_SB_DQS_DP<8>'
 '@S9S_MB_2U_LIB.S9S_MB_2U(SCH_1):M_D_CPU0_SB_DQS_DP'<8>:
 C_SIGNAL='@s9s_mb_2u_lib.s9s_mb_2u(sch_1):m_d_cpu0_sb_dqs_dp(8)';
NODE_NAME     U2 AR21
 '@S9S_MB_2U_LIB.S9S_MB_2U(SCH_1):PAGE23_I169@PURE_QUANTA.SOCKET4677_AZIF0045P001C01CS(CHIPS)':
 'DDR3_SB_DQS_DP8': CDS_PINID='DDR3_SB_DQS_DP8';
NODE_NAME     J7 283
 '@S9S_MB_2U_LIB.S9S_MB_2U(SCH_1):PAGE88_I178@PURE_QUANTA.SCONN288_ADR50017P130CC(CHIPS)':
 'DQS8_B_T||TDQS8_B_T': CDS_PINID='\dqs8_b_t||tdqs8_b_t\';
NODE_NAME     J8 283
 '@S9S_MB_2U_LIB.S9S_MB_2U(SCH_1):PAGE89_I178@PURE_QUANTA.SCONN288_ADR50017P087CC(CHIPS)':
 'DQS8_B_T||TDQS8_B_T': CDS_PINID='\dqs8_b_t||tdqs8_b_t\';
NET_NAME
'M_D_CPU0_SB_DQS_DP<9>'
 '@S9S_MB_2U_LIB.S9S_MB_2U(SCH_1):M_D_CPU0_SB_DQS_DP'<9>:
 C_SIGNAL='@s9s_mb_2u_lib.s9s_mb_2u(sch_1):m_d_cpu0_sb_dqs_dp(9)';
NODE_NAME     U2 AL39
 '@S9S_MB_2U_LIB.S9S_MB_2U(SCH_1):PAGE23_I169@PURE_QUANTA.SOCKET4677_AZIF0045P001C01CS(CHIPS)':
 'DDR3_SB_DQS_DP9': CDS_PINID='DDR3_SB_DQS_DP9';
NODE_NAME     J7 93
 '@S9S_MB_2U_LIB.S9S_MB_2U(SCH_1):PAGE88_I178@PURE_QUANTA.SCONN288_ADR50017P130CC(CHIPS)':
 'DQS9_B_T||TDQS9_B_T||DBI4_B_N': CDS_PINID='\dqs9_b_t||tdqs9_b_t||dbi4_b_n\';
NODE_NAME     J8 93
 '@S9S_MB_2U_LIB.S9S_MB_2U(SCH_1):PAGE89_I178@PURE_QUANTA.SCONN288_ADR50017P087CC(CHIPS)':
 'DQS9_B_T||TDQS9_B_T||DBI4_B_N': CDS_PINID='\dqs9_b_t||tdqs9_b_t||dbi4_b_n\';
NET_NAME
'M_D_CPU0_SB_PAR'
 '@S9S_MB_2U_LIB.S9S_MB_2U(SCH_1):M_D_CPU0_SB_PAR':
 C_SIGNAL='@s9s_mb_2u_lib.s9s_mb_2u(sch_1):m_d_cpu0_sb_par';
NODE_NAME     U2 AH42
 '@S9S_MB_2U_LIB.S9S_MB_2U(SCH_1):PAGE23_I169@PURE_QUANTA.SOCKET4677_AZIF0045P001C01CS(CHIPS)':
 'DDR3_SB_PAR': CDS_PINID='DDR3_SB_PAR';
NODE_NAME     J7 227
 '@S9S_MB_2U_LIB.S9S_MB_2U(SCH_1):PAGE88_I12@PURE_QUANTA.SCONN288_ADR50017P130CC(CHIPS)':
 'PAR_B': CDS_PINID='PAR_B';
NODE_NAME     J8 227
 '@S9S_MB_2U_LIB.S9S_MB_2U(SCH_1):PAGE89_I50@PURE_QUANTA.SCONN288_ADR50017P087CC(CHIPS)':
 'PAR_B': CDS_PINID='PAR_B';
NET_NAME
'M_D_CPU0_SB_RSP<0>'
 '@S9S_MB_2U_LIB.S9S_MB_2U(SCH_1):M_D_CPU0_SB_RSP'<0>:
 C_SIGNAL='@s9s_mb_2u_lib.s9s_mb_2u(sch_1):m_d_cpu0_sb_rsp(0)';
NODE_NAME     U2 AF51
 '@S9S_MB_2U_LIB.S9S_MB_2U(SCH_1):PAGE23_I169@PURE_QUANTA.SOCKET4677_AZIF0045P001C01CS(CHIPS)':
 'DDR3_B_RSP0': CDS_PINID='DDR3_B_RSP0';
NODE_NAME     J7 87
 '@S9S_MB_2U_LIB.S9S_MB_2U(SCH_1):PAGE88_I12@PURE_QUANTA.SCONN288_ADR50017P130CC(CHIPS)':
 'LBS||RSP_B_N': CDS_PINID='\lbs||rsp_b_n\';
NET_NAME
'M_D_CPU0_SB_RSP<1>'
 '@S9S_MB_2U_LIB.S9S_MB_2U(SCH_1):M_D_CPU0_SB_RSP'<1>:
 C_SIGNAL='@s9s_mb_2u_lib.s9s_mb_2u(sch_1):m_d_cpu0_sb_rsp(1)';
NODE_NAME     U2 AG50
 '@S9S_MB_2U_LIB.S9S_MB_2U(SCH_1):PAGE23_I169@PURE_QUANTA.SOCKET4677_AZIF0045P001C01CS(CHIPS)':
 'DDR3_B_RSP1': CDS_PINID='DDR3_B_RSP1';
NODE_NAME     J8 87
 '@S9S_MB_2U_LIB.S9S_MB_2U(SCH_1):PAGE89_I50@PURE_QUANTA.SCONN288_ADR50017P087CC(CHIPS)':
 'LBS||RSP_B_N': CDS_PINID='\lbs||rsp_b_n\';
NET_NAME
'M_D_CPU1_ALERT_N'
 '@S9S_MB_2U_LIB.S9S_MB_2U(SCH_1):M_D_CPU1_ALERT_N':
 C_SIGNAL='@s9s_mb_2u_lib.s9s_mb_2u(sch_1):m_d_cpu1_alert_n';
NODE_NAME     U1 AV47
 '@S9S_MB_2U_LIB.S9S_MB_2U(SCH_1):PAGE54_I91@PURE_QUANTA.SOCKET4677_AZIF0045P001C01CS(CHIPS)':
 'DDR3_ALERT_N': CDS_PINID='DDR3_ALERT_N';
NODE_NAME     J23 62
 '@S9S_MB_2U_LIB.S9S_MB_2U(SCH_1):PAGE104_I25@PURE_QUANTA.SCONN288_ADR50017P130CC(CHIPS)':
 'ALERT_N': CDS_PINID='ALERT_N';
NODE_NAME     J24 62
 '@S9S_MB_2U_LIB.S9S_MB_2U(SCH_1):PAGE105_I178@PURE_QUANTA.SCONN288_ADR50017P087CC(CHIPS)':
 'ALERT_N': CDS_PINID='ALERT_N';
NET_NAME
'M_D_CPU1_CLK_DN<0>'
 '@S9S_MB_2U_LIB.S9S_MB_2U(SCH_1):M_D_CPU1_CLK_DN'<0>:
 C_SIGNAL='@s9s_mb_2u_lib.s9s_mb_2u(sch_1):m_d_cpu1_clk_dn(0)';
NODE_NAME     U1 AJ45
 '@S9S_MB_2U_LIB.S9S_MB_2U(SCH_1):PAGE54_I91@PURE_QUANTA.SOCKET4677_AZIF0045P001C01CS(CHIPS)':
 'DDR3_CLK_DN0': CDS_PINID='DDR3_CLK_DN0';
NODE_NAME     J23 218
 '@S9S_MB_2U_LIB.S9S_MB_2U(SCH_1):PAGE104_I25@PURE_QUANTA.SCONN288_ADR50017P130CC(CHIPS)':
 'CK_C': CDS_PINID='CK_C';
NET_NAME
'M_D_CPU1_CLK_DN<1>'
 '@S9S_MB_2U_LIB.S9S_MB_2U(SCH_1):M_D_CPU1_CLK_DN'<1>:
 C_SIGNAL='@s9s_mb_2u_lib.s9s_mb_2u(sch_1):m_d_cpu1_clk_dn(1)';
NODE_NAME     U1 AN45
 '@S9S_MB_2U_LIB.S9S_MB_2U(SCH_1):PAGE54_I91@PURE_QUANTA.SOCKET4677_AZIF0045P001C01CS(CHIPS)':
 'DDR3_CLK_DN1': CDS_PINID='DDR3_CLK_DN1';
NODE_NAME     J24 218
 '@S9S_MB_2U_LIB.S9S_MB_2U(SCH_1):PAGE105_I178@PURE_QUANTA.SCONN288_ADR50017P087CC(CHIPS)':
 'CK_C': CDS_PINID='CK_C';
NET_NAME
'M_D_CPU1_CLK_DP<0>'
 '@S9S_MB_2U_LIB.S9S_MB_2U(SCH_1):M_D_CPU1_CLK_DP'<0>:
 C_SIGNAL='@s9s_mb_2u_lib.s9s_mb_2u(sch_1):m_d_cpu1_clk_dp(0)';
NODE_NAME     U1 AL45
 '@S9S_MB_2U_LIB.S9S_MB_2U(SCH_1):PAGE54_I91@PURE_QUANTA.SOCKET4677_AZIF0045P001C01CS(CHIPS)':
 'DDR3_CLK_DP0': CDS_PINID='DDR3_CLK_DP0';
NODE_NAME     J23 217
 '@S9S_MB_2U_LIB.S9S_MB_2U(SCH_1):PAGE104_I25@PURE_QUANTA.SCONN288_ADR50017P130CC(CHIPS)':
 'CK_T': CDS_PINID='CK_T';
NET_NAME
'M_D_CPU1_CLK_DP<1>'
 '@S9S_MB_2U_LIB.S9S_MB_2U(SCH_1):M_D_CPU1_CLK_DP'<1>:
 C_SIGNAL='@s9s_mb_2u_lib.s9s_mb_2u(sch_1):m_d_cpu1_clk_dp(1)';
NODE_NAME     U1 AR45
 '@S9S_MB_2U_LIB.S9S_MB_2U(SCH_1):PAGE54_I91@PURE_QUANTA.SOCKET4677_AZIF0045P001C01CS(CHIPS)':
 'DDR3_CLK_DP1': CDS_PINID='DDR3_CLK_DP1';
NODE_NAME     J24 217
 '@S9S_MB_2U_LIB.S9S_MB_2U(SCH_1):PAGE105_I178@PURE_QUANTA.SCONN288_ADR50017P087CC(CHIPS)':
 'CK_T': CDS_PINID='CK_T';
NET_NAME
'M_D_CPU1_SA_CA<0>'
 '@S9S_MB_2U_LIB.S9S_MB_2U(SCH_1):M_D_CPU1_SA_CA'<0>:
 C_SIGNAL='@s9s_mb_2u_lib.s9s_mb_2u(sch_1):m_d_cpu1_sa_ca(0)';
NODE_NAME     U1 AJ52
 '@S9S_MB_2U_LIB.S9S_MB_2U(SCH_1):PAGE54_I91@PURE_QUANTA.SOCKET4677_AZIF0045P001C01CS(CHIPS)':
 'DDR3_SA_CA0': CDS_PINID='DDR3_SA_CA0';
NODE_NAME     J23 66
 '@S9S_MB_2U_LIB.S9S_MB_2U(SCH_1):PAGE104_I25@PURE_QUANTA.SCONN288_ADR50017P130CC(CHIPS)':
 'CA0_A': CDS_PINID='CA0_A';
NODE_NAME     J24 66
 '@S9S_MB_2U_LIB.S9S_MB_2U(SCH_1):PAGE105_I178@PURE_QUANTA.SCONN288_ADR50017P087CC(CHIPS)':
 'CA0_A': CDS_PINID='CA0_A';
NET_NAME
'M_D_CPU1_SA_CA<1>'
 '@S9S_MB_2U_LIB.S9S_MB_2U(SCH_1):M_D_CPU1_SA_CA'<1>:
 C_SIGNAL='@s9s_mb_2u_lib.s9s_mb_2u(sch_1):m_d_cpu1_sa_ca(1)';
NODE_NAME     U1 AR52
 '@S9S_MB_2U_LIB.S9S_MB_2U(SCH_1):PAGE54_I91@PURE_QUANTA.SOCKET4677_AZIF0045P001C01CS(CHIPS)':
 'DDR3_SA_CA1': CDS_PINID='DDR3_SA_CA1';
NODE_NAME     J23 211
 '@S9S_MB_2U_LIB.S9S_MB_2U(SCH_1):PAGE104_I25@PURE_QUANTA.SCONN288_ADR50017P130CC(CHIPS)':
 'CA1_A': CDS_PINID='CA1_A';
NODE_NAME     J24 211
 '@S9S_MB_2U_LIB.S9S_MB_2U(SCH_1):PAGE105_I178@PURE_QUANTA.SCONN288_ADR50017P087CC(CHIPS)':
 'CA1_A': CDS_PINID='CA1_A';
NET_NAME
'M_D_CPU1_SA_CA<2>'
 '@S9S_MB_2U_LIB.S9S_MB_2U(SCH_1):M_D_CPU1_SA_CA'<2>:
 C_SIGNAL='@s9s_mb_2u_lib.s9s_mb_2u(sch_1):m_d_cpu1_sa_ca(2)';
NODE_NAME     U1 AK51
 '@S9S_MB_2U_LIB.S9S_MB_2U(SCH_1):PAGE54_I91@PURE_QUANTA.SOCKET4677_AZIF0045P001C01CS(CHIPS)':
 'DDR3_SA_CA2': CDS_PINID='DDR3_SA_CA2';
NODE_NAME     J23 68
 '@S9S_MB_2U_LIB.S9S_MB_2U(SCH_1):PAGE104_I25@PURE_QUANTA.SCONN288_ADR50017P130CC(CHIPS)':
 'CA2_A': CDS_PINID='CA2_A';
NODE_NAME     J24 68
 '@S9S_MB_2U_LIB.S9S_MB_2U(SCH_1):PAGE105_I178@PURE_QUANTA.SCONN288_ADR50017P087CC(CHIPS)':
 'CA2_A': CDS_PINID='CA2_A';
NET_NAME
'M_D_CPU1_SA_CA<3>'
 '@S9S_MB_2U_LIB.S9S_MB_2U(SCH_1):M_D_CPU1_SA_CA'<3>:
 C_SIGNAL='@s9s_mb_2u_lib.s9s_mb_2u(sch_1):m_d_cpu1_sa_ca(3)';
NODE_NAME     U1 AP51
 '@S9S_MB_2U_LIB.S9S_MB_2U(SCH_1):PAGE54_I91@PURE_QUANTA.SOCKET4677_AZIF0045P001C01CS(CHIPS)':
 'DDR3_SA_CA3': CDS_PINID='DDR3_SA_CA3';
NODE_NAME     J23 213
 '@S9S_MB_2U_LIB.S9S_MB_2U(SCH_1):PAGE104_I25@PURE_QUANTA.SCONN288_ADR50017P130CC(CHIPS)':
 'CA3_A': CDS_PINID='CA3_A';
NODE_NAME     J24 213
 '@S9S_MB_2U_LIB.S9S_MB_2U(SCH_1):PAGE105_I178@PURE_QUANTA.SCONN288_ADR50017P087CC(CHIPS)':
 'CA3_A': CDS_PINID='CA3_A';
NET_NAME
'M_D_CPU1_SA_CA<4>'
 '@S9S_MB_2U_LIB.S9S_MB_2U(SCH_1):M_D_CPU1_SA_CA'<4>:
 C_SIGNAL='@s9s_mb_2u_lib.s9s_mb_2u(sch_1):m_d_cpu1_sa_ca(4)';
NODE_NAME     U1 AL50
 '@S9S_MB_2U_LIB.S9S_MB_2U(SCH_1):PAGE54_I91@PURE_QUANTA.SOCKET4677_AZIF0045P001C01CS(CHIPS)':
 'DDR3_SA_CA4': CDS_PINID='DDR3_SA_CA4';
NODE_NAME     J23 70
 '@S9S_MB_2U_LIB.S9S_MB_2U(SCH_1):PAGE104_I25@PURE_QUANTA.SCONN288_ADR50017P130CC(CHIPS)':
 'CA4_A': CDS_PINID='CA4_A';
NODE_NAME     J24 70
 '@S9S_MB_2U_LIB.S9S_MB_2U(SCH_1):PAGE105_I178@PURE_QUANTA.SCONN288_ADR50017P087CC(CHIPS)':
 'CA4_A': CDS_PINID='CA4_A';
NET_NAME
'M_D_CPU1_SA_CA<5>'
 '@S9S_MB_2U_LIB.S9S_MB_2U(SCH_1):M_D_CPU1_SA_CA'<5>:
 C_SIGNAL='@s9s_mb_2u_lib.s9s_mb_2u(sch_1):m_d_cpu1_sa_ca(5)';
NODE_NAME     U1 AN50
 '@S9S_MB_2U_LIB.S9S_MB_2U(SCH_1):PAGE54_I91@PURE_QUANTA.SOCKET4677_AZIF0045P001C01CS(CHIPS)':
 'DDR3_SA_CA5': CDS_PINID='DDR3_SA_CA5';
NODE_NAME     J23 215
 '@S9S_MB_2U_LIB.S9S_MB_2U(SCH_1):PAGE104_I25@PURE_QUANTA.SCONN288_ADR50017P130CC(CHIPS)':
 'CA5_A': CDS_PINID='CA5_A';
NODE_NAME     J24 215
 '@S9S_MB_2U_LIB.S9S_MB_2U(SCH_1):PAGE105_I178@PURE_QUANTA.SCONN288_ADR50017P087CC(CHIPS)':
 'CA5_A': CDS_PINID='CA5_A';
NET_NAME
'M_D_CPU1_SA_CA<6>'
 '@S9S_MB_2U_LIB.S9S_MB_2U(SCH_1):M_D_CPU1_SA_CA'<6>:
 C_SIGNAL='@s9s_mb_2u_lib.s9s_mb_2u(sch_1):m_d_cpu1_sa_ca(6)';
NODE_NAME     U1 AN43
 '@S9S_MB_2U_LIB.S9S_MB_2U(SCH_1):PAGE54_I91@PURE_QUANTA.SOCKET4677_AZIF0045P001C01CS(CHIPS)':
 'DDR3_SA_CA6': CDS_PINID='DDR3_SA_CA6';
NODE_NAME     J23 72
 '@S9S_MB_2U_LIB.S9S_MB_2U(SCH_1):PAGE104_I25@PURE_QUANTA.SCONN288_ADR50017P130CC(CHIPS)':
 'CA6_A': CDS_PINID='CA6_A';
NODE_NAME     J24 72
 '@S9S_MB_2U_LIB.S9S_MB_2U(SCH_1):PAGE105_I178@PURE_QUANTA.SCONN288_ADR50017P087CC(CHIPS)':
 'CA6_A': CDS_PINID='CA6_A';
NET_NAME
'M_D_CPU1_SA_CB<0>'
 '@S9S_MB_2U_LIB.S9S_MB_2U(SCH_1):M_D_CPU1_SA_CB'<0>:
 C_SIGNAL='@s9s_mb_2u_lib.s9s_mb_2u(sch_1):m_d_cpu1_sa_cb(0)';
NODE_NAME     U1 AL60
 '@S9S_MB_2U_LIB.S9S_MB_2U(SCH_1):PAGE54_I91@PURE_QUANTA.SOCKET4677_AZIF0045P001C01CS(CHIPS)':
 'DDR3_SA_ECC0': CDS_PINID='DDR3_SA_ECC0';
NODE_NAME     J23 51
 '@S9S_MB_2U_LIB.S9S_MB_2U(SCH_1):PAGE104_I25@PURE_QUANTA.SCONN288_ADR50017P130CC(CHIPS)':
 'CB0_A': CDS_PINID='CB0_A';
NODE_NAME     J24 51
 '@S9S_MB_2U_LIB.S9S_MB_2U(SCH_1):PAGE105_I178@PURE_QUANTA.SCONN288_ADR50017P087CC(CHIPS)':
 'CB0_A': CDS_PINID='CB0_A';
NET_NAME
'M_D_CPU1_SA_CB<1>'
 '@S9S_MB_2U_LIB.S9S_MB_2U(SCH_1):M_D_CPU1_SA_CB'<1>:
 C_SIGNAL='@s9s_mb_2u_lib.s9s_mb_2u(sch_1):m_d_cpu1_sa_cb(1)';
NODE_NAME     U1 AK59
 '@S9S_MB_2U_LIB.S9S_MB_2U(SCH_1):PAGE54_I91@PURE_QUANTA.SOCKET4677_AZIF0045P001C01CS(CHIPS)':
 'DDR3_SA_ECC1': CDS_PINID='DDR3_SA_ECC1';
NODE_NAME     J23 53
 '@S9S_MB_2U_LIB.S9S_MB_2U(SCH_1):PAGE104_I25@PURE_QUANTA.SCONN288_ADR50017P130CC(CHIPS)':
 'CB1_A': CDS_PINID='CB1_A';
NODE_NAME     J24 53
 '@S9S_MB_2U_LIB.S9S_MB_2U(SCH_1):PAGE105_I178@PURE_QUANTA.SCONN288_ADR50017P087CC(CHIPS)':
 'CB1_A': CDS_PINID='CB1_A';
NET_NAME
'M_D_CPU1_SA_CB<2>'
 '@S9S_MB_2U_LIB.S9S_MB_2U(SCH_1):M_D_CPU1_SA_CB'<2>:
 C_SIGNAL='@s9s_mb_2u_lib.s9s_mb_2u(sch_1):m_d_cpu1_sa_cb(2)';
NODE_NAME     U1 AN60
 '@S9S_MB_2U_LIB.S9S_MB_2U(SCH_1):PAGE54_I91@PURE_QUANTA.SOCKET4677_AZIF0045P001C01CS(CHIPS)':
 'DDR3_SA_ECC2': CDS_PINID='DDR3_SA_ECC2';
NODE_NAME     J23 196
 '@S9S_MB_2U_LIB.S9S_MB_2U(SCH_1):PAGE104_I25@PURE_QUANTA.SCONN288_ADR50017P130CC(CHIPS)':
 'CB2_A': CDS_PINID='CB2_A';
NODE_NAME     J24 196
 '@S9S_MB_2U_LIB.S9S_MB_2U(SCH_1):PAGE105_I178@PURE_QUANTA.SCONN288_ADR50017P087CC(CHIPS)':
 'CB2_A': CDS_PINID='CB2_A';
NET_NAME
'M_D_CPU1_SA_CB<3>'
 '@S9S_MB_2U_LIB.S9S_MB_2U(SCH_1):M_D_CPU1_SA_CB'<3>:
 C_SIGNAL='@s9s_mb_2u_lib.s9s_mb_2u(sch_1):m_d_cpu1_sa_cb(3)';
NODE_NAME     U1 AP59
 '@S9S_MB_2U_LIB.S9S_MB_2U(SCH_1):PAGE54_I91@PURE_QUANTA.SOCKET4677_AZIF0045P001C01CS(CHIPS)':
 'DDR3_SA_ECC3': CDS_PINID='DDR3_SA_ECC3';
NODE_NAME     J23 198
 '@S9S_MB_2U_LIB.S9S_MB_2U(SCH_1):PAGE104_I25@PURE_QUANTA.SCONN288_ADR50017P130CC(CHIPS)':
 'CB3_A': CDS_PINID='CB3_A';
NODE_NAME     J24 198
 '@S9S_MB_2U_LIB.S9S_MB_2U(SCH_1):PAGE105_I178@PURE_QUANTA.SCONN288_ADR50017P087CC(CHIPS)':
 'CB3_A': CDS_PINID='CB3_A';
NET_NAME
'M_D_CPU1_SA_CB<4>'
 '@S9S_MB_2U_LIB.S9S_MB_2U(SCH_1):M_D_CPU1_SA_CB'<4>:
 C_SIGNAL='@s9s_mb_2u_lib.s9s_mb_2u(sch_1):m_d_cpu1_sa_cb(4)';
NODE_NAME     U1 AK57
 '@S9S_MB_2U_LIB.S9S_MB_2U(SCH_1):PAGE54_I91@PURE_QUANTA.SOCKET4677_AZIF0045P001C01CS(CHIPS)':
 'DDR3_SA_ECC4': CDS_PINID='DDR3_SA_ECC4';
NODE_NAME     J23 58
 '@S9S_MB_2U_LIB.S9S_MB_2U(SCH_1):PAGE104_I25@PURE_QUANTA.SCONN288_ADR50017P130CC(CHIPS)':
 'CB4_A': CDS_PINID='CB4_A';
NODE_NAME     J24 58
 '@S9S_MB_2U_LIB.S9S_MB_2U(SCH_1):PAGE105_I178@PURE_QUANTA.SCONN288_ADR50017P087CC(CHIPS)':
 'CB4_A': CDS_PINID='CB4_A';
NET_NAME
'M_D_CPU1_SA_CB<5>'
 '@S9S_MB_2U_LIB.S9S_MB_2U(SCH_1):M_D_CPU1_SA_CB'<5>:
 C_SIGNAL='@s9s_mb_2u_lib.s9s_mb_2u(sch_1):m_d_cpu1_sa_cb(5)';
NODE_NAME     U1 AL56
 '@S9S_MB_2U_LIB.S9S_MB_2U(SCH_1):PAGE54_I91@PURE_QUANTA.SOCKET4677_AZIF0045P001C01CS(CHIPS)':
 'DDR3_SA_ECC5': CDS_PINID='DDR3_SA_ECC5';
NODE_NAME     J23 60
 '@S9S_MB_2U_LIB.S9S_MB_2U(SCH_1):PAGE104_I25@PURE_QUANTA.SCONN288_ADR50017P130CC(CHIPS)':
 'CB5_A': CDS_PINID='CB5_A';
NODE_NAME     J24 60
 '@S9S_MB_2U_LIB.S9S_MB_2U(SCH_1):PAGE105_I178@PURE_QUANTA.SCONN288_ADR50017P087CC(CHIPS)':
 'CB5_A': CDS_PINID='CB5_A';
NET_NAME
'M_D_CPU1_SA_CB<6>'
 '@S9S_MB_2U_LIB.S9S_MB_2U(SCH_1):M_D_CPU1_SA_CB'<6>:
 C_SIGNAL='@s9s_mb_2u_lib.s9s_mb_2u(sch_1):m_d_cpu1_sa_cb(6)';
NODE_NAME     U1 AP57
 '@S9S_MB_2U_LIB.S9S_MB_2U(SCH_1):PAGE54_I91@PURE_QUANTA.SOCKET4677_AZIF0045P001C01CS(CHIPS)':
 'DDR3_SA_ECC6': CDS_PINID='DDR3_SA_ECC6';
NODE_NAME     J23 203
 '@S9S_MB_2U_LIB.S9S_MB_2U(SCH_1):PAGE104_I25@PURE_QUANTA.SCONN288_ADR50017P130CC(CHIPS)':
 'CB6_A': CDS_PINID='CB6_A';
NODE_NAME     J24 203
 '@S9S_MB_2U_LIB.S9S_MB_2U(SCH_1):PAGE105_I178@PURE_QUANTA.SCONN288_ADR50017P087CC(CHIPS)':
 'CB6_A': CDS_PINID='CB6_A';
NET_NAME
'M_D_CPU1_SA_CB<7>'
 '@S9S_MB_2U_LIB.S9S_MB_2U(SCH_1):M_D_CPU1_SA_CB'<7>:
 C_SIGNAL='@s9s_mb_2u_lib.s9s_mb_2u(sch_1):m_d_cpu1_sa_cb(7)';
NODE_NAME     U1 AN56
 '@S9S_MB_2U_LIB.S9S_MB_2U(SCH_1):PAGE54_I91@PURE_QUANTA.SOCKET4677_AZIF0045P001C01CS(CHIPS)':
 'DDR3_SA_ECC7': CDS_PINID='DDR3_SA_ECC7';
NODE_NAME     J23 205
 '@S9S_MB_2U_LIB.S9S_MB_2U(SCH_1):PAGE104_I25@PURE_QUANTA.SCONN288_ADR50017P130CC(CHIPS)':
 'CB7_A': CDS_PINID='CB7_A';
NODE_NAME     J24 205
 '@S9S_MB_2U_LIB.S9S_MB_2U(SCH_1):PAGE105_I178@PURE_QUANTA.SCONN288_ADR50017P087CC(CHIPS)':
 'CB7_A': CDS_PINID='CB7_A';
NET_NAME
'M_D_CPU1_SA_CS_N<0>'
 '@S9S_MB_2U_LIB.S9S_MB_2U(SCH_1):M_D_CPU1_SA_CS_N'<0>:
 C_SIGNAL='@s9s_mb_2u_lib.s9s_mb_2u(sch_1):m_d_cpu1_sa_cs_n(0)';
NODE_NAME     U1 AL54
 '@S9S_MB_2U_LIB.S9S_MB_2U(SCH_1):PAGE54_I91@PURE_QUANTA.SOCKET4677_AZIF0045P001C01CS(CHIPS)':
 'DDR3_SA_CS_N0': CDS_PINID='DDR3_SA_CS_N0';
NODE_NAME     J23 64
 '@S9S_MB_2U_LIB.S9S_MB_2U(SCH_1):PAGE104_I25@PURE_QUANTA.SCONN288_ADR50017P130CC(CHIPS)':
 'CS0_A_N': CDS_PINID='CS0_A_N';
NET_NAME
'M_D_CPU1_SA_CS_N<1>'
 '@S9S_MB_2U_LIB.S9S_MB_2U(SCH_1):M_D_CPU1_SA_CS_N'<1>:
 C_SIGNAL='@s9s_mb_2u_lib.s9s_mb_2u(sch_1):m_d_cpu1_sa_cs_n(1)';
NODE_NAME     U1 AK53
 '@S9S_MB_2U_LIB.S9S_MB_2U(SCH_1):PAGE54_I91@PURE_QUANTA.SOCKET4677_AZIF0045P001C01CS(CHIPS)':
 'DDR3_SA_CS_N1': CDS_PINID='DDR3_SA_CS_N1';
NODE_NAME     J23 209
 '@S9S_MB_2U_LIB.S9S_MB_2U(SCH_1):PAGE104_I25@PURE_QUANTA.SCONN288_ADR50017P130CC(CHIPS)':
 'CS1_A_N': CDS_PINID='CS1_A_N';
NET_NAME
'M_D_CPU1_SA_CS_N<2>'
 '@S9S_MB_2U_LIB.S9S_MB_2U(SCH_1):M_D_CPU1_SA_CS_N'<2>:
 C_SIGNAL='@s9s_mb_2u_lib.s9s_mb_2u(sch_1):m_d_cpu1_sa_cs_n(2)';
NODE_NAME     U1 AN54
 '@S9S_MB_2U_LIB.S9S_MB_2U(SCH_1):PAGE54_I91@PURE_QUANTA.SOCKET4677_AZIF0045P001C01CS(CHIPS)':
 'DDR3_SA_CS_N2': CDS_PINID='DDR3_SA_CS_N2';
NODE_NAME     J24 64
 '@S9S_MB_2U_LIB.S9S_MB_2U(SCH_1):PAGE105_I178@PURE_QUANTA.SCONN288_ADR50017P087CC(CHIPS)':
 'CS0_A_N': CDS_PINID='CS0_A_N';
NET_NAME
'M_D_CPU1_SA_CS_N<3>'
 '@S9S_MB_2U_LIB.S9S_MB_2U(SCH_1):M_D_CPU1_SA_CS_N'<3>:
 C_SIGNAL='@s9s_mb_2u_lib.s9s_mb_2u(sch_1):m_d_cpu1_sa_cs_n(3)';
NODE_NAME     U1 AP53
 '@S9S_MB_2U_LIB.S9S_MB_2U(SCH_1):PAGE54_I91@PURE_QUANTA.SOCKET4677_AZIF0045P001C01CS(CHIPS)':
 'DDR3_SA_CS_N3': CDS_PINID='DDR3_SA_CS_N3';
NODE_NAME     J24 209
 '@S9S_MB_2U_LIB.S9S_MB_2U(SCH_1):PAGE105_I178@PURE_QUANTA.SCONN288_ADR50017P087CC(CHIPS)':
 'CS1_A_N': CDS_PINID='CS1_A_N';
NET_NAME
'M_D_CPU1_SA_DQ<0>'
 '@S9S_MB_2U_LIB.S9S_MB_2U(SCH_1):M_D_CPU1_SA_DQ'<0>:
 C_SIGNAL='@s9s_mb_2u_lib.s9s_mb_2u(sch_1):m_d_cpu1_sa_dq(0)';
NODE_NAME     U1 AD75
 '@S9S_MB_2U_LIB.S9S_MB_2U(SCH_1):PAGE54_I91@PURE_QUANTA.SOCKET4677_AZIF0045P001C01CS(CHIPS)':
 'DDR3_SA_DQ0': CDS_PINID='DDR3_SA_DQ0';
NODE_NAME     J23 7
 '@S9S_MB_2U_LIB.S9S_MB_2U(SCH_1):PAGE104_I25@PURE_QUANTA.SCONN288_ADR50017P130CC(CHIPS)':
 'DQ0_A': CDS_PINID='DQ0_A';
NODE_NAME     J24 7
 '@S9S_MB_2U_LIB.S9S_MB_2U(SCH_1):PAGE105_I178@PURE_QUANTA.SCONN288_ADR50017P087CC(CHIPS)':
 'DQ0_A': CDS_PINID='DQ0_A';
NET_NAME
'M_D_CPU1_SA_DQ<10>'
 '@S9S_MB_2U_LIB.S9S_MB_2U(SCH_1):M_D_CPU1_SA_DQ'<10>:
 C_SIGNAL='@s9s_mb_2u_lib.s9s_mb_2u(sch_1):m_d_cpu1_sa_dq(10)';
NODE_NAME     U1 AN78
 '@S9S_MB_2U_LIB.S9S_MB_2U(SCH_1):PAGE54_I91@PURE_QUANTA.SOCKET4677_AZIF0045P001C01CS(CHIPS)':
 'DDR3_SA_DQ10': CDS_PINID='DDR3_SA_DQ10';
NODE_NAME     J23 163
 '@S9S_MB_2U_LIB.S9S_MB_2U(SCH_1):PAGE104_I25@PURE_QUANTA.SCONN288_ADR50017P130CC(CHIPS)':
 'DQ10_A': CDS_PINID='DQ10_A';
NODE_NAME     J24 163
 '@S9S_MB_2U_LIB.S9S_MB_2U(SCH_1):PAGE105_I178@PURE_QUANTA.SCONN288_ADR50017P087CC(CHIPS)':
 'DQ10_A': CDS_PINID='DQ10_A';
NET_NAME
'M_D_CPU1_SA_DQ<11>'
 '@S9S_MB_2U_LIB.S9S_MB_2U(SCH_1):M_D_CPU1_SA_DQ'<11>:
 C_SIGNAL='@s9s_mb_2u_lib.s9s_mb_2u(sch_1):m_d_cpu1_sa_dq(11)';
NODE_NAME     U1 AP77
 '@S9S_MB_2U_LIB.S9S_MB_2U(SCH_1):PAGE54_I91@PURE_QUANTA.SOCKET4677_AZIF0045P001C01CS(CHIPS)':
 'DDR3_SA_DQ11': CDS_PINID='DDR3_SA_DQ11';
NODE_NAME     J23 165
 '@S9S_MB_2U_LIB.S9S_MB_2U(SCH_1):PAGE104_I25@PURE_QUANTA.SCONN288_ADR50017P130CC(CHIPS)':
 'DQ11_A': CDS_PINID='DQ11_A';
NODE_NAME     J24 165
 '@S9S_MB_2U_LIB.S9S_MB_2U(SCH_1):PAGE105_I178@PURE_QUANTA.SCONN288_ADR50017P087CC(CHIPS)':
 'DQ11_A': CDS_PINID='DQ11_A';
NET_NAME
'M_D_CPU1_SA_DQ<12>'
 '@S9S_MB_2U_LIB.S9S_MB_2U(SCH_1):M_D_CPU1_SA_DQ'<12>:
 C_SIGNAL='@s9s_mb_2u_lib.s9s_mb_2u(sch_1):m_d_cpu1_sa_dq(12)';
NODE_NAME     U1 AK75
 '@S9S_MB_2U_LIB.S9S_MB_2U(SCH_1):PAGE54_I91@PURE_QUANTA.SOCKET4677_AZIF0045P001C01CS(CHIPS)':
 'DDR3_SA_DQ12': CDS_PINID='DDR3_SA_DQ12';
NODE_NAME     J23 25
 '@S9S_MB_2U_LIB.S9S_MB_2U(SCH_1):PAGE104_I25@PURE_QUANTA.SCONN288_ADR50017P130CC(CHIPS)':
 'DQ12_A': CDS_PINID='DQ12_A';
NODE_NAME     J24 25
 '@S9S_MB_2U_LIB.S9S_MB_2U(SCH_1):PAGE105_I178@PURE_QUANTA.SCONN288_ADR50017P087CC(CHIPS)':
 'DQ12_A': CDS_PINID='DQ12_A';
NET_NAME
'M_D_CPU1_SA_DQ<13>'
 '@S9S_MB_2U_LIB.S9S_MB_2U(SCH_1):M_D_CPU1_SA_DQ'<13>:
 C_SIGNAL='@s9s_mb_2u_lib.s9s_mb_2u(sch_1):m_d_cpu1_sa_dq(13)';
NODE_NAME     U1 AL74
 '@S9S_MB_2U_LIB.S9S_MB_2U(SCH_1):PAGE54_I91@PURE_QUANTA.SOCKET4677_AZIF0045P001C01CS(CHIPS)':
 'DDR3_SA_DQ13': CDS_PINID='DDR3_SA_DQ13';
NODE_NAME     J23 27
 '@S9S_MB_2U_LIB.S9S_MB_2U(SCH_1):PAGE104_I25@PURE_QUANTA.SCONN288_ADR50017P130CC(CHIPS)':
 'DQ13_A': CDS_PINID='DQ13_A';
NODE_NAME     J24 27
 '@S9S_MB_2U_LIB.S9S_MB_2U(SCH_1):PAGE105_I178@PURE_QUANTA.SCONN288_ADR50017P087CC(CHIPS)':
 'DQ13_A': CDS_PINID='DQ13_A';
NET_NAME
'M_D_CPU1_SA_DQ<14>'
 '@S9S_MB_2U_LIB.S9S_MB_2U(SCH_1):M_D_CPU1_SA_DQ'<14>:
 C_SIGNAL='@s9s_mb_2u_lib.s9s_mb_2u(sch_1):m_d_cpu1_sa_dq(14)';
NODE_NAME     U1 AP75
 '@S9S_MB_2U_LIB.S9S_MB_2U(SCH_1):PAGE54_I91@PURE_QUANTA.SOCKET4677_AZIF0045P001C01CS(CHIPS)':
 'DDR3_SA_DQ14': CDS_PINID='DDR3_SA_DQ14';
NODE_NAME     J23 170
 '@S9S_MB_2U_LIB.S9S_MB_2U(SCH_1):PAGE104_I25@PURE_QUANTA.SCONN288_ADR50017P130CC(CHIPS)':
 'DQ14_A': CDS_PINID='DQ14_A';
NODE_NAME     J24 170
 '@S9S_MB_2U_LIB.S9S_MB_2U(SCH_1):PAGE105_I178@PURE_QUANTA.SCONN288_ADR50017P087CC(CHIPS)':
 'DQ14_A': CDS_PINID='DQ14_A';
NET_NAME
'M_D_CPU1_SA_DQ<15>'
 '@S9S_MB_2U_LIB.S9S_MB_2U(SCH_1):M_D_CPU1_SA_DQ'<15>:
 C_SIGNAL='@s9s_mb_2u_lib.s9s_mb_2u(sch_1):m_d_cpu1_sa_dq(15)';
NODE_NAME     U1 AN74
 '@S9S_MB_2U_LIB.S9S_MB_2U(SCH_1):PAGE54_I91@PURE_QUANTA.SOCKET4677_AZIF0045P001C01CS(CHIPS)':
 'DDR3_SA_DQ15': CDS_PINID='DDR3_SA_DQ15';
NODE_NAME     J23 172
 '@S9S_MB_2U_LIB.S9S_MB_2U(SCH_1):PAGE104_I25@PURE_QUANTA.SCONN288_ADR50017P130CC(CHIPS)':
 'DQ15_A': CDS_PINID='DQ15_A';
NODE_NAME     J24 172
 '@S9S_MB_2U_LIB.S9S_MB_2U(SCH_1):PAGE105_I178@PURE_QUANTA.SCONN288_ADR50017P087CC(CHIPS)':
 'DQ15_A': CDS_PINID='DQ15_A';
NET_NAME
'M_D_CPU1_SA_DQ<16>'
 '@S9S_MB_2U_LIB.S9S_MB_2U(SCH_1):M_D_CPU1_SA_DQ'<16>:
 C_SIGNAL='@s9s_mb_2u_lib.s9s_mb_2u(sch_1):m_d_cpu1_sa_dq(16)';
NODE_NAME     U1 AL72
 '@S9S_MB_2U_LIB.S9S_MB_2U(SCH_1):PAGE54_I91@PURE_QUANTA.SOCKET4677_AZIF0045P001C01CS(CHIPS)':
 'DDR3_SA_DQ16': CDS_PINID='DDR3_SA_DQ16';
NODE_NAME     J23 29
 '@S9S_MB_2U_LIB.S9S_MB_2U(SCH_1):PAGE104_I25@PURE_QUANTA.SCONN288_ADR50017P130CC(CHIPS)':
 'DQ16_A': CDS_PINID='DQ16_A';
NODE_NAME     J24 29
 '@S9S_MB_2U_LIB.S9S_MB_2U(SCH_1):PAGE105_I178@PURE_QUANTA.SCONN288_ADR50017P087CC(CHIPS)':
 'DQ16_A': CDS_PINID='DQ16_A';
NET_NAME
'M_D_CPU1_SA_DQ<17>'
 '@S9S_MB_2U_LIB.S9S_MB_2U(SCH_1):M_D_CPU1_SA_DQ'<17>:
 C_SIGNAL='@s9s_mb_2u_lib.s9s_mb_2u(sch_1):m_d_cpu1_sa_dq(17)';
NODE_NAME     U1 AK71
 '@S9S_MB_2U_LIB.S9S_MB_2U(SCH_1):PAGE54_I91@PURE_QUANTA.SOCKET4677_AZIF0045P001C01CS(CHIPS)':
 'DDR3_SA_DQ17': CDS_PINID='DDR3_SA_DQ17';
NODE_NAME     J23 31
 '@S9S_MB_2U_LIB.S9S_MB_2U(SCH_1):PAGE104_I25@PURE_QUANTA.SCONN288_ADR50017P130CC(CHIPS)':
 'DQ17_A': CDS_PINID='DQ17_A';
NODE_NAME     J24 31
 '@S9S_MB_2U_LIB.S9S_MB_2U(SCH_1):PAGE105_I178@PURE_QUANTA.SCONN288_ADR50017P087CC(CHIPS)':
 'DQ17_A': CDS_PINID='DQ17_A';
NET_NAME
'M_D_CPU1_SA_DQ<18>'
 '@S9S_MB_2U_LIB.S9S_MB_2U(SCH_1):M_D_CPU1_SA_DQ'<18>:
 C_SIGNAL='@s9s_mb_2u_lib.s9s_mb_2u(sch_1):m_d_cpu1_sa_dq(18)';
NODE_NAME     U1 AN72
 '@S9S_MB_2U_LIB.S9S_MB_2U(SCH_1):PAGE54_I91@PURE_QUANTA.SOCKET4677_AZIF0045P001C01CS(CHIPS)':
 'DDR3_SA_DQ18': CDS_PINID='DDR3_SA_DQ18';
NODE_NAME     J23 174
 '@S9S_MB_2U_LIB.S9S_MB_2U(SCH_1):PAGE104_I25@PURE_QUANTA.SCONN288_ADR50017P130CC(CHIPS)':
 'DQ18_A': CDS_PINID='DQ18_A';
NODE_NAME     J24 174
 '@S9S_MB_2U_LIB.S9S_MB_2U(SCH_1):PAGE105_I178@PURE_QUANTA.SCONN288_ADR50017P087CC(CHIPS)':
 'DQ18_A': CDS_PINID='DQ18_A';
NET_NAME
'M_D_CPU1_SA_DQ<19>'
 '@S9S_MB_2U_LIB.S9S_MB_2U(SCH_1):M_D_CPU1_SA_DQ'<19>:
 C_SIGNAL='@s9s_mb_2u_lib.s9s_mb_2u(sch_1):m_d_cpu1_sa_dq(19)';
NODE_NAME     U1 AP71
 '@S9S_MB_2U_LIB.S9S_MB_2U(SCH_1):PAGE54_I91@PURE_QUANTA.SOCKET4677_AZIF0045P001C01CS(CHIPS)':
 'DDR3_SA_DQ19': CDS_PINID='DDR3_SA_DQ19';
NODE_NAME     J23 176
 '@S9S_MB_2U_LIB.S9S_MB_2U(SCH_1):PAGE104_I25@PURE_QUANTA.SCONN288_ADR50017P130CC(CHIPS)':
 'DQ19_A': CDS_PINID='DQ19_A';
NODE_NAME     J24 176
 '@S9S_MB_2U_LIB.S9S_MB_2U(SCH_1):PAGE105_I178@PURE_QUANTA.SCONN288_ADR50017P087CC(CHIPS)':
 'DQ19_A': CDS_PINID='DQ19_A';
NET_NAME
'M_D_CPU1_SA_DQ<1>'
 '@S9S_MB_2U_LIB.S9S_MB_2U(SCH_1):M_D_CPU1_SA_DQ'<1>:
 C_SIGNAL='@s9s_mb_2u_lib.s9s_mb_2u(sch_1):m_d_cpu1_sa_dq(1)';
NODE_NAME     U1 AC74
 '@S9S_MB_2U_LIB.S9S_MB_2U(SCH_1):PAGE54_I91@PURE_QUANTA.SOCKET4677_AZIF0045P001C01CS(CHIPS)':
 'DDR3_SA_DQ1': CDS_PINID='DDR3_SA_DQ1';
NODE_NAME     J23 9
 '@S9S_MB_2U_LIB.S9S_MB_2U(SCH_1):PAGE104_I25@PURE_QUANTA.SCONN288_ADR50017P130CC(CHIPS)':
 'DQ1_A': CDS_PINID='DQ1_A';
NODE_NAME     J24 9
 '@S9S_MB_2U_LIB.S9S_MB_2U(SCH_1):PAGE105_I178@PURE_QUANTA.SCONN288_ADR50017P087CC(CHIPS)':
 'DQ1_A': CDS_PINID='DQ1_A';
NET_NAME
'M_D_CPU1_SA_DQ<20>'
 '@S9S_MB_2U_LIB.S9S_MB_2U(SCH_1):M_D_CPU1_SA_DQ'<20>:
 C_SIGNAL='@s9s_mb_2u_lib.s9s_mb_2u(sch_1):m_d_cpu1_sa_dq(20)';
NODE_NAME     U1 AK69
 '@S9S_MB_2U_LIB.S9S_MB_2U(SCH_1):PAGE54_I91@PURE_QUANTA.SOCKET4677_AZIF0045P001C01CS(CHIPS)':
 'DDR3_SA_DQ20': CDS_PINID='DDR3_SA_DQ20';
NODE_NAME     J23 36
 '@S9S_MB_2U_LIB.S9S_MB_2U(SCH_1):PAGE104_I25@PURE_QUANTA.SCONN288_ADR50017P130CC(CHIPS)':
 'DQ20_A': CDS_PINID='DQ20_A';
NODE_NAME     J24 36
 '@S9S_MB_2U_LIB.S9S_MB_2U(SCH_1):PAGE105_I178@PURE_QUANTA.SCONN288_ADR50017P087CC(CHIPS)':
 'DQ20_A': CDS_PINID='DQ20_A';
NET_NAME
'M_D_CPU1_SA_DQ<21>'
 '@S9S_MB_2U_LIB.S9S_MB_2U(SCH_1):M_D_CPU1_SA_DQ'<21>:
 C_SIGNAL='@s9s_mb_2u_lib.s9s_mb_2u(sch_1):m_d_cpu1_sa_dq(21)';
NODE_NAME     U1 AL68
 '@S9S_MB_2U_LIB.S9S_MB_2U(SCH_1):PAGE54_I91@PURE_QUANTA.SOCKET4677_AZIF0045P001C01CS(CHIPS)':
 'DDR3_SA_DQ21': CDS_PINID='DDR3_SA_DQ21';
NODE_NAME     J23 38
 '@S9S_MB_2U_LIB.S9S_MB_2U(SCH_1):PAGE104_I25@PURE_QUANTA.SCONN288_ADR50017P130CC(CHIPS)':
 'DQ21_A': CDS_PINID='DQ21_A';
NODE_NAME     J24 38
 '@S9S_MB_2U_LIB.S9S_MB_2U(SCH_1):PAGE105_I178@PURE_QUANTA.SCONN288_ADR50017P087CC(CHIPS)':
 'DQ21_A': CDS_PINID='DQ21_A';
NET_NAME
'M_D_CPU1_SA_DQ<22>'
 '@S9S_MB_2U_LIB.S9S_MB_2U(SCH_1):M_D_CPU1_SA_DQ'<22>:
 C_SIGNAL='@s9s_mb_2u_lib.s9s_mb_2u(sch_1):m_d_cpu1_sa_dq(22)';
NODE_NAME     U1 AP69
 '@S9S_MB_2U_LIB.S9S_MB_2U(SCH_1):PAGE54_I91@PURE_QUANTA.SOCKET4677_AZIF0045P001C01CS(CHIPS)':
 'DDR3_SA_DQ22': CDS_PINID='DDR3_SA_DQ22';
NODE_NAME     J23 181
 '@S9S_MB_2U_LIB.S9S_MB_2U(SCH_1):PAGE104_I25@PURE_QUANTA.SCONN288_ADR50017P130CC(CHIPS)':
 'DQ22_A': CDS_PINID='DQ22_A';
NODE_NAME     J24 181
 '@S9S_MB_2U_LIB.S9S_MB_2U(SCH_1):PAGE105_I178@PURE_QUANTA.SCONN288_ADR50017P087CC(CHIPS)':
 'DQ22_A': CDS_PINID='DQ22_A';
NET_NAME
'M_D_CPU1_SA_DQ<23>'
 '@S9S_MB_2U_LIB.S9S_MB_2U(SCH_1):M_D_CPU1_SA_DQ'<23>:
 C_SIGNAL='@s9s_mb_2u_lib.s9s_mb_2u(sch_1):m_d_cpu1_sa_dq(23)';
NODE_NAME     U1 AN68
 '@S9S_MB_2U_LIB.S9S_MB_2U(SCH_1):PAGE54_I91@PURE_QUANTA.SOCKET4677_AZIF0045P001C01CS(CHIPS)':
 'DDR3_SA_DQ23': CDS_PINID='DDR3_SA_DQ23';
NODE_NAME     J23 183
 '@S9S_MB_2U_LIB.S9S_MB_2U(SCH_1):PAGE104_I25@PURE_QUANTA.SCONN288_ADR50017P130CC(CHIPS)':
 'DQ23_A': CDS_PINID='DQ23_A';
NODE_NAME     J24 183
 '@S9S_MB_2U_LIB.S9S_MB_2U(SCH_1):PAGE105_I178@PURE_QUANTA.SCONN288_ADR50017P087CC(CHIPS)':
 'DQ23_A': CDS_PINID='DQ23_A';
NET_NAME
'M_D_CPU1_SA_DQ<24>'
 '@S9S_MB_2U_LIB.S9S_MB_2U(SCH_1):M_D_CPU1_SA_DQ'<24>:
 C_SIGNAL='@s9s_mb_2u_lib.s9s_mb_2u(sch_1):m_d_cpu1_sa_dq(24)';
NODE_NAME     U1 AL66
 '@S9S_MB_2U_LIB.S9S_MB_2U(SCH_1):PAGE54_I91@PURE_QUANTA.SOCKET4677_AZIF0045P001C01CS(CHIPS)':
 'DDR3_SA_DQ24': CDS_PINID='DDR3_SA_DQ24';
NODE_NAME     J23 40
 '@S9S_MB_2U_LIB.S9S_MB_2U(SCH_1):PAGE104_I25@PURE_QUANTA.SCONN288_ADR50017P130CC(CHIPS)':
 'DQ24_A': CDS_PINID='DQ24_A';
NODE_NAME     J24 40
 '@S9S_MB_2U_LIB.S9S_MB_2U(SCH_1):PAGE105_I178@PURE_QUANTA.SCONN288_ADR50017P087CC(CHIPS)':
 'DQ24_A': CDS_PINID='DQ24_A';
NET_NAME
'M_D_CPU1_SA_DQ<25>'
 '@S9S_MB_2U_LIB.S9S_MB_2U(SCH_1):M_D_CPU1_SA_DQ'<25>:
 C_SIGNAL='@s9s_mb_2u_lib.s9s_mb_2u(sch_1):m_d_cpu1_sa_dq(25)';
NODE_NAME     U1 AK65
 '@S9S_MB_2U_LIB.S9S_MB_2U(SCH_1):PAGE54_I91@PURE_QUANTA.SOCKET4677_AZIF0045P001C01CS(CHIPS)':
 'DDR3_SA_DQ25': CDS_PINID='DDR3_SA_DQ25';
NODE_NAME     J23 42
 '@S9S_MB_2U_LIB.S9S_MB_2U(SCH_1):PAGE104_I25@PURE_QUANTA.SCONN288_ADR50017P130CC(CHIPS)':
 'DQ25_A': CDS_PINID='DQ25_A';
NODE_NAME     J24 42
 '@S9S_MB_2U_LIB.S9S_MB_2U(SCH_1):PAGE105_I178@PURE_QUANTA.SCONN288_ADR50017P087CC(CHIPS)':
 'DQ25_A': CDS_PINID='DQ25_A';
NET_NAME
'M_D_CPU1_SA_DQ<26>'
 '@S9S_MB_2U_LIB.S9S_MB_2U(SCH_1):M_D_CPU1_SA_DQ'<26>:
 C_SIGNAL='@s9s_mb_2u_lib.s9s_mb_2u(sch_1):m_d_cpu1_sa_dq(26)';
NODE_NAME     U1 AN66
 '@S9S_MB_2U_LIB.S9S_MB_2U(SCH_1):PAGE54_I91@PURE_QUANTA.SOCKET4677_AZIF0045P001C01CS(CHIPS)':
 'DDR3_SA_DQ26': CDS_PINID='DDR3_SA_DQ26';
NODE_NAME     J23 185
 '@S9S_MB_2U_LIB.S9S_MB_2U(SCH_1):PAGE104_I25@PURE_QUANTA.SCONN288_ADR50017P130CC(CHIPS)':
 'DQ26_A': CDS_PINID='DQ26_A';
NODE_NAME     J24 185
 '@S9S_MB_2U_LIB.S9S_MB_2U(SCH_1):PAGE105_I178@PURE_QUANTA.SCONN288_ADR50017P087CC(CHIPS)':
 'DQ26_A': CDS_PINID='DQ26_A';
NET_NAME
'M_D_CPU1_SA_DQ<27>'
 '@S9S_MB_2U_LIB.S9S_MB_2U(SCH_1):M_D_CPU1_SA_DQ'<27>:
 C_SIGNAL='@s9s_mb_2u_lib.s9s_mb_2u(sch_1):m_d_cpu1_sa_dq(27)';
NODE_NAME     U1 AP65
 '@S9S_MB_2U_LIB.S9S_MB_2U(SCH_1):PAGE54_I91@PURE_QUANTA.SOCKET4677_AZIF0045P001C01CS(CHIPS)':
 'DDR3_SA_DQ27': CDS_PINID='DDR3_SA_DQ27';
NODE_NAME     J23 187
 '@S9S_MB_2U_LIB.S9S_MB_2U(SCH_1):PAGE104_I25@PURE_QUANTA.SCONN288_ADR50017P130CC(CHIPS)':
 'DQ27_A': CDS_PINID='DQ27_A';
NODE_NAME     J24 187
 '@S9S_MB_2U_LIB.S9S_MB_2U(SCH_1):PAGE105_I178@PURE_QUANTA.SCONN288_ADR50017P087CC(CHIPS)':
 'DQ27_A': CDS_PINID='DQ27_A';
NET_NAME
'M_D_CPU1_SA_DQ<28>'
 '@S9S_MB_2U_LIB.S9S_MB_2U(SCH_1):M_D_CPU1_SA_DQ'<28>:
 C_SIGNAL='@s9s_mb_2u_lib.s9s_mb_2u(sch_1):m_d_cpu1_sa_dq(28)';
NODE_NAME     U1 AK63
 '@S9S_MB_2U_LIB.S9S_MB_2U(SCH_1):PAGE54_I91@PURE_QUANTA.SOCKET4677_AZIF0045P001C01CS(CHIPS)':
 'DDR3_SA_DQ28': CDS_PINID='DDR3_SA_DQ28';
NODE_NAME     J23 47
 '@S9S_MB_2U_LIB.S9S_MB_2U(SCH_1):PAGE104_I25@PURE_QUANTA.SCONN288_ADR50017P130CC(CHIPS)':
 'DQ28_A': CDS_PINID='DQ28_A';
NODE_NAME     J24 47
 '@S9S_MB_2U_LIB.S9S_MB_2U(SCH_1):PAGE105_I178@PURE_QUANTA.SCONN288_ADR50017P087CC(CHIPS)':
 'DQ28_A': CDS_PINID='DQ28_A';
NET_NAME
'M_D_CPU1_SA_DQ<29>'
 '@S9S_MB_2U_LIB.S9S_MB_2U(SCH_1):M_D_CPU1_SA_DQ'<29>:
 C_SIGNAL='@s9s_mb_2u_lib.s9s_mb_2u(sch_1):m_d_cpu1_sa_dq(29)';
NODE_NAME     U1 AL62
 '@S9S_MB_2U_LIB.S9S_MB_2U(SCH_1):PAGE54_I91@PURE_QUANTA.SOCKET4677_AZIF0045P001C01CS(CHIPS)':
 'DDR3_SA_DQ29': CDS_PINID='DDR3_SA_DQ29';
NODE_NAME     J23 49
 '@S9S_MB_2U_LIB.S9S_MB_2U(SCH_1):PAGE104_I25@PURE_QUANTA.SCONN288_ADR50017P130CC(CHIPS)':
 'DQ29_A': CDS_PINID='DQ29_A';
NODE_NAME     J24 49
 '@S9S_MB_2U_LIB.S9S_MB_2U(SCH_1):PAGE105_I178@PURE_QUANTA.SCONN288_ADR50017P087CC(CHIPS)':
 'DQ29_A': CDS_PINID='DQ29_A';
NET_NAME
'M_D_CPU1_SA_DQ<2>'
 '@S9S_MB_2U_LIB.S9S_MB_2U(SCH_1):M_D_CPU1_SA_DQ'<2>:
 C_SIGNAL='@s9s_mb_2u_lib.s9s_mb_2u(sch_1):m_d_cpu1_sa_dq(2)';
NODE_NAME     U1 AF75
 '@S9S_MB_2U_LIB.S9S_MB_2U(SCH_1):PAGE54_I91@PURE_QUANTA.SOCKET4677_AZIF0045P001C01CS(CHIPS)':
 'DDR3_SA_DQ2': CDS_PINID='DDR3_SA_DQ2';
NODE_NAME     J23 152
 '@S9S_MB_2U_LIB.S9S_MB_2U(SCH_1):PAGE104_I25@PURE_QUANTA.SCONN288_ADR50017P130CC(CHIPS)':
 'DQ2_A': CDS_PINID='DQ2_A';
NODE_NAME     J24 152
 '@S9S_MB_2U_LIB.S9S_MB_2U(SCH_1):PAGE105_I178@PURE_QUANTA.SCONN288_ADR50017P087CC(CHIPS)':
 'DQ2_A': CDS_PINID='DQ2_A';
NET_NAME
'M_D_CPU1_SA_DQ<30>'
 '@S9S_MB_2U_LIB.S9S_MB_2U(SCH_1):M_D_CPU1_SA_DQ'<30>:
 C_SIGNAL='@s9s_mb_2u_lib.s9s_mb_2u(sch_1):m_d_cpu1_sa_dq(30)';
NODE_NAME     U1 AP63
 '@S9S_MB_2U_LIB.S9S_MB_2U(SCH_1):PAGE54_I91@PURE_QUANTA.SOCKET4677_AZIF0045P001C01CS(CHIPS)':
 'DDR3_SA_DQ30': CDS_PINID='DDR3_SA_DQ30';
NODE_NAME     J23 192
 '@S9S_MB_2U_LIB.S9S_MB_2U(SCH_1):PAGE104_I25@PURE_QUANTA.SCONN288_ADR50017P130CC(CHIPS)':
 'DQ30_A': CDS_PINID='DQ30_A';
NODE_NAME     J24 192
 '@S9S_MB_2U_LIB.S9S_MB_2U(SCH_1):PAGE105_I178@PURE_QUANTA.SCONN288_ADR50017P087CC(CHIPS)':
 'DQ30_A': CDS_PINID='DQ30_A';
NET_NAME
'M_D_CPU1_SA_DQ<31>'
 '@S9S_MB_2U_LIB.S9S_MB_2U(SCH_1):M_D_CPU1_SA_DQ'<31>:
 C_SIGNAL='@s9s_mb_2u_lib.s9s_mb_2u(sch_1):m_d_cpu1_sa_dq(31)';
NODE_NAME     U1 AN62
 '@S9S_MB_2U_LIB.S9S_MB_2U(SCH_1):PAGE54_I91@PURE_QUANTA.SOCKET4677_AZIF0045P001C01CS(CHIPS)':
 'DDR3_SA_DQ31': CDS_PINID='DDR3_SA_DQ31';
NODE_NAME     J23 194
 '@S9S_MB_2U_LIB.S9S_MB_2U(SCH_1):PAGE104_I25@PURE_QUANTA.SCONN288_ADR50017P130CC(CHIPS)':
 'DQ31_A': CDS_PINID='DQ31_A';
NODE_NAME     J24 194
 '@S9S_MB_2U_LIB.S9S_MB_2U(SCH_1):PAGE105_I178@PURE_QUANTA.SCONN288_ADR50017P087CC(CHIPS)':
 'DQ31_A': CDS_PINID='DQ31_A';
NET_NAME
'M_D_CPU1_SA_DQ<3>'
 '@S9S_MB_2U_LIB.S9S_MB_2U(SCH_1):M_D_CPU1_SA_DQ'<3>:
 C_SIGNAL='@s9s_mb_2u_lib.s9s_mb_2u(sch_1):m_d_cpu1_sa_dq(3)';
NODE_NAME     U1 AG74
 '@S9S_MB_2U_LIB.S9S_MB_2U(SCH_1):PAGE54_I91@PURE_QUANTA.SOCKET4677_AZIF0045P001C01CS(CHIPS)':
 'DDR3_SA_DQ3': CDS_PINID='DDR3_SA_DQ3';
NODE_NAME     J23 154
 '@S9S_MB_2U_LIB.S9S_MB_2U(SCH_1):PAGE104_I25@PURE_QUANTA.SCONN288_ADR50017P130CC(CHIPS)':
 'DQ3_A': CDS_PINID='DQ3_A';
NODE_NAME     J24 154
 '@S9S_MB_2U_LIB.S9S_MB_2U(SCH_1):PAGE105_I178@PURE_QUANTA.SCONN288_ADR50017P087CC(CHIPS)':
 'DQ3_A': CDS_PINID='DQ3_A';
NET_NAME
'M_D_CPU1_SA_DQ<4>'
 '@S9S_MB_2U_LIB.S9S_MB_2U(SCH_1):M_D_CPU1_SA_DQ'<4>:
 C_SIGNAL='@s9s_mb_2u_lib.s9s_mb_2u(sch_1):m_d_cpu1_sa_dq(4)';
NODE_NAME     U1 AC72
 '@S9S_MB_2U_LIB.S9S_MB_2U(SCH_1):PAGE54_I91@PURE_QUANTA.SOCKET4677_AZIF0045P001C01CS(CHIPS)':
 'DDR3_SA_DQ4': CDS_PINID='DDR3_SA_DQ4';
NODE_NAME     J23 14
 '@S9S_MB_2U_LIB.S9S_MB_2U(SCH_1):PAGE104_I25@PURE_QUANTA.SCONN288_ADR50017P130CC(CHIPS)':
 'DQ4_A': CDS_PINID='DQ4_A';
NODE_NAME     J24 14
 '@S9S_MB_2U_LIB.S9S_MB_2U(SCH_1):PAGE105_I178@PURE_QUANTA.SCONN288_ADR50017P087CC(CHIPS)':
 'DQ4_A': CDS_PINID='DQ4_A';
NET_NAME
'M_D_CPU1_SA_DQ<5>'
 '@S9S_MB_2U_LIB.S9S_MB_2U(SCH_1):M_D_CPU1_SA_DQ'<5>:
 C_SIGNAL='@s9s_mb_2u_lib.s9s_mb_2u(sch_1):m_d_cpu1_sa_dq(5)';
NODE_NAME     U1 AD71
 '@S9S_MB_2U_LIB.S9S_MB_2U(SCH_1):PAGE54_I91@PURE_QUANTA.SOCKET4677_AZIF0045P001C01CS(CHIPS)':
 'DDR3_SA_DQ5': CDS_PINID='DDR3_SA_DQ5';
NODE_NAME     J23 16
 '@S9S_MB_2U_LIB.S9S_MB_2U(SCH_1):PAGE104_I25@PURE_QUANTA.SCONN288_ADR50017P130CC(CHIPS)':
 'DQ5_A': CDS_PINID='DQ5_A';
NODE_NAME     J24 16
 '@S9S_MB_2U_LIB.S9S_MB_2U(SCH_1):PAGE105_I178@PURE_QUANTA.SCONN288_ADR50017P087CC(CHIPS)':
 'DQ5_A': CDS_PINID='DQ5_A';
NET_NAME
'M_D_CPU1_SA_DQ<6>'
 '@S9S_MB_2U_LIB.S9S_MB_2U(SCH_1):M_D_CPU1_SA_DQ'<6>:
 C_SIGNAL='@s9s_mb_2u_lib.s9s_mb_2u(sch_1):m_d_cpu1_sa_dq(6)';
NODE_NAME     U1 AG72
 '@S9S_MB_2U_LIB.S9S_MB_2U(SCH_1):PAGE54_I91@PURE_QUANTA.SOCKET4677_AZIF0045P001C01CS(CHIPS)':
 'DDR3_SA_DQ6': CDS_PINID='DDR3_SA_DQ6';
NODE_NAME     J23 159
 '@S9S_MB_2U_LIB.S9S_MB_2U(SCH_1):PAGE104_I25@PURE_QUANTA.SCONN288_ADR50017P130CC(CHIPS)':
 'DQ6_A': CDS_PINID='DQ6_A';
NODE_NAME     J24 159
 '@S9S_MB_2U_LIB.S9S_MB_2U(SCH_1):PAGE105_I178@PURE_QUANTA.SCONN288_ADR50017P087CC(CHIPS)':
 'DQ6_A': CDS_PINID='DQ6_A';
NET_NAME
'M_D_CPU1_SA_DQ<7>'
 '@S9S_MB_2U_LIB.S9S_MB_2U(SCH_1):M_D_CPU1_SA_DQ'<7>:
 C_SIGNAL='@s9s_mb_2u_lib.s9s_mb_2u(sch_1):m_d_cpu1_sa_dq(7)';
NODE_NAME     U1 AF71
 '@S9S_MB_2U_LIB.S9S_MB_2U(SCH_1):PAGE54_I91@PURE_QUANTA.SOCKET4677_AZIF0045P001C01CS(CHIPS)':
 'DDR3_SA_DQ7': CDS_PINID='DDR3_SA_DQ7';
NODE_NAME     J23 161
 '@S9S_MB_2U_LIB.S9S_MB_2U(SCH_1):PAGE104_I25@PURE_QUANTA.SCONN288_ADR50017P130CC(CHIPS)':
 'DQ7_A': CDS_PINID='DQ7_A';
NODE_NAME     J24 161
 '@S9S_MB_2U_LIB.S9S_MB_2U(SCH_1):PAGE105_I178@PURE_QUANTA.SCONN288_ADR50017P087CC(CHIPS)':
 'DQ7_A': CDS_PINID='DQ7_A';
NET_NAME
'M_D_CPU1_SA_DQ<8>'
 '@S9S_MB_2U_LIB.S9S_MB_2U(SCH_1):M_D_CPU1_SA_DQ'<8>:
 C_SIGNAL='@s9s_mb_2u_lib.s9s_mb_2u(sch_1):m_d_cpu1_sa_dq(8)';
NODE_NAME     U1 AL78
 '@S9S_MB_2U_LIB.S9S_MB_2U(SCH_1):PAGE54_I91@PURE_QUANTA.SOCKET4677_AZIF0045P001C01CS(CHIPS)':
 'DDR3_SA_DQ8': CDS_PINID='DDR3_SA_DQ8';
NODE_NAME     J23 18
 '@S9S_MB_2U_LIB.S9S_MB_2U(SCH_1):PAGE104_I25@PURE_QUANTA.SCONN288_ADR50017P130CC(CHIPS)':
 'DQ8_A': CDS_PINID='DQ8_A';
NODE_NAME     J24 18
 '@S9S_MB_2U_LIB.S9S_MB_2U(SCH_1):PAGE105_I178@PURE_QUANTA.SCONN288_ADR50017P087CC(CHIPS)':
 'DQ8_A': CDS_PINID='DQ8_A';
NET_NAME
'M_D_CPU1_SA_DQ<9>'
 '@S9S_MB_2U_LIB.S9S_MB_2U(SCH_1):M_D_CPU1_SA_DQ'<9>:
 C_SIGNAL='@s9s_mb_2u_lib.s9s_mb_2u(sch_1):m_d_cpu1_sa_dq(9)';
NODE_NAME     U1 AK77
 '@S9S_MB_2U_LIB.S9S_MB_2U(SCH_1):PAGE54_I91@PURE_QUANTA.SOCKET4677_AZIF0045P001C01CS(CHIPS)':
 'DDR3_SA_DQ9': CDS_PINID='DDR3_SA_DQ9';
NODE_NAME     J23 20
 '@S9S_MB_2U_LIB.S9S_MB_2U(SCH_1):PAGE104_I25@PURE_QUANTA.SCONN288_ADR50017P130CC(CHIPS)':
 'DQ9_A': CDS_PINID='DQ9_A';
NODE_NAME     J24 20
 '@S9S_MB_2U_LIB.S9S_MB_2U(SCH_1):PAGE105_I178@PURE_QUANTA.SCONN288_ADR50017P087CC(CHIPS)':
 'DQ9_A': CDS_PINID='DQ9_A';
NET_NAME
'M_D_CPU1_SA_DQS_DN<0>'
 '@S9S_MB_2U_LIB.S9S_MB_2U(SCH_1):M_D_CPU1_SA_DQS_DN'<0>:
 C_SIGNAL='@s9s_mb_2u_lib.s9s_mb_2u(sch_1):m_d_cpu1_sa_dqs_dn(0)';
NODE_NAME     U1 AB73
 '@S9S_MB_2U_LIB.S9S_MB_2U(SCH_1):PAGE54_I91@PURE_QUANTA.SOCKET4677_AZIF0045P001C01CS(CHIPS)':
 'DDR3_SA_DQS_DN0': CDS_PINID='DDR3_SA_DQS_DN0';
NODE_NAME     J23 12
 '@S9S_MB_2U_LIB.S9S_MB_2U(SCH_1):PAGE104_I178@PURE_QUANTA.SCONN288_ADR50017P130CC(CHIPS)':
 'DQS0_A_C': CDS_PINID='DQS0_A_C';
NODE_NAME     J24 12
 '@S9S_MB_2U_LIB.S9S_MB_2U(SCH_1):PAGE105_I181@PURE_QUANTA.SCONN288_ADR50017P087CC(CHIPS)':
 'DQS0_A_C': CDS_PINID='DQS0_A_C';
NET_NAME
'M_D_CPU1_SA_DQS_DN<1>'
 '@S9S_MB_2U_LIB.S9S_MB_2U(SCH_1):M_D_CPU1_SA_DQS_DN'<1>:
 C_SIGNAL='@s9s_mb_2u_lib.s9s_mb_2u(sch_1):m_d_cpu1_sa_dqs_dn(1)';
NODE_NAME     U1 AJ76
 '@S9S_MB_2U_LIB.S9S_MB_2U(SCH_1):PAGE54_I91@PURE_QUANTA.SOCKET4677_AZIF0045P001C01CS(CHIPS)':
 'DDR3_SA_DQS_DN1': CDS_PINID='DDR3_SA_DQS_DN1';
NODE_NAME     J23 23
 '@S9S_MB_2U_LIB.S9S_MB_2U(SCH_1):PAGE104_I178@PURE_QUANTA.SCONN288_ADR50017P130CC(CHIPS)':
 'DQS1_A_C': CDS_PINID='DQS1_A_C';
NODE_NAME     J24 23
 '@S9S_MB_2U_LIB.S9S_MB_2U(SCH_1):PAGE105_I181@PURE_QUANTA.SCONN288_ADR50017P087CC(CHIPS)':
 'DQS1_A_C': CDS_PINID='DQS1_A_C';
NET_NAME
'M_D_CPU1_SA_DQS_DN<2>'
 '@S9S_MB_2U_LIB.S9S_MB_2U(SCH_1):M_D_CPU1_SA_DQS_DN'<2>:
 C_SIGNAL='@s9s_mb_2u_lib.s9s_mb_2u(sch_1):m_d_cpu1_sa_dqs_dn(2)';
NODE_NAME     U1 AJ70
 '@S9S_MB_2U_LIB.S9S_MB_2U(SCH_1):PAGE54_I91@PURE_QUANTA.SOCKET4677_AZIF0045P001C01CS(CHIPS)':
 'DDR3_SA_DQS_DN2': CDS_PINID='DDR3_SA_DQS_DN2';
NODE_NAME     J23 34
 '@S9S_MB_2U_LIB.S9S_MB_2U(SCH_1):PAGE104_I178@PURE_QUANTA.SCONN288_ADR50017P130CC(CHIPS)':
 'DQS2_A_C': CDS_PINID='DQS2_A_C';
NODE_NAME     J24 34
 '@S9S_MB_2U_LIB.S9S_MB_2U(SCH_1):PAGE105_I181@PURE_QUANTA.SCONN288_ADR50017P087CC(CHIPS)':
 'DQS2_A_C': CDS_PINID='DQS2_A_C';
NET_NAME
'M_D_CPU1_SA_DQS_DN<3>'
 '@S9S_MB_2U_LIB.S9S_MB_2U(SCH_1):M_D_CPU1_SA_DQS_DN'<3>:
 C_SIGNAL='@s9s_mb_2u_lib.s9s_mb_2u(sch_1):m_d_cpu1_sa_dqs_dn(3)';
NODE_NAME     U1 AJ64
 '@S9S_MB_2U_LIB.S9S_MB_2U(SCH_1):PAGE54_I91@PURE_QUANTA.SOCKET4677_AZIF0045P001C01CS(CHIPS)':
 'DDR3_SA_DQS_DN3': CDS_PINID='DDR3_SA_DQS_DN3';
NODE_NAME     J23 45
 '@S9S_MB_2U_LIB.S9S_MB_2U(SCH_1):PAGE104_I178@PURE_QUANTA.SCONN288_ADR50017P130CC(CHIPS)':
 'DQS3_A_C': CDS_PINID='DQS3_A_C';
NODE_NAME     J24 45
 '@S9S_MB_2U_LIB.S9S_MB_2U(SCH_1):PAGE105_I181@PURE_QUANTA.SCONN288_ADR50017P087CC(CHIPS)':
 'DQS3_A_C': CDS_PINID='DQS3_A_C';
NET_NAME
'M_D_CPU1_SA_DQS_DN<4>'
 '@S9S_MB_2U_LIB.S9S_MB_2U(SCH_1):M_D_CPU1_SA_DQS_DN'<4>:
 C_SIGNAL='@s9s_mb_2u_lib.s9s_mb_2u(sch_1):m_d_cpu1_sa_dqs_dn(4)';
NODE_NAME     U1 AJ58
 '@S9S_MB_2U_LIB.S9S_MB_2U(SCH_1):PAGE54_I91@PURE_QUANTA.SOCKET4677_AZIF0045P001C01CS(CHIPS)':
 'DDR3_SA_DQS_DN4': CDS_PINID='DDR3_SA_DQS_DN4';
NODE_NAME     J23 56
 '@S9S_MB_2U_LIB.S9S_MB_2U(SCH_1):PAGE104_I178@PURE_QUANTA.SCONN288_ADR50017P130CC(CHIPS)':
 'DQS4_A_C': CDS_PINID='DQS4_A_C';
NODE_NAME     J24 56
 '@S9S_MB_2U_LIB.S9S_MB_2U(SCH_1):PAGE105_I181@PURE_QUANTA.SCONN288_ADR50017P087CC(CHIPS)':
 'DQS4_A_C': CDS_PINID='DQS4_A_C';
NET_NAME
'M_D_CPU1_SA_DQS_DN<5>'
 '@S9S_MB_2U_LIB.S9S_MB_2U(SCH_1):M_D_CPU1_SA_DQS_DN'<5>:
 C_SIGNAL='@s9s_mb_2u_lib.s9s_mb_2u(sch_1):m_d_cpu1_sa_dqs_dn(5)';
NODE_NAME     U1 AH73
 '@S9S_MB_2U_LIB.S9S_MB_2U(SCH_1):PAGE54_I91@PURE_QUANTA.SOCKET4677_AZIF0045P001C01CS(CHIPS)':
 'DDR3_SA_DQS_DN5': CDS_PINID='DDR3_SA_DQS_DN5';
NODE_NAME     J23 156
 '@S9S_MB_2U_LIB.S9S_MB_2U(SCH_1):PAGE104_I178@PURE_QUANTA.SCONN288_ADR50017P130CC(CHIPS)':
 'DQS5_A_C||TDQS5_A_C||DQS5_A_T||TDQS5_A_T': CDS_PINID='\dqs5_a_c||tdqs5_a_c||dqs5_a_t||tdqs5_a_t\';
NODE_NAME     J24 156
 '@S9S_MB_2U_LIB.S9S_MB_2U(SCH_1):PAGE105_I181@PURE_QUANTA.SCONN288_ADR50017P087CC(CHIPS)':
 'DQS5_A_C||TDQS5_A_C||DQS5_A_T||TDQS5_A_T': CDS_PINID='\dqs5_a_c||tdqs5_a_c||dqs5_a_t||tdqs5_a_t\';
NET_NAME
'M_D_CPU1_SA_DQS_DN<6>'
 '@S9S_MB_2U_LIB.S9S_MB_2U(SCH_1):M_D_CPU1_SA_DQS_DN'<6>:
 C_SIGNAL='@s9s_mb_2u_lib.s9s_mb_2u(sch_1):m_d_cpu1_sa_dqs_dn(6)';
NODE_NAME     U1 AN76
 '@S9S_MB_2U_LIB.S9S_MB_2U(SCH_1):PAGE54_I91@PURE_QUANTA.SOCKET4677_AZIF0045P001C01CS(CHIPS)':
 'DDR3_SA_DQS_DN6': CDS_PINID='DDR3_SA_DQS_DN6';
NODE_NAME     J23 167
 '@S9S_MB_2U_LIB.S9S_MB_2U(SCH_1):PAGE104_I178@PURE_QUANTA.SCONN288_ADR50017P130CC(CHIPS)':
 'DQS6_A_C||TDQS6_A_C||DQS6_A_T||TDQS6_A_T': CDS_PINID='\dqs6_a_c||tdqs6_a_c||dqs6_a_t||tdqs6_a_t\';
NODE_NAME     J24 167
 '@S9S_MB_2U_LIB.S9S_MB_2U(SCH_1):PAGE105_I181@PURE_QUANTA.SCONN288_ADR50017P087CC(CHIPS)':
 'DQS6_A_C||TDQS6_A_C||DQS6_A_T||TDQS6_A_T': CDS_PINID='\dqs6_a_c||tdqs6_a_c||dqs6_a_t||tdqs6_a_t\';
NET_NAME
'M_D_CPU1_SA_DQS_DN<7>'
 '@S9S_MB_2U_LIB.S9S_MB_2U(SCH_1):M_D_CPU1_SA_DQS_DN'<7>:
 C_SIGNAL='@s9s_mb_2u_lib.s9s_mb_2u(sch_1):m_d_cpu1_sa_dqs_dn(7)';
NODE_NAME     U1 AN70
 '@S9S_MB_2U_LIB.S9S_MB_2U(SCH_1):PAGE54_I91@PURE_QUANTA.SOCKET4677_AZIF0045P001C01CS(CHIPS)':
 'DDR3_SA_DQS_DN7': CDS_PINID='DDR3_SA_DQS_DN7';
NODE_NAME     J23 178
 '@S9S_MB_2U_LIB.S9S_MB_2U(SCH_1):PAGE104_I178@PURE_QUANTA.SCONN288_ADR50017P130CC(CHIPS)':
 'DQS7_A_C||TDQS7_A_C': CDS_PINID='\dqs7_a_c||tdqs7_a_c\';
NODE_NAME     J24 178
 '@S9S_MB_2U_LIB.S9S_MB_2U(SCH_1):PAGE105_I181@PURE_QUANTA.SCONN288_ADR50017P087CC(CHIPS)':
 'DQS7_A_C||TDQS7_A_C': CDS_PINID='\dqs7_a_c||tdqs7_a_c\';
NET_NAME
'M_D_CPU1_SA_DQS_DN<8>'
 '@S9S_MB_2U_LIB.S9S_MB_2U(SCH_1):M_D_CPU1_SA_DQS_DN'<8>:
 C_SIGNAL='@s9s_mb_2u_lib.s9s_mb_2u(sch_1):m_d_cpu1_sa_dqs_dn(8)';
NODE_NAME     U1 AN64
 '@S9S_MB_2U_LIB.S9S_MB_2U(SCH_1):PAGE54_I91@PURE_QUANTA.SOCKET4677_AZIF0045P001C01CS(CHIPS)':
 'DDR3_SA_DQS_DN8': CDS_PINID='DDR3_SA_DQS_DN8';
NODE_NAME     J23 189
 '@S9S_MB_2U_LIB.S9S_MB_2U(SCH_1):PAGE104_I178@PURE_QUANTA.SCONN288_ADR50017P130CC(CHIPS)':
 'DQS8_A_C||TDQS8_A_C': CDS_PINID='\dqs8_a_c||tdqs8_a_c\';
NODE_NAME     J24 189
 '@S9S_MB_2U_LIB.S9S_MB_2U(SCH_1):PAGE105_I181@PURE_QUANTA.SCONN288_ADR50017P087CC(CHIPS)':
 'DQS8_A_C||TDQS8_A_C': CDS_PINID='\dqs8_a_c||tdqs8_a_c\';
NET_NAME
'M_D_CPU1_SA_DQS_DN<9>'
 '@S9S_MB_2U_LIB.S9S_MB_2U(SCH_1):M_D_CPU1_SA_DQS_DN'<9>:
 C_SIGNAL='@s9s_mb_2u_lib.s9s_mb_2u(sch_1):m_d_cpu1_sa_dqs_dn(9)';
NODE_NAME     U1 AN58
 '@S9S_MB_2U_LIB.S9S_MB_2U(SCH_1):PAGE54_I91@PURE_QUANTA.SOCKET4677_AZIF0045P001C01CS(CHIPS)':
 'DDR3_SA_DQS_DN9': CDS_PINID='DDR3_SA_DQS_DN9';
NODE_NAME     J23 200
 '@S9S_MB_2U_LIB.S9S_MB_2U(SCH_1):PAGE104_I178@PURE_QUANTA.SCONN288_ADR50017P130CC(CHIPS)':
 'DQS9_A_C||TDQS9_A_C': CDS_PINID='\dqs9_a_c||tdqs9_a_c\';
NODE_NAME     J24 200
 '@S9S_MB_2U_LIB.S9S_MB_2U(SCH_1):PAGE105_I181@PURE_QUANTA.SCONN288_ADR50017P087CC(CHIPS)':
 'DQS9_A_C||TDQS9_A_C': CDS_PINID='\dqs9_a_c||tdqs9_a_c\';
NET_NAME
'M_D_CPU1_SA_DQS_DP<0>'
 '@S9S_MB_2U_LIB.S9S_MB_2U(SCH_1):M_D_CPU1_SA_DQS_DP'<0>:
 C_SIGNAL='@s9s_mb_2u_lib.s9s_mb_2u(sch_1):m_d_cpu1_sa_dqs_dp(0)';
NODE_NAME     U1 AD73
 '@S9S_MB_2U_LIB.S9S_MB_2U(SCH_1):PAGE54_I91@PURE_QUANTA.SOCKET4677_AZIF0045P001C01CS(CHIPS)':
 'DDR3_SA_DQS_DP0': CDS_PINID='DDR3_SA_DQS_DP0';
NODE_NAME     J23 11
 '@S9S_MB_2U_LIB.S9S_MB_2U(SCH_1):PAGE104_I178@PURE_QUANTA.SCONN288_ADR50017P130CC(CHIPS)':
 'DQS0_A_T': CDS_PINID='DQS0_A_T';
NODE_NAME     J24 11
 '@S9S_MB_2U_LIB.S9S_MB_2U(SCH_1):PAGE105_I181@PURE_QUANTA.SCONN288_ADR50017P087CC(CHIPS)':
 'DQS0_A_T': CDS_PINID='DQS0_A_T';
NET_NAME
'M_D_CPU1_SA_DQS_DP<1>'
 '@S9S_MB_2U_LIB.S9S_MB_2U(SCH_1):M_D_CPU1_SA_DQS_DP'<1>:
 C_SIGNAL='@s9s_mb_2u_lib.s9s_mb_2u(sch_1):m_d_cpu1_sa_dqs_dp(1)';
NODE_NAME     U1 AL76
 '@S9S_MB_2U_LIB.S9S_MB_2U(SCH_1):PAGE54_I91@PURE_QUANTA.SOCKET4677_AZIF0045P001C01CS(CHIPS)':
 'DDR3_SA_DQS_DP1': CDS_PINID='DDR3_SA_DQS_DP1';
NODE_NAME     J23 22
 '@S9S_MB_2U_LIB.S9S_MB_2U(SCH_1):PAGE104_I178@PURE_QUANTA.SCONN288_ADR50017P130CC(CHIPS)':
 'DQS1_A_T': CDS_PINID='DQS1_A_T';
NODE_NAME     J24 22
 '@S9S_MB_2U_LIB.S9S_MB_2U(SCH_1):PAGE105_I181@PURE_QUANTA.SCONN288_ADR50017P087CC(CHIPS)':
 'DQS1_A_T': CDS_PINID='DQS1_A_T';
NET_NAME
'M_D_CPU1_SA_DQS_DP<2>'
 '@S9S_MB_2U_LIB.S9S_MB_2U(SCH_1):M_D_CPU1_SA_DQS_DP'<2>:
 C_SIGNAL='@s9s_mb_2u_lib.s9s_mb_2u(sch_1):m_d_cpu1_sa_dqs_dp(2)';
NODE_NAME     U1 AL70
 '@S9S_MB_2U_LIB.S9S_MB_2U(SCH_1):PAGE54_I91@PURE_QUANTA.SOCKET4677_AZIF0045P001C01CS(CHIPS)':
 'DDR3_SA_DQS_DP2': CDS_PINID='DDR3_SA_DQS_DP2';
NODE_NAME     J23 33
 '@S9S_MB_2U_LIB.S9S_MB_2U(SCH_1):PAGE104_I178@PURE_QUANTA.SCONN288_ADR50017P130CC(CHIPS)':
 'DQS2_A_T': CDS_PINID='DQS2_A_T';
NODE_NAME     J24 33
 '@S9S_MB_2U_LIB.S9S_MB_2U(SCH_1):PAGE105_I181@PURE_QUANTA.SCONN288_ADR50017P087CC(CHIPS)':
 'DQS2_A_T': CDS_PINID='DQS2_A_T';
NET_NAME
'M_D_CPU1_SA_DQS_DP<3>'
 '@S9S_MB_2U_LIB.S9S_MB_2U(SCH_1):M_D_CPU1_SA_DQS_DP'<3>:
 C_SIGNAL='@s9s_mb_2u_lib.s9s_mb_2u(sch_1):m_d_cpu1_sa_dqs_dp(3)';
NODE_NAME     U1 AL64
 '@S9S_MB_2U_LIB.S9S_MB_2U(SCH_1):PAGE54_I91@PURE_QUANTA.SOCKET4677_AZIF0045P001C01CS(CHIPS)':
 'DDR3_SA_DQS_DP3': CDS_PINID='DDR3_SA_DQS_DP3';
NODE_NAME     J23 44
 '@S9S_MB_2U_LIB.S9S_MB_2U(SCH_1):PAGE104_I178@PURE_QUANTA.SCONN288_ADR50017P130CC(CHIPS)':
 'DQS3_A_T': CDS_PINID='DQS3_A_T';
NODE_NAME     J24 44
 '@S9S_MB_2U_LIB.S9S_MB_2U(SCH_1):PAGE105_I181@PURE_QUANTA.SCONN288_ADR50017P087CC(CHIPS)':
 'DQS3_A_T': CDS_PINID='DQS3_A_T';
NET_NAME
'M_D_CPU1_SA_DQS_DP<4>'
 '@S9S_MB_2U_LIB.S9S_MB_2U(SCH_1):M_D_CPU1_SA_DQS_DP'<4>:
 C_SIGNAL='@s9s_mb_2u_lib.s9s_mb_2u(sch_1):m_d_cpu1_sa_dqs_dp(4)';
NODE_NAME     U1 AL58
 '@S9S_MB_2U_LIB.S9S_MB_2U(SCH_1):PAGE54_I91@PURE_QUANTA.SOCKET4677_AZIF0045P001C01CS(CHIPS)':
 'DDR3_SA_DQS_DP4': CDS_PINID='DDR3_SA_DQS_DP4';
NODE_NAME     J23 55
 '@S9S_MB_2U_LIB.S9S_MB_2U(SCH_1):PAGE104_I178@PURE_QUANTA.SCONN288_ADR50017P130CC(CHIPS)':
 'DQS4_A_T': CDS_PINID='DQS4_A_T';
NODE_NAME     J24 55
 '@S9S_MB_2U_LIB.S9S_MB_2U(SCH_1):PAGE105_I181@PURE_QUANTA.SCONN288_ADR50017P087CC(CHIPS)':
 'DQS4_A_T': CDS_PINID='DQS4_A_T';
NET_NAME
'M_D_CPU1_SA_DQS_DP<5>'
 '@S9S_MB_2U_LIB.S9S_MB_2U(SCH_1):M_D_CPU1_SA_DQS_DP'<5>:
 C_SIGNAL='@s9s_mb_2u_lib.s9s_mb_2u(sch_1):m_d_cpu1_sa_dqs_dp(5)';
NODE_NAME     U1 AF73
 '@S9S_MB_2U_LIB.S9S_MB_2U(SCH_1):PAGE54_I91@PURE_QUANTA.SOCKET4677_AZIF0045P001C01CS(CHIPS)':
 'DDR3_SA_DQS_DP5': CDS_PINID='DDR3_SA_DQS_DP5';
NODE_NAME     J23 157
 '@S9S_MB_2U_LIB.S9S_MB_2U(SCH_1):PAGE104_I178@PURE_QUANTA.SCONN288_ADR50017P130CC(CHIPS)':
 'DQS5_A_T||TDQS5_A_T': CDS_PINID='\dqs5_a_t||tdqs5_a_t\';
NODE_NAME     J24 157
 '@S9S_MB_2U_LIB.S9S_MB_2U(SCH_1):PAGE105_I181@PURE_QUANTA.SCONN288_ADR50017P087CC(CHIPS)':
 'DQS5_A_T||TDQS5_A_T': CDS_PINID='\dqs5_a_t||tdqs5_a_t\';
NET_NAME
'M_D_CPU1_SA_DQS_DP<6>'
 '@S9S_MB_2U_LIB.S9S_MB_2U(SCH_1):M_D_CPU1_SA_DQS_DP'<6>:
 C_SIGNAL='@s9s_mb_2u_lib.s9s_mb_2u(sch_1):m_d_cpu1_sa_dqs_dp(6)';
NODE_NAME     U1 AR76
 '@S9S_MB_2U_LIB.S9S_MB_2U(SCH_1):PAGE54_I91@PURE_QUANTA.SOCKET4677_AZIF0045P001C01CS(CHIPS)':
 'DDR3_SA_DQS_DP6': CDS_PINID='DDR3_SA_DQS_DP6';
NODE_NAME     J23 168
 '@S9S_MB_2U_LIB.S9S_MB_2U(SCH_1):PAGE104_I178@PURE_QUANTA.SCONN288_ADR50017P130CC(CHIPS)':
 'DQS6_A_T||TDQS6_A_T': CDS_PINID='\dqs6_a_t||tdqs6_a_t\';
NODE_NAME     J24 168
 '@S9S_MB_2U_LIB.S9S_MB_2U(SCH_1):PAGE105_I181@PURE_QUANTA.SCONN288_ADR50017P087CC(CHIPS)':
 'DQS6_A_T||TDQS6_A_T': CDS_PINID='\dqs6_a_t||tdqs6_a_t\';
NET_NAME
'M_D_CPU1_SA_DQS_DP<7>'
 '@S9S_MB_2U_LIB.S9S_MB_2U(SCH_1):M_D_CPU1_SA_DQS_DP'<7>:
 C_SIGNAL='@s9s_mb_2u_lib.s9s_mb_2u(sch_1):m_d_cpu1_sa_dqs_dp(7)';
NODE_NAME     U1 AR70
 '@S9S_MB_2U_LIB.S9S_MB_2U(SCH_1):PAGE54_I91@PURE_QUANTA.SOCKET4677_AZIF0045P001C01CS(CHIPS)':
 'DDR3_SA_DQS_DP7': CDS_PINID='DDR3_SA_DQS_DP7';
NODE_NAME     J23 179
 '@S9S_MB_2U_LIB.S9S_MB_2U(SCH_1):PAGE104_I178@PURE_QUANTA.SCONN288_ADR50017P130CC(CHIPS)':
 'DQS7_A_T||TDQS7_A_T': CDS_PINID='\dqs7_a_t||tdqs7_a_t\';
NODE_NAME     J24 179
 '@S9S_MB_2U_LIB.S9S_MB_2U(SCH_1):PAGE105_I181@PURE_QUANTA.SCONN288_ADR50017P087CC(CHIPS)':
 'DQS7_A_T||TDQS7_A_T': CDS_PINID='\dqs7_a_t||tdqs7_a_t\';
NET_NAME
'M_D_CPU1_SA_DQS_DP<8>'
 '@S9S_MB_2U_LIB.S9S_MB_2U(SCH_1):M_D_CPU1_SA_DQS_DP'<8>:
 C_SIGNAL='@s9s_mb_2u_lib.s9s_mb_2u(sch_1):m_d_cpu1_sa_dqs_dp(8)';
NODE_NAME     U1 AR64
 '@S9S_MB_2U_LIB.S9S_MB_2U(SCH_1):PAGE54_I91@PURE_QUANTA.SOCKET4677_AZIF0045P001C01CS(CHIPS)':
 'DDR3_SA_DQS_DP8': CDS_PINID='DDR3_SA_DQS_DP8';
NODE_NAME     J23 190
 '@S9S_MB_2U_LIB.S9S_MB_2U(SCH_1):PAGE104_I178@PURE_QUANTA.SCONN288_ADR50017P130CC(CHIPS)':
 'DQS8_A_T||TDQS8_A_T': CDS_PINID='\dqs8_a_t||tdqs8_a_t\';
NODE_NAME     J24 190
 '@S9S_MB_2U_LIB.S9S_MB_2U(SCH_1):PAGE105_I181@PURE_QUANTA.SCONN288_ADR50017P087CC(CHIPS)':
 'DQS8_A_T||TDQS8_A_T': CDS_PINID='\dqs8_a_t||tdqs8_a_t\';
NET_NAME
'M_D_CPU1_SA_DQS_DP<9>'
 '@S9S_MB_2U_LIB.S9S_MB_2U(SCH_1):M_D_CPU1_SA_DQS_DP'<9>:
 C_SIGNAL='@s9s_mb_2u_lib.s9s_mb_2u(sch_1):m_d_cpu1_sa_dqs_dp(9)';
NODE_NAME     U1 AR58
 '@S9S_MB_2U_LIB.S9S_MB_2U(SCH_1):PAGE54_I91@PURE_QUANTA.SOCKET4677_AZIF0045P001C01CS(CHIPS)':
 'DDR3_SA_DQS_DP9': CDS_PINID='DDR3_SA_DQS_DP9';
NODE_NAME     J23 201
 '@S9S_MB_2U_LIB.S9S_MB_2U(SCH_1):PAGE104_I178@PURE_QUANTA.SCONN288_ADR50017P130CC(CHIPS)':
 'DQS9_A_T||TDQS9_A_T': CDS_PINID='\dqs9_a_t||tdqs9_a_t\';
NODE_NAME     J24 201
 '@S9S_MB_2U_LIB.S9S_MB_2U(SCH_1):PAGE105_I181@PURE_QUANTA.SCONN288_ADR50017P087CC(CHIPS)':
 'DQS9_A_T||TDQS9_A_T': CDS_PINID='\dqs9_a_t||tdqs9_a_t\';
NET_NAME
'M_D_CPU1_SA_PAR'
 '@S9S_MB_2U_LIB.S9S_MB_2U(SCH_1):M_D_CPU1_SA_PAR':
 C_SIGNAL='@s9s_mb_2u_lib.s9s_mb_2u(sch_1):m_d_cpu1_sa_par';
NODE_NAME     U1 AP44
 '@S9S_MB_2U_LIB.S9S_MB_2U(SCH_1):PAGE54_I91@PURE_QUANTA.SOCKET4677_AZIF0045P001C01CS(CHIPS)':
 'DDR3_SA_PAR': CDS_PINID='DDR3_SA_PAR';
NODE_NAME     J23 74
 '@S9S_MB_2U_LIB.S9S_MB_2U(SCH_1):PAGE104_I25@PURE_QUANTA.SCONN288_ADR50017P130CC(CHIPS)':
 'PAR_A': CDS_PINID='PAR_A';
NODE_NAME     J24 74
 '@S9S_MB_2U_LIB.S9S_MB_2U(SCH_1):PAGE105_I178@PURE_QUANTA.SCONN288_ADR50017P087CC(CHIPS)':
 'PAR_A': CDS_PINID='PAR_A';
NET_NAME
'M_D_CPU1_SA_RSP<0>'
 '@S9S_MB_2U_LIB.S9S_MB_2U(SCH_1):M_D_CPU1_SA_RSP'<0>:
 C_SIGNAL='@s9s_mb_2u_lib.s9s_mb_2u(sch_1):m_d_cpu1_sa_rsp(0)';
NODE_NAME     U1 AD51
 '@S9S_MB_2U_LIB.S9S_MB_2U(SCH_1):PAGE54_I91@PURE_QUANTA.SOCKET4677_AZIF0045P001C01CS(CHIPS)':
 'DDR3_A_RSP0': CDS_PINID='DDR3_A_RSP0';
NODE_NAME     J23 86
 '@S9S_MB_2U_LIB.S9S_MB_2U(SCH_1):PAGE104_I25@PURE_QUANTA.SCONN288_ADR50017P130CC(CHIPS)':
 'LBD||RSP_A_N': CDS_PINID='\lbd||rsp_a_n\';
NET_NAME
'M_D_CPU1_SA_RSP<1>'
 '@S9S_MB_2U_LIB.S9S_MB_2U(SCH_1):M_D_CPU1_SA_RSP'<1>:
 C_SIGNAL='@s9s_mb_2u_lib.s9s_mb_2u(sch_1):m_d_cpu1_sa_rsp(1)';
NODE_NAME     U1 AC50
 '@S9S_MB_2U_LIB.S9S_MB_2U(SCH_1):PAGE54_I91@PURE_QUANTA.SOCKET4677_AZIF0045P001C01CS(CHIPS)':
 'DDR3_A_RSP1': CDS_PINID='DDR3_A_RSP1';
NODE_NAME     J24 86
 '@S9S_MB_2U_LIB.S9S_MB_2U(SCH_1):PAGE105_I178@PURE_QUANTA.SCONN288_ADR50017P087CC(CHIPS)':
 'LBD||RSP_A_N': CDS_PINID='\lbd||rsp_a_n\';
NET_NAME
'M_D_CPU1_SB_CA<0>'
 '@S9S_MB_2U_LIB.S9S_MB_2U(SCH_1):M_D_CPU1_SB_CA'<0>:
 C_SIGNAL='@s9s_mb_2u_lib.s9s_mb_2u(sch_1):m_d_cpu1_sb_ca(0)';
NODE_NAME     U1 AK44
 '@S9S_MB_2U_LIB.S9S_MB_2U(SCH_1):PAGE54_I91@PURE_QUANTA.SOCKET4677_AZIF0045P001C01CS(CHIPS)':
 'DDR3_SB_CA0': CDS_PINID='DDR3_SB_CA0';
NODE_NAME     J23 76
 '@S9S_MB_2U_LIB.S9S_MB_2U(SCH_1):PAGE104_I25@PURE_QUANTA.SCONN288_ADR50017P130CC(CHIPS)':
 'CA0_B': CDS_PINID='CA0_B';
NODE_NAME     J24 76
 '@S9S_MB_2U_LIB.S9S_MB_2U(SCH_1):PAGE105_I178@PURE_QUANTA.SCONN288_ADR50017P087CC(CHIPS)':
 'CA0_B': CDS_PINID='CA0_B';
NET_NAME
'M_D_CPU1_SB_CA<1>'
 '@S9S_MB_2U_LIB.S9S_MB_2U(SCH_1):M_D_CPU1_SB_CA'<1>:
 C_SIGNAL='@s9s_mb_2u_lib.s9s_mb_2u(sch_1):m_d_cpu1_sb_ca(1)';
NODE_NAME     U1 AL43
 '@S9S_MB_2U_LIB.S9S_MB_2U(SCH_1):PAGE54_I91@PURE_QUANTA.SOCKET4677_AZIF0045P001C01CS(CHIPS)':
 'DDR3_SB_CA1': CDS_PINID='DDR3_SB_CA1';
NODE_NAME     J23 221
 '@S9S_MB_2U_LIB.S9S_MB_2U(SCH_1):PAGE104_I25@PURE_QUANTA.SCONN288_ADR50017P130CC(CHIPS)':
 'CA1_B': CDS_PINID='CA1_B';
NODE_NAME     J24 221
 '@S9S_MB_2U_LIB.S9S_MB_2U(SCH_1):PAGE105_I178@PURE_QUANTA.SCONN288_ADR50017P087CC(CHIPS)':
 'CA1_B': CDS_PINID='CA1_B';
NET_NAME
'M_D_CPU1_SB_CA<2>'
 '@S9S_MB_2U_LIB.S9S_MB_2U(SCH_1):M_D_CPU1_SB_CA'<2>:
 C_SIGNAL='@s9s_mb_2u_lib.s9s_mb_2u(sch_1):m_d_cpu1_sb_ca(2)';
NODE_NAME     U1 AD44
 '@S9S_MB_2U_LIB.S9S_MB_2U(SCH_1):PAGE54_I91@PURE_QUANTA.SOCKET4677_AZIF0045P001C01CS(CHIPS)':
 'DDR3_SB_CA2': CDS_PINID='DDR3_SB_CA2';
NODE_NAME     J23 78
 '@S9S_MB_2U_LIB.S9S_MB_2U(SCH_1):PAGE104_I25@PURE_QUANTA.SCONN288_ADR50017P130CC(CHIPS)':
 'CA2_B': CDS_PINID='CA2_B';
NODE_NAME     J24 78
 '@S9S_MB_2U_LIB.S9S_MB_2U(SCH_1):PAGE105_I178@PURE_QUANTA.SCONN288_ADR50017P087CC(CHIPS)':
 'CA2_B': CDS_PINID='CA2_B';
NET_NAME
'M_D_CPU1_SB_CA<3>'
 '@S9S_MB_2U_LIB.S9S_MB_2U(SCH_1):M_D_CPU1_SB_CA'<3>:
 C_SIGNAL='@s9s_mb_2u_lib.s9s_mb_2u(sch_1):m_d_cpu1_sb_ca(3)';
NODE_NAME     U1 AF44
 '@S9S_MB_2U_LIB.S9S_MB_2U(SCH_1):PAGE54_I91@PURE_QUANTA.SOCKET4677_AZIF0045P001C01CS(CHIPS)':
 'DDR3_SB_CA3': CDS_PINID='DDR3_SB_CA3';
NODE_NAME     J23 223
 '@S9S_MB_2U_LIB.S9S_MB_2U(SCH_1):PAGE104_I25@PURE_QUANTA.SCONN288_ADR50017P130CC(CHIPS)':
 'CA3_B': CDS_PINID='CA3_B';
NODE_NAME     J24 223
 '@S9S_MB_2U_LIB.S9S_MB_2U(SCH_1):PAGE105_I178@PURE_QUANTA.SCONN288_ADR50017P087CC(CHIPS)':
 'CA3_B': CDS_PINID='CA3_B';
NET_NAME
'M_D_CPU1_SB_CA<4>'
 '@S9S_MB_2U_LIB.S9S_MB_2U(SCH_1):M_D_CPU1_SB_CA'<4>:
 C_SIGNAL='@s9s_mb_2u_lib.s9s_mb_2u(sch_1):m_d_cpu1_sb_ca(4)';
NODE_NAME     U1 AC43
 '@S9S_MB_2U_LIB.S9S_MB_2U(SCH_1):PAGE54_I91@PURE_QUANTA.SOCKET4677_AZIF0045P001C01CS(CHIPS)':
 'DDR3_SB_CA4': CDS_PINID='DDR3_SB_CA4';
NODE_NAME     J23 80
 '@S9S_MB_2U_LIB.S9S_MB_2U(SCH_1):PAGE104_I25@PURE_QUANTA.SCONN288_ADR50017P130CC(CHIPS)':
 'CA4_B': CDS_PINID='CA4_B';
NODE_NAME     J24 80
 '@S9S_MB_2U_LIB.S9S_MB_2U(SCH_1):PAGE105_I178@PURE_QUANTA.SCONN288_ADR50017P087CC(CHIPS)':
 'CA4_B': CDS_PINID='CA4_B';
NET_NAME
'M_D_CPU1_SB_CA<5>'
 '@S9S_MB_2U_LIB.S9S_MB_2U(SCH_1):M_D_CPU1_SB_CA'<5>:
 C_SIGNAL='@s9s_mb_2u_lib.s9s_mb_2u(sch_1):m_d_cpu1_sb_ca(5)';
NODE_NAME     U1 AG43
 '@S9S_MB_2U_LIB.S9S_MB_2U(SCH_1):PAGE54_I91@PURE_QUANTA.SOCKET4677_AZIF0045P001C01CS(CHIPS)':
 'DDR3_SB_CA5': CDS_PINID='DDR3_SB_CA5';
NODE_NAME     J23 225
 '@S9S_MB_2U_LIB.S9S_MB_2U(SCH_1):PAGE104_I25@PURE_QUANTA.SCONN288_ADR50017P130CC(CHIPS)':
 'CA5_B': CDS_PINID='CA5_B';
NODE_NAME     J24 225
 '@S9S_MB_2U_LIB.S9S_MB_2U(SCH_1):PAGE105_I178@PURE_QUANTA.SCONN288_ADR50017P087CC(CHIPS)':
 'CA5_B': CDS_PINID='CA5_B';
NET_NAME
'M_D_CPU1_SB_CA<6>'
 '@S9S_MB_2U_LIB.S9S_MB_2U(SCH_1):M_D_CPU1_SB_CA'<6>:
 C_SIGNAL='@s9s_mb_2u_lib.s9s_mb_2u(sch_1):m_d_cpu1_sb_ca(6)';
NODE_NAME     U1 AB42
 '@S9S_MB_2U_LIB.S9S_MB_2U(SCH_1):PAGE54_I91@PURE_QUANTA.SOCKET4677_AZIF0045P001C01CS(CHIPS)':
 'DDR3_SB_CA6': CDS_PINID='DDR3_SB_CA6';
NODE_NAME     J23 82
 '@S9S_MB_2U_LIB.S9S_MB_2U(SCH_1):PAGE104_I25@PURE_QUANTA.SCONN288_ADR50017P130CC(CHIPS)':
 'CA6_B': CDS_PINID='CA6_B';
NODE_NAME     J24 82
 '@S9S_MB_2U_LIB.S9S_MB_2U(SCH_1):PAGE105_I178@PURE_QUANTA.SCONN288_ADR50017P087CC(CHIPS)':
 'CA6_B': CDS_PINID='CA6_B';
NET_NAME
'M_D_CPU1_SB_CB<0>'
 '@S9S_MB_2U_LIB.S9S_MB_2U(SCH_1):M_D_CPU1_SB_CB'<0>:
 C_SIGNAL='@s9s_mb_2u_lib.s9s_mb_2u(sch_1):m_d_cpu1_sb_cb(0)';
NODE_NAME     U1 AK38
 '@S9S_MB_2U_LIB.S9S_MB_2U(SCH_1):PAGE54_I91@PURE_QUANTA.SOCKET4677_AZIF0045P001C01CS(CHIPS)':
 'DDR3_SB_ECC0': CDS_PINID='DDR3_SB_ECC0';
NODE_NAME     J23 96
 '@S9S_MB_2U_LIB.S9S_MB_2U(SCH_1):PAGE104_I25@PURE_QUANTA.SCONN288_ADR50017P130CC(CHIPS)':
 'CB0_B': CDS_PINID='CB0_B';
NODE_NAME     J24 96
 '@S9S_MB_2U_LIB.S9S_MB_2U(SCH_1):PAGE105_I178@PURE_QUANTA.SCONN288_ADR50017P087CC(CHIPS)':
 'CB0_B': CDS_PINID='CB0_B';
NET_NAME
'M_D_CPU1_SB_CB<1>'
 '@S9S_MB_2U_LIB.S9S_MB_2U(SCH_1):M_D_CPU1_SB_CB'<1>:
 C_SIGNAL='@s9s_mb_2u_lib.s9s_mb_2u(sch_1):m_d_cpu1_sb_cb(1)';
NODE_NAME     U1 AL37
 '@S9S_MB_2U_LIB.S9S_MB_2U(SCH_1):PAGE54_I91@PURE_QUANTA.SOCKET4677_AZIF0045P001C01CS(CHIPS)':
 'DDR3_SB_ECC1': CDS_PINID='DDR3_SB_ECC1';
NODE_NAME     J23 98
 '@S9S_MB_2U_LIB.S9S_MB_2U(SCH_1):PAGE104_I25@PURE_QUANTA.SCONN288_ADR50017P130CC(CHIPS)':
 'CB1_B': CDS_PINID='CB1_B';
NODE_NAME     J24 98
 '@S9S_MB_2U_LIB.S9S_MB_2U(SCH_1):PAGE105_I178@PURE_QUANTA.SCONN288_ADR50017P087CC(CHIPS)':
 'CB1_B': CDS_PINID='CB1_B';
NET_NAME
'M_D_CPU1_SB_CB<2>'
 '@S9S_MB_2U_LIB.S9S_MB_2U(SCH_1):M_D_CPU1_SB_CB'<2>:
 C_SIGNAL='@s9s_mb_2u_lib.s9s_mb_2u(sch_1):m_d_cpu1_sb_cb(2)';
NODE_NAME     U1 AP38
 '@S9S_MB_2U_LIB.S9S_MB_2U(SCH_1):PAGE54_I91@PURE_QUANTA.SOCKET4677_AZIF0045P001C01CS(CHIPS)':
 'DDR3_SB_ECC2': CDS_PINID='DDR3_SB_ECC2';
NODE_NAME     J23 241
 '@S9S_MB_2U_LIB.S9S_MB_2U(SCH_1):PAGE104_I25@PURE_QUANTA.SCONN288_ADR50017P130CC(CHIPS)':
 'CB2_B': CDS_PINID='CB2_B';
NODE_NAME     J24 241
 '@S9S_MB_2U_LIB.S9S_MB_2U(SCH_1):PAGE105_I178@PURE_QUANTA.SCONN288_ADR50017P087CC(CHIPS)':
 'CB2_B': CDS_PINID='CB2_B';
NET_NAME
'M_D_CPU1_SB_CB<3>'
 '@S9S_MB_2U_LIB.S9S_MB_2U(SCH_1):M_D_CPU1_SB_CB'<3>:
 C_SIGNAL='@s9s_mb_2u_lib.s9s_mb_2u(sch_1):m_d_cpu1_sb_cb(3)';
NODE_NAME     U1 AN37
 '@S9S_MB_2U_LIB.S9S_MB_2U(SCH_1):PAGE54_I91@PURE_QUANTA.SOCKET4677_AZIF0045P001C01CS(CHIPS)':
 'DDR3_SB_ECC3': CDS_PINID='DDR3_SB_ECC3';
NODE_NAME     J23 243
 '@S9S_MB_2U_LIB.S9S_MB_2U(SCH_1):PAGE104_I25@PURE_QUANTA.SCONN288_ADR50017P130CC(CHIPS)':
 'CB3_B': CDS_PINID='CB3_B';
NODE_NAME     J24 243
 '@S9S_MB_2U_LIB.S9S_MB_2U(SCH_1):PAGE105_I178@PURE_QUANTA.SCONN288_ADR50017P087CC(CHIPS)':
 'CB3_B': CDS_PINID='CB3_B';
NET_NAME
'M_D_CPU1_SB_CB<4>'
 '@S9S_MB_2U_LIB.S9S_MB_2U(SCH_1):M_D_CPU1_SB_CB'<4>:
 C_SIGNAL='@s9s_mb_2u_lib.s9s_mb_2u(sch_1):m_d_cpu1_sb_cb(4)';
NODE_NAME     U1 AL41
 '@S9S_MB_2U_LIB.S9S_MB_2U(SCH_1):PAGE54_I91@PURE_QUANTA.SOCKET4677_AZIF0045P001C01CS(CHIPS)':
 'DDR3_SB_ECC4': CDS_PINID='DDR3_SB_ECC4';
NODE_NAME     J23 89
 '@S9S_MB_2U_LIB.S9S_MB_2U(SCH_1):PAGE104_I25@PURE_QUANTA.SCONN288_ADR50017P130CC(CHIPS)':
 'CB4_B': CDS_PINID='CB4_B';
NODE_NAME     J24 89
 '@S9S_MB_2U_LIB.S9S_MB_2U(SCH_1):PAGE105_I178@PURE_QUANTA.SCONN288_ADR50017P087CC(CHIPS)':
 'CB4_B': CDS_PINID='CB4_B';
NET_NAME
'M_D_CPU1_SB_CB<5>'
 '@S9S_MB_2U_LIB.S9S_MB_2U(SCH_1):M_D_CPU1_SB_CB'<5>:
 C_SIGNAL='@s9s_mb_2u_lib.s9s_mb_2u(sch_1):m_d_cpu1_sb_cb(5)';
NODE_NAME     U1 AK40
 '@S9S_MB_2U_LIB.S9S_MB_2U(SCH_1):PAGE54_I91@PURE_QUANTA.SOCKET4677_AZIF0045P001C01CS(CHIPS)':
 'DDR3_SB_ECC5': CDS_PINID='DDR3_SB_ECC5';
NODE_NAME     J23 91
 '@S9S_MB_2U_LIB.S9S_MB_2U(SCH_1):PAGE104_I25@PURE_QUANTA.SCONN288_ADR50017P130CC(CHIPS)':
 'CB5_B': CDS_PINID='CB5_B';
NODE_NAME     J24 91
 '@S9S_MB_2U_LIB.S9S_MB_2U(SCH_1):PAGE105_I178@PURE_QUANTA.SCONN288_ADR50017P087CC(CHIPS)':
 'CB5_B': CDS_PINID='CB5_B';
NET_NAME
'M_D_CPU1_SB_CB<6>'
 '@S9S_MB_2U_LIB.S9S_MB_2U(SCH_1):M_D_CPU1_SB_CB'<6>:
 C_SIGNAL='@s9s_mb_2u_lib.s9s_mb_2u(sch_1):m_d_cpu1_sb_cb(6)';
NODE_NAME     U1 AN41
 '@S9S_MB_2U_LIB.S9S_MB_2U(SCH_1):PAGE54_I91@PURE_QUANTA.SOCKET4677_AZIF0045P001C01CS(CHIPS)':
 'DDR3_SB_ECC6': CDS_PINID='DDR3_SB_ECC6';
NODE_NAME     J23 234
 '@S9S_MB_2U_LIB.S9S_MB_2U(SCH_1):PAGE104_I25@PURE_QUANTA.SCONN288_ADR50017P130CC(CHIPS)':
 'CB6_B': CDS_PINID='CB6_B';
NODE_NAME     J24 234
 '@S9S_MB_2U_LIB.S9S_MB_2U(SCH_1):PAGE105_I178@PURE_QUANTA.SCONN288_ADR50017P087CC(CHIPS)':
 'CB6_B': CDS_PINID='CB6_B';
NET_NAME
'M_D_CPU1_SB_CB<7>'
 '@S9S_MB_2U_LIB.S9S_MB_2U(SCH_1):M_D_CPU1_SB_CB'<7>:
 C_SIGNAL='@s9s_mb_2u_lib.s9s_mb_2u(sch_1):m_d_cpu1_sb_cb(7)';
NODE_NAME     U1 AP40
 '@S9S_MB_2U_LIB.S9S_MB_2U(SCH_1):PAGE54_I91@PURE_QUANTA.SOCKET4677_AZIF0045P001C01CS(CHIPS)':
 'DDR3_SB_ECC7': CDS_PINID='DDR3_SB_ECC7';
NODE_NAME     J23 236
 '@S9S_MB_2U_LIB.S9S_MB_2U(SCH_1):PAGE104_I25@PURE_QUANTA.SCONN288_ADR50017P130CC(CHIPS)':
 'CB7_B': CDS_PINID='CB7_B';
NODE_NAME     J24 236
 '@S9S_MB_2U_LIB.S9S_MB_2U(SCH_1):PAGE105_I178@PURE_QUANTA.SCONN288_ADR50017P087CC(CHIPS)':
 'CB7_B': CDS_PINID='CB7_B';
NET_NAME
'M_D_CPU1_SB_CS_N<0>'
 '@S9S_MB_2U_LIB.S9S_MB_2U(SCH_1):M_D_CPU1_SB_CS_N'<0>:
 C_SIGNAL='@s9s_mb_2u_lib.s9s_mb_2u(sch_1):m_d_cpu1_sb_cs_n(0)';
NODE_NAME     U1 AC41
 '@S9S_MB_2U_LIB.S9S_MB_2U(SCH_1):PAGE54_I91@PURE_QUANTA.SOCKET4677_AZIF0045P001C01CS(CHIPS)':
 'DDR3_SB_CS_N0': CDS_PINID='DDR3_SB_CS_N0';
NODE_NAME     J23 84
 '@S9S_MB_2U_LIB.S9S_MB_2U(SCH_1):PAGE104_I25@PURE_QUANTA.SCONN288_ADR50017P130CC(CHIPS)':
 'CS0_B_N': CDS_PINID='CS0_B_N';
NET_NAME
'M_D_CPU1_SB_CS_N<1>'
 '@S9S_MB_2U_LIB.S9S_MB_2U(SCH_1):M_D_CPU1_SB_CS_N'<1>:
 C_SIGNAL='@s9s_mb_2u_lib.s9s_mb_2u(sch_1):m_d_cpu1_sb_cs_n(1)';
NODE_NAME     U1 AG41
 '@S9S_MB_2U_LIB.S9S_MB_2U(SCH_1):PAGE54_I91@PURE_QUANTA.SOCKET4677_AZIF0045P001C01CS(CHIPS)':
 'DDR3_SB_CS_N1': CDS_PINID='DDR3_SB_CS_N1';
NODE_NAME     J23 229
 '@S9S_MB_2U_LIB.S9S_MB_2U(SCH_1):PAGE104_I25@PURE_QUANTA.SCONN288_ADR50017P130CC(CHIPS)':
 'CS1_B_N': CDS_PINID='CS1_B_N';
NET_NAME
'M_D_CPU1_SB_CS_N<2>'
 '@S9S_MB_2U_LIB.S9S_MB_2U(SCH_1):M_D_CPU1_SB_CS_N'<2>:
 C_SIGNAL='@s9s_mb_2u_lib.s9s_mb_2u(sch_1):m_d_cpu1_sb_cs_n(2)';
NODE_NAME     U1 AF40
 '@S9S_MB_2U_LIB.S9S_MB_2U(SCH_1):PAGE54_I91@PURE_QUANTA.SOCKET4677_AZIF0045P001C01CS(CHIPS)':
 'DDR3_SB_CS_N2': CDS_PINID='DDR3_SB_CS_N2';
NODE_NAME     J24 84
 '@S9S_MB_2U_LIB.S9S_MB_2U(SCH_1):PAGE105_I178@PURE_QUANTA.SCONN288_ADR50017P087CC(CHIPS)':
 'CS0_B_N': CDS_PINID='CS0_B_N';
NET_NAME
'M_D_CPU1_SB_CS_N<3>'
 '@S9S_MB_2U_LIB.S9S_MB_2U(SCH_1):M_D_CPU1_SB_CS_N'<3>:
 C_SIGNAL='@s9s_mb_2u_lib.s9s_mb_2u(sch_1):m_d_cpu1_sb_cs_n(3)';
NODE_NAME     U1 AD40
 '@S9S_MB_2U_LIB.S9S_MB_2U(SCH_1):PAGE54_I91@PURE_QUANTA.SOCKET4677_AZIF0045P001C01CS(CHIPS)':
 'DDR3_SB_CS_N3': CDS_PINID='DDR3_SB_CS_N3';
NODE_NAME     J24 229
 '@S9S_MB_2U_LIB.S9S_MB_2U(SCH_1):PAGE105_I178@PURE_QUANTA.SCONN288_ADR50017P087CC(CHIPS)':
 'CS1_B_N': CDS_PINID='CS1_B_N';
NET_NAME
'M_D_CPU1_SB_DQ<0>'
 '@S9S_MB_2U_LIB.S9S_MB_2U(SCH_1):M_D_CPU1_SB_DQ'<0>:
 C_SIGNAL='@s9s_mb_2u_lib.s9s_mb_2u(sch_1):m_d_cpu1_sb_dq(0)';
NODE_NAME     U1 AL35
 '@S9S_MB_2U_LIB.S9S_MB_2U(SCH_1):PAGE54_I91@PURE_QUANTA.SOCKET4677_AZIF0045P001C01CS(CHIPS)':
 'DDR3_SB_DQ0': CDS_PINID='DDR3_SB_DQ0';
NODE_NAME     J23 100
 '@S9S_MB_2U_LIB.S9S_MB_2U(SCH_1):PAGE104_I25@PURE_QUANTA.SCONN288_ADR50017P130CC(CHIPS)':
 'DQ0_B': CDS_PINID='DQ0_B';
NODE_NAME     J24 100
 '@S9S_MB_2U_LIB.S9S_MB_2U(SCH_1):PAGE105_I178@PURE_QUANTA.SCONN288_ADR50017P087CC(CHIPS)':
 'DQ0_B': CDS_PINID='DQ0_B';
NET_NAME
'M_D_CPU1_SB_DQ<10>'
 '@S9S_MB_2U_LIB.S9S_MB_2U(SCH_1):M_D_CPU1_SB_DQ'<10>:
 C_SIGNAL='@s9s_mb_2u_lib.s9s_mb_2u(sch_1):m_d_cpu1_sb_dq(10)';
NODE_NAME     U1 AN29
 '@S9S_MB_2U_LIB.S9S_MB_2U(SCH_1):PAGE54_I91@PURE_QUANTA.SOCKET4677_AZIF0045P001C01CS(CHIPS)':
 'DDR3_SB_DQ10': CDS_PINID='DDR3_SB_DQ10';
NODE_NAME     J23 256
 '@S9S_MB_2U_LIB.S9S_MB_2U(SCH_1):PAGE104_I25@PURE_QUANTA.SCONN288_ADR50017P130CC(CHIPS)':
 'DQ10_B': CDS_PINID='DQ10_B';
NODE_NAME     J24 256
 '@S9S_MB_2U_LIB.S9S_MB_2U(SCH_1):PAGE105_I178@PURE_QUANTA.SCONN288_ADR50017P087CC(CHIPS)':
 'DQ10_B': CDS_PINID='DQ10_B';
NET_NAME
'M_D_CPU1_SB_DQ<11>'
 '@S9S_MB_2U_LIB.S9S_MB_2U(SCH_1):M_D_CPU1_SB_DQ'<11>:
 C_SIGNAL='@s9s_mb_2u_lib.s9s_mb_2u(sch_1):m_d_cpu1_sb_dq(11)';
NODE_NAME     U1 AP28
 '@S9S_MB_2U_LIB.S9S_MB_2U(SCH_1):PAGE54_I91@PURE_QUANTA.SOCKET4677_AZIF0045P001C01CS(CHIPS)':
 'DDR3_SB_DQ11': CDS_PINID='DDR3_SB_DQ11';
NODE_NAME     J23 258
 '@S9S_MB_2U_LIB.S9S_MB_2U(SCH_1):PAGE104_I25@PURE_QUANTA.SCONN288_ADR50017P130CC(CHIPS)':
 'DQ11_B': CDS_PINID='DQ11_B';
NODE_NAME     J24 258
 '@S9S_MB_2U_LIB.S9S_MB_2U(SCH_1):PAGE105_I178@PURE_QUANTA.SCONN288_ADR50017P087CC(CHIPS)':
 'DQ11_B': CDS_PINID='DQ11_B';
NET_NAME
'M_D_CPU1_SB_DQ<12>'
 '@S9S_MB_2U_LIB.S9S_MB_2U(SCH_1):M_D_CPU1_SB_DQ'<12>:
 C_SIGNAL='@s9s_mb_2u_lib.s9s_mb_2u(sch_1):m_d_cpu1_sb_dq(12)';
NODE_NAME     U1 AK26
 '@S9S_MB_2U_LIB.S9S_MB_2U(SCH_1):PAGE54_I91@PURE_QUANTA.SOCKET4677_AZIF0045P001C01CS(CHIPS)':
 'DDR3_SB_DQ12': CDS_PINID='DDR3_SB_DQ12';
NODE_NAME     J23 118
 '@S9S_MB_2U_LIB.S9S_MB_2U(SCH_1):PAGE104_I25@PURE_QUANTA.SCONN288_ADR50017P130CC(CHIPS)':
 'DQ12_B': CDS_PINID='DQ12_B';
NODE_NAME     J24 118
 '@S9S_MB_2U_LIB.S9S_MB_2U(SCH_1):PAGE105_I178@PURE_QUANTA.SCONN288_ADR50017P087CC(CHIPS)':
 'DQ12_B': CDS_PINID='DQ12_B';
NET_NAME
'M_D_CPU1_SB_DQ<13>'
 '@S9S_MB_2U_LIB.S9S_MB_2U(SCH_1):M_D_CPU1_SB_DQ'<13>:
 C_SIGNAL='@s9s_mb_2u_lib.s9s_mb_2u(sch_1):m_d_cpu1_sb_dq(13)';
NODE_NAME     U1 AL25
 '@S9S_MB_2U_LIB.S9S_MB_2U(SCH_1):PAGE54_I91@PURE_QUANTA.SOCKET4677_AZIF0045P001C01CS(CHIPS)':
 'DDR3_SB_DQ13': CDS_PINID='DDR3_SB_DQ13';
NODE_NAME     J23 120
 '@S9S_MB_2U_LIB.S9S_MB_2U(SCH_1):PAGE104_I25@PURE_QUANTA.SCONN288_ADR50017P130CC(CHIPS)':
 'DQ13_B': CDS_PINID='DQ13_B';
NODE_NAME     J24 120
 '@S9S_MB_2U_LIB.S9S_MB_2U(SCH_1):PAGE105_I178@PURE_QUANTA.SCONN288_ADR50017P087CC(CHIPS)':
 'DQ13_B': CDS_PINID='DQ13_B';
NET_NAME
'M_D_CPU1_SB_DQ<14>'
 '@S9S_MB_2U_LIB.S9S_MB_2U(SCH_1):M_D_CPU1_SB_DQ'<14>:
 C_SIGNAL='@s9s_mb_2u_lib.s9s_mb_2u(sch_1):m_d_cpu1_sb_dq(14)';
NODE_NAME     U1 AP26
 '@S9S_MB_2U_LIB.S9S_MB_2U(SCH_1):PAGE54_I91@PURE_QUANTA.SOCKET4677_AZIF0045P001C01CS(CHIPS)':
 'DDR3_SB_DQ14': CDS_PINID='DDR3_SB_DQ14';
NODE_NAME     J23 263
 '@S9S_MB_2U_LIB.S9S_MB_2U(SCH_1):PAGE104_I25@PURE_QUANTA.SCONN288_ADR50017P130CC(CHIPS)':
 'DQ14_B': CDS_PINID='DQ14_B';
NODE_NAME     J24 263
 '@S9S_MB_2U_LIB.S9S_MB_2U(SCH_1):PAGE105_I178@PURE_QUANTA.SCONN288_ADR50017P087CC(CHIPS)':
 'DQ14_B': CDS_PINID='DQ14_B';
NET_NAME
'M_D_CPU1_SB_DQ<15>'
 '@S9S_MB_2U_LIB.S9S_MB_2U(SCH_1):M_D_CPU1_SB_DQ'<15>:
 C_SIGNAL='@s9s_mb_2u_lib.s9s_mb_2u(sch_1):m_d_cpu1_sb_dq(15)';
NODE_NAME     U1 AN25
 '@S9S_MB_2U_LIB.S9S_MB_2U(SCH_1):PAGE54_I91@PURE_QUANTA.SOCKET4677_AZIF0045P001C01CS(CHIPS)':
 'DDR3_SB_DQ15': CDS_PINID='DDR3_SB_DQ15';
NODE_NAME     J23 265
 '@S9S_MB_2U_LIB.S9S_MB_2U(SCH_1):PAGE104_I25@PURE_QUANTA.SCONN288_ADR50017P130CC(CHIPS)':
 'DQ15_B': CDS_PINID='DQ15_B';
NODE_NAME     J24 265
 '@S9S_MB_2U_LIB.S9S_MB_2U(SCH_1):PAGE105_I178@PURE_QUANTA.SCONN288_ADR50017P087CC(CHIPS)':
 'DQ15_B': CDS_PINID='DQ15_B';
NET_NAME
'M_D_CPU1_SB_DQ<16>'
 '@S9S_MB_2U_LIB.S9S_MB_2U(SCH_1):M_D_CPU1_SB_DQ'<16>:
 C_SIGNAL='@s9s_mb_2u_lib.s9s_mb_2u(sch_1):m_d_cpu1_sb_dq(16)';
NODE_NAME     U1 AD26
 '@S9S_MB_2U_LIB.S9S_MB_2U(SCH_1):PAGE54_I91@PURE_QUANTA.SOCKET4677_AZIF0045P001C01CS(CHIPS)':
 'DDR3_SB_DQ16': CDS_PINID='DDR3_SB_DQ16';
NODE_NAME     J23 122
 '@S9S_MB_2U_LIB.S9S_MB_2U(SCH_1):PAGE104_I25@PURE_QUANTA.SCONN288_ADR50017P130CC(CHIPS)':
 'DQ16_B': CDS_PINID='DQ16_B';
NODE_NAME     J24 122
 '@S9S_MB_2U_LIB.S9S_MB_2U(SCH_1):PAGE105_I178@PURE_QUANTA.SCONN288_ADR50017P087CC(CHIPS)':
 'DQ16_B': CDS_PINID='DQ16_B';
NET_NAME
'M_D_CPU1_SB_DQ<17>'
 '@S9S_MB_2U_LIB.S9S_MB_2U(SCH_1):M_D_CPU1_SB_DQ'<17>:
 C_SIGNAL='@s9s_mb_2u_lib.s9s_mb_2u(sch_1):m_d_cpu1_sb_dq(17)';
NODE_NAME     U1 AC25
 '@S9S_MB_2U_LIB.S9S_MB_2U(SCH_1):PAGE54_I91@PURE_QUANTA.SOCKET4677_AZIF0045P001C01CS(CHIPS)':
 'DDR3_SB_DQ17': CDS_PINID='DDR3_SB_DQ17';
NODE_NAME     J23 124
 '@S9S_MB_2U_LIB.S9S_MB_2U(SCH_1):PAGE104_I25@PURE_QUANTA.SCONN288_ADR50017P130CC(CHIPS)':
 'DQ17_B': CDS_PINID='DQ17_B';
NODE_NAME     J24 124
 '@S9S_MB_2U_LIB.S9S_MB_2U(SCH_1):PAGE105_I178@PURE_QUANTA.SCONN288_ADR50017P087CC(CHIPS)':
 'DQ17_B': CDS_PINID='DQ17_B';
NET_NAME
'M_D_CPU1_SB_DQ<18>'
 '@S9S_MB_2U_LIB.S9S_MB_2U(SCH_1):M_D_CPU1_SB_DQ'<18>:
 C_SIGNAL='@s9s_mb_2u_lib.s9s_mb_2u(sch_1):m_d_cpu1_sb_dq(18)';
NODE_NAME     U1 AF26
 '@S9S_MB_2U_LIB.S9S_MB_2U(SCH_1):PAGE54_I91@PURE_QUANTA.SOCKET4677_AZIF0045P001C01CS(CHIPS)':
 'DDR3_SB_DQ18': CDS_PINID='DDR3_SB_DQ18';
NODE_NAME     J23 267
 '@S9S_MB_2U_LIB.S9S_MB_2U(SCH_1):PAGE104_I25@PURE_QUANTA.SCONN288_ADR50017P130CC(CHIPS)':
 'DQ18_B': CDS_PINID='DQ18_B';
NODE_NAME     J24 267
 '@S9S_MB_2U_LIB.S9S_MB_2U(SCH_1):PAGE105_I178@PURE_QUANTA.SCONN288_ADR50017P087CC(CHIPS)':
 'DQ18_B': CDS_PINID='DQ18_B';
NET_NAME
'M_D_CPU1_SB_DQ<19>'
 '@S9S_MB_2U_LIB.S9S_MB_2U(SCH_1):M_D_CPU1_SB_DQ'<19>:
 C_SIGNAL='@s9s_mb_2u_lib.s9s_mb_2u(sch_1):m_d_cpu1_sb_dq(19)';
NODE_NAME     U1 AG25
 '@S9S_MB_2U_LIB.S9S_MB_2U(SCH_1):PAGE54_I91@PURE_QUANTA.SOCKET4677_AZIF0045P001C01CS(CHIPS)':
 'DDR3_SB_DQ19': CDS_PINID='DDR3_SB_DQ19';
NODE_NAME     J23 269
 '@S9S_MB_2U_LIB.S9S_MB_2U(SCH_1):PAGE104_I25@PURE_QUANTA.SCONN288_ADR50017P130CC(CHIPS)':
 'DQ19_B': CDS_PINID='DQ19_B';
NODE_NAME     J24 269
 '@S9S_MB_2U_LIB.S9S_MB_2U(SCH_1):PAGE105_I178@PURE_QUANTA.SCONN288_ADR50017P087CC(CHIPS)':
 'DQ19_B': CDS_PINID='DQ19_B';
NET_NAME
'M_D_CPU1_SB_DQ<1>'
 '@S9S_MB_2U_LIB.S9S_MB_2U(SCH_1):M_D_CPU1_SB_DQ'<1>:
 C_SIGNAL='@s9s_mb_2u_lib.s9s_mb_2u(sch_1):m_d_cpu1_sb_dq(1)';
NODE_NAME     U1 AK34
 '@S9S_MB_2U_LIB.S9S_MB_2U(SCH_1):PAGE54_I91@PURE_QUANTA.SOCKET4677_AZIF0045P001C01CS(CHIPS)':
 'DDR3_SB_DQ1': CDS_PINID='DDR3_SB_DQ1';
NODE_NAME     J23 102
 '@S9S_MB_2U_LIB.S9S_MB_2U(SCH_1):PAGE104_I25@PURE_QUANTA.SCONN288_ADR50017P130CC(CHIPS)':
 'DQ1_B': CDS_PINID='DQ1_B';
NODE_NAME     J24 102
 '@S9S_MB_2U_LIB.S9S_MB_2U(SCH_1):PAGE105_I178@PURE_QUANTA.SCONN288_ADR50017P087CC(CHIPS)':
 'DQ1_B': CDS_PINID='DQ1_B';
NET_NAME
'M_D_CPU1_SB_DQ<20>'
 '@S9S_MB_2U_LIB.S9S_MB_2U(SCH_1):M_D_CPU1_SB_DQ'<20>:
 C_SIGNAL='@s9s_mb_2u_lib.s9s_mb_2u(sch_1):m_d_cpu1_sb_dq(20)';
NODE_NAME     U1 AC23
 '@S9S_MB_2U_LIB.S9S_MB_2U(SCH_1):PAGE54_I91@PURE_QUANTA.SOCKET4677_AZIF0045P001C01CS(CHIPS)':
 'DDR3_SB_DQ20': CDS_PINID='DDR3_SB_DQ20';
NODE_NAME     J23 129
 '@S9S_MB_2U_LIB.S9S_MB_2U(SCH_1):PAGE104_I25@PURE_QUANTA.SCONN288_ADR50017P130CC(CHIPS)':
 'DQ20_B': CDS_PINID='DQ20_B';
NODE_NAME     J24 129
 '@S9S_MB_2U_LIB.S9S_MB_2U(SCH_1):PAGE105_I178@PURE_QUANTA.SCONN288_ADR50017P087CC(CHIPS)':
 'DQ20_B': CDS_PINID='DQ20_B';
NET_NAME
'M_D_CPU1_SB_DQ<21>'
 '@S9S_MB_2U_LIB.S9S_MB_2U(SCH_1):M_D_CPU1_SB_DQ'<21>:
 C_SIGNAL='@s9s_mb_2u_lib.s9s_mb_2u(sch_1):m_d_cpu1_sb_dq(21)';
NODE_NAME     U1 AD22
 '@S9S_MB_2U_LIB.S9S_MB_2U(SCH_1):PAGE54_I91@PURE_QUANTA.SOCKET4677_AZIF0045P001C01CS(CHIPS)':
 'DDR3_SB_DQ21': CDS_PINID='DDR3_SB_DQ21';
NODE_NAME     J23 131
 '@S9S_MB_2U_LIB.S9S_MB_2U(SCH_1):PAGE104_I25@PURE_QUANTA.SCONN288_ADR50017P130CC(CHIPS)':
 'DQ21_B': CDS_PINID='DQ21_B';
NODE_NAME     J24 131
 '@S9S_MB_2U_LIB.S9S_MB_2U(SCH_1):PAGE105_I178@PURE_QUANTA.SCONN288_ADR50017P087CC(CHIPS)':
 'DQ21_B': CDS_PINID='DQ21_B';
NET_NAME
'M_D_CPU1_SB_DQ<22>'
 '@S9S_MB_2U_LIB.S9S_MB_2U(SCH_1):M_D_CPU1_SB_DQ'<22>:
 C_SIGNAL='@s9s_mb_2u_lib.s9s_mb_2u(sch_1):m_d_cpu1_sb_dq(22)';
NODE_NAME     U1 AG23
 '@S9S_MB_2U_LIB.S9S_MB_2U(SCH_1):PAGE54_I91@PURE_QUANTA.SOCKET4677_AZIF0045P001C01CS(CHIPS)':
 'DDR3_SB_DQ22': CDS_PINID='DDR3_SB_DQ22';
NODE_NAME     J23 274
 '@S9S_MB_2U_LIB.S9S_MB_2U(SCH_1):PAGE104_I25@PURE_QUANTA.SCONN288_ADR50017P130CC(CHIPS)':
 'DQ22_B': CDS_PINID='DQ22_B';
NODE_NAME     J24 274
 '@S9S_MB_2U_LIB.S9S_MB_2U(SCH_1):PAGE105_I178@PURE_QUANTA.SCONN288_ADR50017P087CC(CHIPS)':
 'DQ22_B': CDS_PINID='DQ22_B';
NET_NAME
'M_D_CPU1_SB_DQ<23>'
 '@S9S_MB_2U_LIB.S9S_MB_2U(SCH_1):M_D_CPU1_SB_DQ'<23>:
 C_SIGNAL='@s9s_mb_2u_lib.s9s_mb_2u(sch_1):m_d_cpu1_sb_dq(23)';
NODE_NAME     U1 AF22
 '@S9S_MB_2U_LIB.S9S_MB_2U(SCH_1):PAGE54_I91@PURE_QUANTA.SOCKET4677_AZIF0045P001C01CS(CHIPS)':
 'DDR3_SB_DQ23': CDS_PINID='DDR3_SB_DQ23';
NODE_NAME     J23 276
 '@S9S_MB_2U_LIB.S9S_MB_2U(SCH_1):PAGE104_I25@PURE_QUANTA.SCONN288_ADR50017P130CC(CHIPS)':
 'DQ23_B': CDS_PINID='DQ23_B';
NODE_NAME     J24 276
 '@S9S_MB_2U_LIB.S9S_MB_2U(SCH_1):PAGE105_I178@PURE_QUANTA.SCONN288_ADR50017P087CC(CHIPS)':
 'DQ23_B': CDS_PINID='DQ23_B';
NET_NAME
'M_D_CPU1_SB_DQ<24>'
 '@S9S_MB_2U_LIB.S9S_MB_2U(SCH_1):M_D_CPU1_SB_DQ'<24>:
 C_SIGNAL='@s9s_mb_2u_lib.s9s_mb_2u(sch_1):m_d_cpu1_sb_dq(24)';
NODE_NAME     U1 AL23
 '@S9S_MB_2U_LIB.S9S_MB_2U(SCH_1):PAGE54_I91@PURE_QUANTA.SOCKET4677_AZIF0045P001C01CS(CHIPS)':
 'DDR3_SB_DQ24': CDS_PINID='DDR3_SB_DQ24';
NODE_NAME     J23 133
 '@S9S_MB_2U_LIB.S9S_MB_2U(SCH_1):PAGE104_I25@PURE_QUANTA.SCONN288_ADR50017P130CC(CHIPS)':
 'DQ24_B': CDS_PINID='DQ24_B';
NODE_NAME     J24 133
 '@S9S_MB_2U_LIB.S9S_MB_2U(SCH_1):PAGE105_I178@PURE_QUANTA.SCONN288_ADR50017P087CC(CHIPS)':
 'DQ24_B': CDS_PINID='DQ24_B';
NET_NAME
'M_D_CPU1_SB_DQ<25>'
 '@S9S_MB_2U_LIB.S9S_MB_2U(SCH_1):M_D_CPU1_SB_DQ'<25>:
 C_SIGNAL='@s9s_mb_2u_lib.s9s_mb_2u(sch_1):m_d_cpu1_sb_dq(25)';
NODE_NAME     U1 AK22
 '@S9S_MB_2U_LIB.S9S_MB_2U(SCH_1):PAGE54_I91@PURE_QUANTA.SOCKET4677_AZIF0045P001C01CS(CHIPS)':
 'DDR3_SB_DQ25': CDS_PINID='DDR3_SB_DQ25';
NODE_NAME     J23 135
 '@S9S_MB_2U_LIB.S9S_MB_2U(SCH_1):PAGE104_I25@PURE_QUANTA.SCONN288_ADR50017P130CC(CHIPS)':
 'DQ25_B': CDS_PINID='DQ25_B';
NODE_NAME     J24 135
 '@S9S_MB_2U_LIB.S9S_MB_2U(SCH_1):PAGE105_I178@PURE_QUANTA.SCONN288_ADR50017P087CC(CHIPS)':
 'DQ25_B': CDS_PINID='DQ25_B';
NET_NAME
'M_D_CPU1_SB_DQ<26>'
 '@S9S_MB_2U_LIB.S9S_MB_2U(SCH_1):M_D_CPU1_SB_DQ'<26>:
 C_SIGNAL='@s9s_mb_2u_lib.s9s_mb_2u(sch_1):m_d_cpu1_sb_dq(26)';
NODE_NAME     U1 AN23
 '@S9S_MB_2U_LIB.S9S_MB_2U(SCH_1):PAGE54_I91@PURE_QUANTA.SOCKET4677_AZIF0045P001C01CS(CHIPS)':
 'DDR3_SB_DQ26': CDS_PINID='DDR3_SB_DQ26';
NODE_NAME     J23 278
 '@S9S_MB_2U_LIB.S9S_MB_2U(SCH_1):PAGE104_I25@PURE_QUANTA.SCONN288_ADR50017P130CC(CHIPS)':
 'DQ26_B': CDS_PINID='DQ26_B';
NODE_NAME     J24 278
 '@S9S_MB_2U_LIB.S9S_MB_2U(SCH_1):PAGE105_I178@PURE_QUANTA.SCONN288_ADR50017P087CC(CHIPS)':
 'DQ26_B': CDS_PINID='DQ26_B';
NET_NAME
'M_D_CPU1_SB_DQ<27>'
 '@S9S_MB_2U_LIB.S9S_MB_2U(SCH_1):M_D_CPU1_SB_DQ'<27>:
 C_SIGNAL='@s9s_mb_2u_lib.s9s_mb_2u(sch_1):m_d_cpu1_sb_dq(27)';
NODE_NAME     U1 AP22
 '@S9S_MB_2U_LIB.S9S_MB_2U(SCH_1):PAGE54_I91@PURE_QUANTA.SOCKET4677_AZIF0045P001C01CS(CHIPS)':
 'DDR3_SB_DQ27': CDS_PINID='DDR3_SB_DQ27';
NODE_NAME     J23 280
 '@S9S_MB_2U_LIB.S9S_MB_2U(SCH_1):PAGE104_I25@PURE_QUANTA.SCONN288_ADR50017P130CC(CHIPS)':
 'DQ27_B': CDS_PINID='DQ27_B';
NODE_NAME     J24 280
 '@S9S_MB_2U_LIB.S9S_MB_2U(SCH_1):PAGE105_I178@PURE_QUANTA.SCONN288_ADR50017P087CC(CHIPS)':
 'DQ27_B': CDS_PINID='DQ27_B';
NET_NAME
'M_D_CPU1_SB_DQ<28>'
 '@S9S_MB_2U_LIB.S9S_MB_2U(SCH_1):M_D_CPU1_SB_DQ'<28>:
 C_SIGNAL='@s9s_mb_2u_lib.s9s_mb_2u(sch_1):m_d_cpu1_sb_dq(28)';
NODE_NAME     U1 AK20
 '@S9S_MB_2U_LIB.S9S_MB_2U(SCH_1):PAGE54_I91@PURE_QUANTA.SOCKET4677_AZIF0045P001C01CS(CHIPS)':
 'DDR3_SB_DQ28': CDS_PINID='DDR3_SB_DQ28';
NODE_NAME     J23 140
 '@S9S_MB_2U_LIB.S9S_MB_2U(SCH_1):PAGE104_I25@PURE_QUANTA.SCONN288_ADR50017P130CC(CHIPS)':
 'DQ28_B': CDS_PINID='DQ28_B';
NODE_NAME     J24 140
 '@S9S_MB_2U_LIB.S9S_MB_2U(SCH_1):PAGE105_I178@PURE_QUANTA.SCONN288_ADR50017P087CC(CHIPS)':
 'DQ28_B': CDS_PINID='DQ28_B';
NET_NAME
'M_D_CPU1_SB_DQ<29>'
 '@S9S_MB_2U_LIB.S9S_MB_2U(SCH_1):M_D_CPU1_SB_DQ'<29>:
 C_SIGNAL='@s9s_mb_2u_lib.s9s_mb_2u(sch_1):m_d_cpu1_sb_dq(29)';
NODE_NAME     U1 AL19
 '@S9S_MB_2U_LIB.S9S_MB_2U(SCH_1):PAGE54_I91@PURE_QUANTA.SOCKET4677_AZIF0045P001C01CS(CHIPS)':
 'DDR3_SB_DQ29': CDS_PINID='DDR3_SB_DQ29';
NODE_NAME     J23 142
 '@S9S_MB_2U_LIB.S9S_MB_2U(SCH_1):PAGE104_I25@PURE_QUANTA.SCONN288_ADR50017P130CC(CHIPS)':
 'DQ29_B': CDS_PINID='DQ29_B';
NODE_NAME     J24 142
 '@S9S_MB_2U_LIB.S9S_MB_2U(SCH_1):PAGE105_I178@PURE_QUANTA.SCONN288_ADR50017P087CC(CHIPS)':
 'DQ29_B': CDS_PINID='DQ29_B';
NET_NAME
'M_D_CPU1_SB_DQ<2>'
 '@S9S_MB_2U_LIB.S9S_MB_2U(SCH_1):M_D_CPU1_SB_DQ'<2>:
 C_SIGNAL='@s9s_mb_2u_lib.s9s_mb_2u(sch_1):m_d_cpu1_sb_dq(2)';
NODE_NAME     U1 AN35
 '@S9S_MB_2U_LIB.S9S_MB_2U(SCH_1):PAGE54_I91@PURE_QUANTA.SOCKET4677_AZIF0045P001C01CS(CHIPS)':
 'DDR3_SB_DQ2': CDS_PINID='DDR3_SB_DQ2';
NODE_NAME     J23 245
 '@S9S_MB_2U_LIB.S9S_MB_2U(SCH_1):PAGE104_I25@PURE_QUANTA.SCONN288_ADR50017P130CC(CHIPS)':
 'DQ2_B': CDS_PINID='DQ2_B';
NODE_NAME     J24 245
 '@S9S_MB_2U_LIB.S9S_MB_2U(SCH_1):PAGE105_I178@PURE_QUANTA.SCONN288_ADR50017P087CC(CHIPS)':
 'DQ2_B': CDS_PINID='DQ2_B';
NET_NAME
'M_D_CPU1_SB_DQ<30>'
 '@S9S_MB_2U_LIB.S9S_MB_2U(SCH_1):M_D_CPU1_SB_DQ'<30>:
 C_SIGNAL='@s9s_mb_2u_lib.s9s_mb_2u(sch_1):m_d_cpu1_sb_dq(30)';
NODE_NAME     U1 AP20
 '@S9S_MB_2U_LIB.S9S_MB_2U(SCH_1):PAGE54_I91@PURE_QUANTA.SOCKET4677_AZIF0045P001C01CS(CHIPS)':
 'DDR3_SB_DQ30': CDS_PINID='DDR3_SB_DQ30';
NODE_NAME     J23 285
 '@S9S_MB_2U_LIB.S9S_MB_2U(SCH_1):PAGE104_I25@PURE_QUANTA.SCONN288_ADR50017P130CC(CHIPS)':
 'DQ30_B': CDS_PINID='DQ30_B';
NODE_NAME     J24 285
 '@S9S_MB_2U_LIB.S9S_MB_2U(SCH_1):PAGE105_I178@PURE_QUANTA.SCONN288_ADR50017P087CC(CHIPS)':
 'DQ30_B': CDS_PINID='DQ30_B';
NET_NAME
'M_D_CPU1_SB_DQ<31>'
 '@S9S_MB_2U_LIB.S9S_MB_2U(SCH_1):M_D_CPU1_SB_DQ'<31>:
 C_SIGNAL='@s9s_mb_2u_lib.s9s_mb_2u(sch_1):m_d_cpu1_sb_dq(31)';
NODE_NAME     U1 AN19
 '@S9S_MB_2U_LIB.S9S_MB_2U(SCH_1):PAGE54_I91@PURE_QUANTA.SOCKET4677_AZIF0045P001C01CS(CHIPS)':
 'DDR3_SB_DQ31': CDS_PINID='DDR3_SB_DQ31';
NODE_NAME     J23 287
 '@S9S_MB_2U_LIB.S9S_MB_2U(SCH_1):PAGE104_I25@PURE_QUANTA.SCONN288_ADR50017P130CC(CHIPS)':
 'DQ31_B': CDS_PINID='DQ31_B';
NODE_NAME     J24 287
 '@S9S_MB_2U_LIB.S9S_MB_2U(SCH_1):PAGE105_I178@PURE_QUANTA.SCONN288_ADR50017P087CC(CHIPS)':
 'DQ31_B': CDS_PINID='DQ31_B';
NET_NAME
'M_D_CPU1_SB_DQ<3>'
 '@S9S_MB_2U_LIB.S9S_MB_2U(SCH_1):M_D_CPU1_SB_DQ'<3>:
 C_SIGNAL='@s9s_mb_2u_lib.s9s_mb_2u(sch_1):m_d_cpu1_sb_dq(3)';
NODE_NAME     U1 AP34
 '@S9S_MB_2U_LIB.S9S_MB_2U(SCH_1):PAGE54_I91@PURE_QUANTA.SOCKET4677_AZIF0045P001C01CS(CHIPS)':
 'DDR3_SB_DQ3': CDS_PINID='DDR3_SB_DQ3';
NODE_NAME     J23 247
 '@S9S_MB_2U_LIB.S9S_MB_2U(SCH_1):PAGE104_I25@PURE_QUANTA.SCONN288_ADR50017P130CC(CHIPS)':
 'DQ3_B': CDS_PINID='DQ3_B';
NODE_NAME     J24 247
 '@S9S_MB_2U_LIB.S9S_MB_2U(SCH_1):PAGE105_I178@PURE_QUANTA.SCONN288_ADR50017P087CC(CHIPS)':
 'DQ3_B': CDS_PINID='DQ3_B';
NET_NAME
'M_D_CPU1_SB_DQ<4>'
 '@S9S_MB_2U_LIB.S9S_MB_2U(SCH_1):M_D_CPU1_SB_DQ'<4>:
 C_SIGNAL='@s9s_mb_2u_lib.s9s_mb_2u(sch_1):m_d_cpu1_sb_dq(4)';
NODE_NAME     U1 AK32
 '@S9S_MB_2U_LIB.S9S_MB_2U(SCH_1):PAGE54_I91@PURE_QUANTA.SOCKET4677_AZIF0045P001C01CS(CHIPS)':
 'DDR3_SB_DQ4': CDS_PINID='DDR3_SB_DQ4';
NODE_NAME     J23 107
 '@S9S_MB_2U_LIB.S9S_MB_2U(SCH_1):PAGE104_I25@PURE_QUANTA.SCONN288_ADR50017P130CC(CHIPS)':
 'DQ4_B': CDS_PINID='DQ4_B';
NODE_NAME     J24 107
 '@S9S_MB_2U_LIB.S9S_MB_2U(SCH_1):PAGE105_I178@PURE_QUANTA.SCONN288_ADR50017P087CC(CHIPS)':
 'DQ4_B': CDS_PINID='DQ4_B';
NET_NAME
'M_D_CPU1_SB_DQ<5>'
 '@S9S_MB_2U_LIB.S9S_MB_2U(SCH_1):M_D_CPU1_SB_DQ'<5>:
 C_SIGNAL='@s9s_mb_2u_lib.s9s_mb_2u(sch_1):m_d_cpu1_sb_dq(5)';
NODE_NAME     U1 AL31
 '@S9S_MB_2U_LIB.S9S_MB_2U(SCH_1):PAGE54_I91@PURE_QUANTA.SOCKET4677_AZIF0045P001C01CS(CHIPS)':
 'DDR3_SB_DQ5': CDS_PINID='DDR3_SB_DQ5';
NODE_NAME     J23 109
 '@S9S_MB_2U_LIB.S9S_MB_2U(SCH_1):PAGE104_I25@PURE_QUANTA.SCONN288_ADR50017P130CC(CHIPS)':
 'DQ5_B': CDS_PINID='DQ5_B';
NODE_NAME     J24 109
 '@S9S_MB_2U_LIB.S9S_MB_2U(SCH_1):PAGE105_I178@PURE_QUANTA.SCONN288_ADR50017P087CC(CHIPS)':
 'DQ5_B': CDS_PINID='DQ5_B';
NET_NAME
'M_D_CPU1_SB_DQ<6>'
 '@S9S_MB_2U_LIB.S9S_MB_2U(SCH_1):M_D_CPU1_SB_DQ'<6>:
 C_SIGNAL='@s9s_mb_2u_lib.s9s_mb_2u(sch_1):m_d_cpu1_sb_dq(6)';
NODE_NAME     U1 AP32
 '@S9S_MB_2U_LIB.S9S_MB_2U(SCH_1):PAGE54_I91@PURE_QUANTA.SOCKET4677_AZIF0045P001C01CS(CHIPS)':
 'DDR3_SB_DQ6': CDS_PINID='DDR3_SB_DQ6';
NODE_NAME     J23 252
 '@S9S_MB_2U_LIB.S9S_MB_2U(SCH_1):PAGE104_I25@PURE_QUANTA.SCONN288_ADR50017P130CC(CHIPS)':
 'DQ6_B': CDS_PINID='DQ6_B';
NODE_NAME     J24 252
 '@S9S_MB_2U_LIB.S9S_MB_2U(SCH_1):PAGE105_I178@PURE_QUANTA.SCONN288_ADR50017P087CC(CHIPS)':
 'DQ6_B': CDS_PINID='DQ6_B';
NET_NAME
'M_D_CPU1_SB_DQ<7>'
 '@S9S_MB_2U_LIB.S9S_MB_2U(SCH_1):M_D_CPU1_SB_DQ'<7>:
 C_SIGNAL='@s9s_mb_2u_lib.s9s_mb_2u(sch_1):m_d_cpu1_sb_dq(7)';
NODE_NAME     U1 AN31
 '@S9S_MB_2U_LIB.S9S_MB_2U(SCH_1):PAGE54_I91@PURE_QUANTA.SOCKET4677_AZIF0045P001C01CS(CHIPS)':
 'DDR3_SB_DQ7': CDS_PINID='DDR3_SB_DQ7';
NODE_NAME     J23 254
 '@S9S_MB_2U_LIB.S9S_MB_2U(SCH_1):PAGE104_I25@PURE_QUANTA.SCONN288_ADR50017P130CC(CHIPS)':
 'DQ7_B': CDS_PINID='DQ7_B';
NODE_NAME     J24 254
 '@S9S_MB_2U_LIB.S9S_MB_2U(SCH_1):PAGE105_I178@PURE_QUANTA.SCONN288_ADR50017P087CC(CHIPS)':
 'DQ7_B': CDS_PINID='DQ7_B';
NET_NAME
'M_D_CPU1_SB_DQ<8>'
 '@S9S_MB_2U_LIB.S9S_MB_2U(SCH_1):M_D_CPU1_SB_DQ'<8>:
 C_SIGNAL='@s9s_mb_2u_lib.s9s_mb_2u(sch_1):m_d_cpu1_sb_dq(8)';
NODE_NAME     U1 AL29
 '@S9S_MB_2U_LIB.S9S_MB_2U(SCH_1):PAGE54_I91@PURE_QUANTA.SOCKET4677_AZIF0045P001C01CS(CHIPS)':
 'DDR3_SB_DQ8': CDS_PINID='DDR3_SB_DQ8';
NODE_NAME     J23 111
 '@S9S_MB_2U_LIB.S9S_MB_2U(SCH_1):PAGE104_I25@PURE_QUANTA.SCONN288_ADR50017P130CC(CHIPS)':
 'DQ8_B': CDS_PINID='DQ8_B';
NODE_NAME     J24 111
 '@S9S_MB_2U_LIB.S9S_MB_2U(SCH_1):PAGE105_I178@PURE_QUANTA.SCONN288_ADR50017P087CC(CHIPS)':
 'DQ8_B': CDS_PINID='DQ8_B';
NET_NAME
'M_D_CPU1_SB_DQ<9>'
 '@S9S_MB_2U_LIB.S9S_MB_2U(SCH_1):M_D_CPU1_SB_DQ'<9>:
 C_SIGNAL='@s9s_mb_2u_lib.s9s_mb_2u(sch_1):m_d_cpu1_sb_dq(9)';
NODE_NAME     U1 AK28
 '@S9S_MB_2U_LIB.S9S_MB_2U(SCH_1):PAGE54_I91@PURE_QUANTA.SOCKET4677_AZIF0045P001C01CS(CHIPS)':
 'DDR3_SB_DQ9': CDS_PINID='DDR3_SB_DQ9';
NODE_NAME     J23 113
 '@S9S_MB_2U_LIB.S9S_MB_2U(SCH_1):PAGE104_I25@PURE_QUANTA.SCONN288_ADR50017P130CC(CHIPS)':
 'DQ9_B': CDS_PINID='DQ9_B';
NODE_NAME     J24 113
 '@S9S_MB_2U_LIB.S9S_MB_2U(SCH_1):PAGE105_I178@PURE_QUANTA.SCONN288_ADR50017P087CC(CHIPS)':
 'DQ9_B': CDS_PINID='DQ9_B';
NET_NAME
'M_D_CPU1_SB_DQS_DN<0>'
 '@S9S_MB_2U_LIB.S9S_MB_2U(SCH_1):M_D_CPU1_SB_DQS_DN'<0>:
 C_SIGNAL='@s9s_mb_2u_lib.s9s_mb_2u(sch_1):m_d_cpu1_sb_dqs_dn(0)';
NODE_NAME     U1 AJ33
 '@S9S_MB_2U_LIB.S9S_MB_2U(SCH_1):PAGE54_I91@PURE_QUANTA.SOCKET4677_AZIF0045P001C01CS(CHIPS)':
 'DDR3_SB_DQS_DN0': CDS_PINID='DDR3_SB_DQS_DN0';
NODE_NAME     J23 105
 '@S9S_MB_2U_LIB.S9S_MB_2U(SCH_1):PAGE104_I178@PURE_QUANTA.SCONN288_ADR50017P130CC(CHIPS)':
 'DQS0_B_C': CDS_PINID='DQS0_B_C';
NODE_NAME     J24 105
 '@S9S_MB_2U_LIB.S9S_MB_2U(SCH_1):PAGE105_I181@PURE_QUANTA.SCONN288_ADR50017P087CC(CHIPS)':
 'DQS0_B_C': CDS_PINID='DQS0_B_C';
NET_NAME
'M_D_CPU1_SB_DQS_DN<1>'
 '@S9S_MB_2U_LIB.S9S_MB_2U(SCH_1):M_D_CPU1_SB_DQS_DN'<1>:
 C_SIGNAL='@s9s_mb_2u_lib.s9s_mb_2u(sch_1):m_d_cpu1_sb_dqs_dn(1)';
NODE_NAME     U1 AJ27
 '@S9S_MB_2U_LIB.S9S_MB_2U(SCH_1):PAGE54_I91@PURE_QUANTA.SOCKET4677_AZIF0045P001C01CS(CHIPS)':
 'DDR3_SB_DQS_DN1': CDS_PINID='DDR3_SB_DQS_DN1';
NODE_NAME     J23 116
 '@S9S_MB_2U_LIB.S9S_MB_2U(SCH_1):PAGE104_I178@PURE_QUANTA.SCONN288_ADR50017P130CC(CHIPS)':
 'DQS1_B_C': CDS_PINID='DQS1_B_C';
NODE_NAME     J24 116
 '@S9S_MB_2U_LIB.S9S_MB_2U(SCH_1):PAGE105_I181@PURE_QUANTA.SCONN288_ADR50017P087CC(CHIPS)':
 'DQS1_B_C': CDS_PINID='DQS1_B_C';
NET_NAME
'M_D_CPU1_SB_DQS_DN<2>'
 '@S9S_MB_2U_LIB.S9S_MB_2U(SCH_1):M_D_CPU1_SB_DQS_DN'<2>:
 C_SIGNAL='@s9s_mb_2u_lib.s9s_mb_2u(sch_1):m_d_cpu1_sb_dqs_dn(2)';
NODE_NAME     U1 AB24
 '@S9S_MB_2U_LIB.S9S_MB_2U(SCH_1):PAGE54_I91@PURE_QUANTA.SOCKET4677_AZIF0045P001C01CS(CHIPS)':
 'DDR3_SB_DQS_DN2': CDS_PINID='DDR3_SB_DQS_DN2';
NODE_NAME     J23 127
 '@S9S_MB_2U_LIB.S9S_MB_2U(SCH_1):PAGE104_I178@PURE_QUANTA.SCONN288_ADR50017P130CC(CHIPS)':
 'DQS2_B_C': CDS_PINID='DQS2_B_C';
NODE_NAME     J24 127
 '@S9S_MB_2U_LIB.S9S_MB_2U(SCH_1):PAGE105_I181@PURE_QUANTA.SCONN288_ADR50017P087CC(CHIPS)':
 'DQS2_B_C': CDS_PINID='DQS2_B_C';
NET_NAME
'M_D_CPU1_SB_DQS_DN<3>'
 '@S9S_MB_2U_LIB.S9S_MB_2U(SCH_1):M_D_CPU1_SB_DQS_DN'<3>:
 C_SIGNAL='@s9s_mb_2u_lib.s9s_mb_2u(sch_1):m_d_cpu1_sb_dqs_dn(3)';
NODE_NAME     U1 AJ21
 '@S9S_MB_2U_LIB.S9S_MB_2U(SCH_1):PAGE54_I91@PURE_QUANTA.SOCKET4677_AZIF0045P001C01CS(CHIPS)':
 'DDR3_SB_DQS_DN3': CDS_PINID='DDR3_SB_DQS_DN3';
NODE_NAME     J23 138
 '@S9S_MB_2U_LIB.S9S_MB_2U(SCH_1):PAGE104_I178@PURE_QUANTA.SCONN288_ADR50017P130CC(CHIPS)':
 'DQS3_B_C': CDS_PINID='DQS3_B_C';
NODE_NAME     J24 138
 '@S9S_MB_2U_LIB.S9S_MB_2U(SCH_1):PAGE105_I181@PURE_QUANTA.SCONN288_ADR50017P087CC(CHIPS)':
 'DQS3_B_C': CDS_PINID='DQS3_B_C';
NET_NAME
'M_D_CPU1_SB_DQS_DN<4>'
 '@S9S_MB_2U_LIB.S9S_MB_2U(SCH_1):M_D_CPU1_SB_DQS_DN'<4>:
 C_SIGNAL='@s9s_mb_2u_lib.s9s_mb_2u(sch_1):m_d_cpu1_sb_dqs_dn(4)';
NODE_NAME     U1 AR39
 '@S9S_MB_2U_LIB.S9S_MB_2U(SCH_1):PAGE54_I91@PURE_QUANTA.SOCKET4677_AZIF0045P001C01CS(CHIPS)':
 'DDR3_SB_DQS_DN4': CDS_PINID='DDR3_SB_DQS_DN4';
NODE_NAME     J23 238
 '@S9S_MB_2U_LIB.S9S_MB_2U(SCH_1):PAGE104_I178@PURE_QUANTA.SCONN288_ADR50017P130CC(CHIPS)':
 'DQS4_B_C': CDS_PINID='DQS4_B_C';
NODE_NAME     J24 238
 '@S9S_MB_2U_LIB.S9S_MB_2U(SCH_1):PAGE105_I181@PURE_QUANTA.SCONN288_ADR50017P087CC(CHIPS)':
 'DQS4_B_C': CDS_PINID='DQS4_B_C';
NET_NAME
'M_D_CPU1_SB_DQS_DN<5>'
 '@S9S_MB_2U_LIB.S9S_MB_2U(SCH_1):M_D_CPU1_SB_DQS_DN'<5>:
 C_SIGNAL='@s9s_mb_2u_lib.s9s_mb_2u(sch_1):m_d_cpu1_sb_dqs_dn(5)';
NODE_NAME     U1 AN33
 '@S9S_MB_2U_LIB.S9S_MB_2U(SCH_1):PAGE54_I91@PURE_QUANTA.SOCKET4677_AZIF0045P001C01CS(CHIPS)':
 'DDR3_SB_DQS_DN5': CDS_PINID='DDR3_SB_DQS_DN5';
NODE_NAME     J23 249
 '@S9S_MB_2U_LIB.S9S_MB_2U(SCH_1):PAGE104_I178@PURE_QUANTA.SCONN288_ADR50017P130CC(CHIPS)':
 'DQS5_B_C||TDQS5_B_C': CDS_PINID='\dqs5_b_c||tdqs5_b_c\';
NODE_NAME     J24 249
 '@S9S_MB_2U_LIB.S9S_MB_2U(SCH_1):PAGE105_I181@PURE_QUANTA.SCONN288_ADR50017P087CC(CHIPS)':
 'DQS5_B_C||TDQS5_B_C': CDS_PINID='\dqs5_b_c||tdqs5_b_c\';
NET_NAME
'M_D_CPU1_SB_DQS_DN<6>'
 '@S9S_MB_2U_LIB.S9S_MB_2U(SCH_1):M_D_CPU1_SB_DQS_DN'<6>:
 C_SIGNAL='@s9s_mb_2u_lib.s9s_mb_2u(sch_1):m_d_cpu1_sb_dqs_dn(6)';
NODE_NAME     U1 AN27
 '@S9S_MB_2U_LIB.S9S_MB_2U(SCH_1):PAGE54_I91@PURE_QUANTA.SOCKET4677_AZIF0045P001C01CS(CHIPS)':
 'DDR3_SB_DQS_DN6': CDS_PINID='DDR3_SB_DQS_DN6';
NODE_NAME     J23 260
 '@S9S_MB_2U_LIB.S9S_MB_2U(SCH_1):PAGE104_I178@PURE_QUANTA.SCONN288_ADR50017P130CC(CHIPS)':
 'DQS6_B_C||TDQS6_B_C': CDS_PINID='\dqs6_b_c||tdqs6_b_c\';
NODE_NAME     J24 260
 '@S9S_MB_2U_LIB.S9S_MB_2U(SCH_1):PAGE105_I181@PURE_QUANTA.SCONN288_ADR50017P087CC(CHIPS)':
 'DQS6_B_C||TDQS6_B_C': CDS_PINID='\dqs6_b_c||tdqs6_b_c\';
NET_NAME
'M_D_CPU1_SB_DQS_DN<7>'
 '@S9S_MB_2U_LIB.S9S_MB_2U(SCH_1):M_D_CPU1_SB_DQS_DN'<7>:
 C_SIGNAL='@s9s_mb_2u_lib.s9s_mb_2u(sch_1):m_d_cpu1_sb_dqs_dn(7)';
NODE_NAME     U1 AF24
 '@S9S_MB_2U_LIB.S9S_MB_2U(SCH_1):PAGE54_I91@PURE_QUANTA.SOCKET4677_AZIF0045P001C01CS(CHIPS)':
 'DDR3_SB_DQS_DN7': CDS_PINID='DDR3_SB_DQS_DN7';
NODE_NAME     J23 271
 '@S9S_MB_2U_LIB.S9S_MB_2U(SCH_1):PAGE104_I178@PURE_QUANTA.SCONN288_ADR50017P130CC(CHIPS)':
 'DQS7_B_C||TDQS7_B_C': CDS_PINID='\dqs7_b_c||tdqs7_b_c\';
NODE_NAME     J24 271
 '@S9S_MB_2U_LIB.S9S_MB_2U(SCH_1):PAGE105_I181@PURE_QUANTA.SCONN288_ADR50017P087CC(CHIPS)':
 'DQS7_B_C||TDQS7_B_C': CDS_PINID='\dqs7_b_c||tdqs7_b_c\';
NET_NAME
'M_D_CPU1_SB_DQS_DN<8>'
 '@S9S_MB_2U_LIB.S9S_MB_2U(SCH_1):M_D_CPU1_SB_DQS_DN'<8>:
 C_SIGNAL='@s9s_mb_2u_lib.s9s_mb_2u(sch_1):m_d_cpu1_sb_dqs_dn(8)';
NODE_NAME     U1 AN21
 '@S9S_MB_2U_LIB.S9S_MB_2U(SCH_1):PAGE54_I91@PURE_QUANTA.SOCKET4677_AZIF0045P001C01CS(CHIPS)':
 'DDR3_SB_DQS_DN8': CDS_PINID='DDR3_SB_DQS_DN8';
NODE_NAME     J23 282
 '@S9S_MB_2U_LIB.S9S_MB_2U(SCH_1):PAGE104_I178@PURE_QUANTA.SCONN288_ADR50017P130CC(CHIPS)':
 'DQS8_B_C||TDQS8_B_C': CDS_PINID='\dqs8_b_c||tdqs8_b_c\';
NODE_NAME     J24 282
 '@S9S_MB_2U_LIB.S9S_MB_2U(SCH_1):PAGE105_I181@PURE_QUANTA.SCONN288_ADR50017P087CC(CHIPS)':
 'DQS8_B_C||TDQS8_B_C': CDS_PINID='\dqs8_b_c||tdqs8_b_c\';
NET_NAME
'M_D_CPU1_SB_DQS_DN<9>'
 '@S9S_MB_2U_LIB.S9S_MB_2U(SCH_1):M_D_CPU1_SB_DQS_DN'<9>:
 C_SIGNAL='@s9s_mb_2u_lib.s9s_mb_2u(sch_1):m_d_cpu1_sb_dqs_dn(9)';
NODE_NAME     U1 AJ39
 '@S9S_MB_2U_LIB.S9S_MB_2U(SCH_1):PAGE54_I91@PURE_QUANTA.SOCKET4677_AZIF0045P001C01CS(CHIPS)':
 'DDR3_SB_DQS_DN9': CDS_PINID='DDR3_SB_DQS_DN9';
NODE_NAME     J23 94
 '@S9S_MB_2U_LIB.S9S_MB_2U(SCH_1):PAGE104_I178@PURE_QUANTA.SCONN288_ADR50017P130CC(CHIPS)':
 'DQS9_B_C||TDQS9_B_C': CDS_PINID='\dqs9_b_c||tdqs9_b_c\';
NODE_NAME     J24 94
 '@S9S_MB_2U_LIB.S9S_MB_2U(SCH_1):PAGE105_I181@PURE_QUANTA.SCONN288_ADR50017P087CC(CHIPS)':
 'DQS9_B_C||TDQS9_B_C': CDS_PINID='\dqs9_b_c||tdqs9_b_c\';
NET_NAME
'M_D_CPU1_SB_DQS_DP<0>'
 '@S9S_MB_2U_LIB.S9S_MB_2U(SCH_1):M_D_CPU1_SB_DQS_DP'<0>:
 C_SIGNAL='@s9s_mb_2u_lib.s9s_mb_2u(sch_1):m_d_cpu1_sb_dqs_dp(0)';
NODE_NAME     U1 AL33
 '@S9S_MB_2U_LIB.S9S_MB_2U(SCH_1):PAGE54_I91@PURE_QUANTA.SOCKET4677_AZIF0045P001C01CS(CHIPS)':
 'DDR3_SB_DQS_DP0': CDS_PINID='DDR3_SB_DQS_DP0';
NODE_NAME     J23 104
 '@S9S_MB_2U_LIB.S9S_MB_2U(SCH_1):PAGE104_I178@PURE_QUANTA.SCONN288_ADR50017P130CC(CHIPS)':
 'DQS0_B_T': CDS_PINID='DQS0_B_T';
NODE_NAME     J24 104
 '@S9S_MB_2U_LIB.S9S_MB_2U(SCH_1):PAGE105_I181@PURE_QUANTA.SCONN288_ADR50017P087CC(CHIPS)':
 'DQS0_B_T': CDS_PINID='DQS0_B_T';
NET_NAME
'M_D_CPU1_SB_DQS_DP<1>'
 '@S9S_MB_2U_LIB.S9S_MB_2U(SCH_1):M_D_CPU1_SB_DQS_DP'<1>:
 C_SIGNAL='@s9s_mb_2u_lib.s9s_mb_2u(sch_1):m_d_cpu1_sb_dqs_dp(1)';
NODE_NAME     U1 AL27
 '@S9S_MB_2U_LIB.S9S_MB_2U(SCH_1):PAGE54_I91@PURE_QUANTA.SOCKET4677_AZIF0045P001C01CS(CHIPS)':
 'DDR3_SB_DQS_DP1': CDS_PINID='DDR3_SB_DQS_DP1';
NODE_NAME     J23 115
 '@S9S_MB_2U_LIB.S9S_MB_2U(SCH_1):PAGE104_I178@PURE_QUANTA.SCONN288_ADR50017P130CC(CHIPS)':
 'DQS1_B_T': CDS_PINID='DQS1_B_T';
NODE_NAME     J24 115
 '@S9S_MB_2U_LIB.S9S_MB_2U(SCH_1):PAGE105_I181@PURE_QUANTA.SCONN288_ADR50017P087CC(CHIPS)':
 'DQS1_B_T': CDS_PINID='DQS1_B_T';
NET_NAME
'M_D_CPU1_SB_DQS_DP<2>'
 '@S9S_MB_2U_LIB.S9S_MB_2U(SCH_1):M_D_CPU1_SB_DQS_DP'<2>:
 C_SIGNAL='@s9s_mb_2u_lib.s9s_mb_2u(sch_1):m_d_cpu1_sb_dqs_dp(2)';
NODE_NAME     U1 AD24
 '@S9S_MB_2U_LIB.S9S_MB_2U(SCH_1):PAGE54_I91@PURE_QUANTA.SOCKET4677_AZIF0045P001C01CS(CHIPS)':
 'DDR3_SB_DQS_DP2': CDS_PINID='DDR3_SB_DQS_DP2';
NODE_NAME     J23 126
 '@S9S_MB_2U_LIB.S9S_MB_2U(SCH_1):PAGE104_I178@PURE_QUANTA.SCONN288_ADR50017P130CC(CHIPS)':
 'DQS2_B_T': CDS_PINID='DQS2_B_T';
NODE_NAME     J24 126
 '@S9S_MB_2U_LIB.S9S_MB_2U(SCH_1):PAGE105_I181@PURE_QUANTA.SCONN288_ADR50017P087CC(CHIPS)':
 'DQS2_B_T': CDS_PINID='DQS2_B_T';
NET_NAME
'M_D_CPU1_SB_DQS_DP<3>'
 '@S9S_MB_2U_LIB.S9S_MB_2U(SCH_1):M_D_CPU1_SB_DQS_DP'<3>:
 C_SIGNAL='@s9s_mb_2u_lib.s9s_mb_2u(sch_1):m_d_cpu1_sb_dqs_dp(3)';
NODE_NAME     U1 AL21
 '@S9S_MB_2U_LIB.S9S_MB_2U(SCH_1):PAGE54_I91@PURE_QUANTA.SOCKET4677_AZIF0045P001C01CS(CHIPS)':
 'DDR3_SB_DQS_DP3': CDS_PINID='DDR3_SB_DQS_DP3';
NODE_NAME     J23 137
 '@S9S_MB_2U_LIB.S9S_MB_2U(SCH_1):PAGE104_I178@PURE_QUANTA.SCONN288_ADR50017P130CC(CHIPS)':
 'DQS3_B_T': CDS_PINID='DQS3_B_T';
NODE_NAME     J24 137
 '@S9S_MB_2U_LIB.S9S_MB_2U(SCH_1):PAGE105_I181@PURE_QUANTA.SCONN288_ADR50017P087CC(CHIPS)':
 'DQS3_B_T': CDS_PINID='DQS3_B_T';
NET_NAME
'M_D_CPU1_SB_DQS_DP<4>'
 '@S9S_MB_2U_LIB.S9S_MB_2U(SCH_1):M_D_CPU1_SB_DQS_DP'<4>:
 C_SIGNAL='@s9s_mb_2u_lib.s9s_mb_2u(sch_1):m_d_cpu1_sb_dqs_dp(4)';
NODE_NAME     U1 AN39
 '@S9S_MB_2U_LIB.S9S_MB_2U(SCH_1):PAGE54_I91@PURE_QUANTA.SOCKET4677_AZIF0045P001C01CS(CHIPS)':
 'DDR3_SB_DQS_DP4': CDS_PINID='DDR3_SB_DQS_DP4';
NODE_NAME     J23 239
 '@S9S_MB_2U_LIB.S9S_MB_2U(SCH_1):PAGE104_I178@PURE_QUANTA.SCONN288_ADR50017P130CC(CHIPS)':
 'DQS4_B_T': CDS_PINID='DQS4_B_T';
NODE_NAME     J24 239
 '@S9S_MB_2U_LIB.S9S_MB_2U(SCH_1):PAGE105_I181@PURE_QUANTA.SCONN288_ADR50017P087CC(CHIPS)':
 'DQS4_B_T': CDS_PINID='DQS4_B_T';
NET_NAME
'M_D_CPU1_SB_DQS_DP<5>'
 '@S9S_MB_2U_LIB.S9S_MB_2U(SCH_1):M_D_CPU1_SB_DQS_DP'<5>:
 C_SIGNAL='@s9s_mb_2u_lib.s9s_mb_2u(sch_1):m_d_cpu1_sb_dqs_dp(5)';
NODE_NAME     U1 AR33
 '@S9S_MB_2U_LIB.S9S_MB_2U(SCH_1):PAGE54_I91@PURE_QUANTA.SOCKET4677_AZIF0045P001C01CS(CHIPS)':
 'DDR3_SB_DQS_DP5': CDS_PINID='DDR3_SB_DQS_DP5';
NODE_NAME     J23 250
 '@S9S_MB_2U_LIB.S9S_MB_2U(SCH_1):PAGE104_I178@PURE_QUANTA.SCONN288_ADR50017P130CC(CHIPS)':
 'DQS5_B_T||TDQS5_B_T': CDS_PINID='\dqs5_b_t||tdqs5_b_t\';
NODE_NAME     J24 250
 '@S9S_MB_2U_LIB.S9S_MB_2U(SCH_1):PAGE105_I181@PURE_QUANTA.SCONN288_ADR50017P087CC(CHIPS)':
 'DQS5_B_T||TDQS5_B_T': CDS_PINID='\dqs5_b_t||tdqs5_b_t\';
NET_NAME
'M_D_CPU1_SB_DQS_DP<6>'
 '@S9S_MB_2U_LIB.S9S_MB_2U(SCH_1):M_D_CPU1_SB_DQS_DP'<6>:
 C_SIGNAL='@s9s_mb_2u_lib.s9s_mb_2u(sch_1):m_d_cpu1_sb_dqs_dp(6)';
NODE_NAME     U1 AR27
 '@S9S_MB_2U_LIB.S9S_MB_2U(SCH_1):PAGE54_I91@PURE_QUANTA.SOCKET4677_AZIF0045P001C01CS(CHIPS)':
 'DDR3_SB_DQS_DP6': CDS_PINID='DDR3_SB_DQS_DP6';
NODE_NAME     J23 261
 '@S9S_MB_2U_LIB.S9S_MB_2U(SCH_1):PAGE104_I178@PURE_QUANTA.SCONN288_ADR50017P130CC(CHIPS)':
 'DQS6_B_T||TDQS6_B_T': CDS_PINID='\dqs6_b_t||tdqs6_b_t\';
NODE_NAME     J24 261
 '@S9S_MB_2U_LIB.S9S_MB_2U(SCH_1):PAGE105_I181@PURE_QUANTA.SCONN288_ADR50017P087CC(CHIPS)':
 'DQS6_B_T||TDQS6_B_T': CDS_PINID='\dqs6_b_t||tdqs6_b_t\';
NET_NAME
'M_D_CPU1_SB_DQS_DP<7>'
 '@S9S_MB_2U_LIB.S9S_MB_2U(SCH_1):M_D_CPU1_SB_DQS_DP'<7>:
 C_SIGNAL='@s9s_mb_2u_lib.s9s_mb_2u(sch_1):m_d_cpu1_sb_dqs_dp(7)';
NODE_NAME     U1 AH24
 '@S9S_MB_2U_LIB.S9S_MB_2U(SCH_1):PAGE54_I91@PURE_QUANTA.SOCKET4677_AZIF0045P001C01CS(CHIPS)':
 'DDR3_SB_DQS_DP7': CDS_PINID='DDR3_SB_DQS_DP7';
NODE_NAME     J23 272
 '@S9S_MB_2U_LIB.S9S_MB_2U(SCH_1):PAGE104_I178@PURE_QUANTA.SCONN288_ADR50017P130CC(CHIPS)':
 'DQS7_B_T||TDQS7_B_T': CDS_PINID='\dqs7_b_t||tdqs7_b_t\';
NODE_NAME     J24 272
 '@S9S_MB_2U_LIB.S9S_MB_2U(SCH_1):PAGE105_I181@PURE_QUANTA.SCONN288_ADR50017P087CC(CHIPS)':
 'DQS7_B_T||TDQS7_B_T': CDS_PINID='\dqs7_b_t||tdqs7_b_t\';
NET_NAME
'M_D_CPU1_SB_DQS_DP<8>'
 '@S9S_MB_2U_LIB.S9S_MB_2U(SCH_1):M_D_CPU1_SB_DQS_DP'<8>:
 C_SIGNAL='@s9s_mb_2u_lib.s9s_mb_2u(sch_1):m_d_cpu1_sb_dqs_dp(8)';
NODE_NAME     U1 AR21
 '@S9S_MB_2U_LIB.S9S_MB_2U(SCH_1):PAGE54_I91@PURE_QUANTA.SOCKET4677_AZIF0045P001C01CS(CHIPS)':
 'DDR3_SB_DQS_DP8': CDS_PINID='DDR3_SB_DQS_DP8';
NODE_NAME     J23 283
 '@S9S_MB_2U_LIB.S9S_MB_2U(SCH_1):PAGE104_I178@PURE_QUANTA.SCONN288_ADR50017P130CC(CHIPS)':
 'DQS8_B_T||TDQS8_B_T': CDS_PINID='\dqs8_b_t||tdqs8_b_t\';
NODE_NAME     J24 283
 '@S9S_MB_2U_LIB.S9S_MB_2U(SCH_1):PAGE105_I181@PURE_QUANTA.SCONN288_ADR50017P087CC(CHIPS)':
 'DQS8_B_T||TDQS8_B_T': CDS_PINID='\dqs8_b_t||tdqs8_b_t\';
NET_NAME
'M_D_CPU1_SB_DQS_DP<9>'
 '@S9S_MB_2U_LIB.S9S_MB_2U(SCH_1):M_D_CPU1_SB_DQS_DP'<9>:
 C_SIGNAL='@s9s_mb_2u_lib.s9s_mb_2u(sch_1):m_d_cpu1_sb_dqs_dp(9)';
NODE_NAME     U1 AL39
 '@S9S_MB_2U_LIB.S9S_MB_2U(SCH_1):PAGE54_I91@PURE_QUANTA.SOCKET4677_AZIF0045P001C01CS(CHIPS)':
 'DDR3_SB_DQS_DP9': CDS_PINID='DDR3_SB_DQS_DP9';
NODE_NAME     J23 93
 '@S9S_MB_2U_LIB.S9S_MB_2U(SCH_1):PAGE104_I178@PURE_QUANTA.SCONN288_ADR50017P130CC(CHIPS)':
 'DQS9_B_T||TDQS9_B_T||DBI4_B_N': CDS_PINID='\dqs9_b_t||tdqs9_b_t||dbi4_b_n\';
NODE_NAME     J24 93
 '@S9S_MB_2U_LIB.S9S_MB_2U(SCH_1):PAGE105_I181@PURE_QUANTA.SCONN288_ADR50017P087CC(CHIPS)':
 'DQS9_B_T||TDQS9_B_T||DBI4_B_N': CDS_PINID='\dqs9_b_t||tdqs9_b_t||dbi4_b_n\';
NET_NAME
'M_D_CPU1_SB_PAR'
 '@S9S_MB_2U_LIB.S9S_MB_2U(SCH_1):M_D_CPU1_SB_PAR':
 C_SIGNAL='@s9s_mb_2u_lib.s9s_mb_2u(sch_1):m_d_cpu1_sb_par';
NODE_NAME     U1 AH42
 '@S9S_MB_2U_LIB.S9S_MB_2U(SCH_1):PAGE54_I91@PURE_QUANTA.SOCKET4677_AZIF0045P001C01CS(CHIPS)':
 'DDR3_SB_PAR': CDS_PINID='DDR3_SB_PAR';
NODE_NAME     J23 227
 '@S9S_MB_2U_LIB.S9S_MB_2U(SCH_1):PAGE104_I25@PURE_QUANTA.SCONN288_ADR50017P130CC(CHIPS)':
 'PAR_B': CDS_PINID='PAR_B';
NODE_NAME     J24 227
 '@S9S_MB_2U_LIB.S9S_MB_2U(SCH_1):PAGE105_I178@PURE_QUANTA.SCONN288_ADR50017P087CC(CHIPS)':
 'PAR_B': CDS_PINID='PAR_B';
NET_NAME
'M_D_CPU1_SB_RSP<0>'
 '@S9S_MB_2U_LIB.S9S_MB_2U(SCH_1):M_D_CPU1_SB_RSP'<0>:
 C_SIGNAL='@s9s_mb_2u_lib.s9s_mb_2u(sch_1):m_d_cpu1_sb_rsp(0)';
NODE_NAME     U1 AF51
 '@S9S_MB_2U_LIB.S9S_MB_2U(SCH_1):PAGE54_I91@PURE_QUANTA.SOCKET4677_AZIF0045P001C01CS(CHIPS)':
 'DDR3_B_RSP0': CDS_PINID='DDR3_B_RSP0';
NODE_NAME     J23 87
 '@S9S_MB_2U_LIB.S9S_MB_2U(SCH_1):PAGE104_I25@PURE_QUANTA.SCONN288_ADR50017P130CC(CHIPS)':
 'LBS||RSP_B_N': CDS_PINID='\lbs||rsp_b_n\';
NET_NAME
'M_D_CPU1_SB_RSP<1>'
 '@S9S_MB_2U_LIB.S9S_MB_2U(SCH_1):M_D_CPU1_SB_RSP'<1>:
 C_SIGNAL='@s9s_mb_2u_lib.s9s_mb_2u(sch_1):m_d_cpu1_sb_rsp(1)';
NODE_NAME     U1 AG50
 '@S9S_MB_2U_LIB.S9S_MB_2U(SCH_1):PAGE54_I91@PURE_QUANTA.SOCKET4677_AZIF0045P001C01CS(CHIPS)':
 'DDR3_B_RSP1': CDS_PINID='DDR3_B_RSP1';
NODE_NAME     J24 87
 '@S9S_MB_2U_LIB.S9S_MB_2U(SCH_1):PAGE105_I178@PURE_QUANTA.SCONN288_ADR50017P087CC(CHIPS)':
 'LBS||RSP_B_N': CDS_PINID='\lbs||rsp_b_n\';
NET_NAME
'M_E_CPU0_ALERT_N'
 '@S9S_MB_2U_LIB.S9S_MB_2U(SCH_1):M_E_CPU0_ALERT_N':
 C_SIGNAL='@s9s_mb_2u_lib.s9s_mb_2u(sch_1):m_e_cpu0_alert_n';
NODE_NAME     U2 CY47
 '@S9S_MB_2U_LIB.S9S_MB_2U(SCH_1):PAGE24_I169@PURE_QUANTA.SOCKET4677_AZIF0045P001C01CS(CHIPS)':
 'DDR4_ALERT_N': CDS_PINID='DDR4_ALERT_N';
NODE_NAME     J9 62
 '@S9S_MB_2U_LIB.S9S_MB_2U(SCH_1):PAGE90_I12@PURE_QUANTA.SCONN288_ADR50017P130CC(CHIPS)':
 'ALERT_N': CDS_PINID='ALERT_N';
NODE_NAME     J10 62
 '@S9S_MB_2U_LIB.S9S_MB_2U(SCH_1):PAGE91_I13@PURE_QUANTA.SCONN288_ADR50017P087CC(CHIPS)':
 'ALERT_N': CDS_PINID='ALERT_N';
NET_NAME
'M_E_CPU0_CLK_DN<0>'
 '@S9S_MB_2U_LIB.S9S_MB_2U(SCH_1):M_E_CPU0_CLK_DN'<0>:
 C_SIGNAL='@s9s_mb_2u_lib.s9s_mb_2u(sch_1):m_e_cpu0_clk_dn(0)';
NODE_NAME     U2 EJ45
 '@S9S_MB_2U_LIB.S9S_MB_2U(SCH_1):PAGE24_I169@PURE_QUANTA.SOCKET4677_AZIF0045P001C01CS(CHIPS)':
 'DDR4_CLK_DN0': CDS_PINID='DDR4_CLK_DN0';
NODE_NAME     J9 218
 '@S9S_MB_2U_LIB.S9S_MB_2U(SCH_1):PAGE90_I12@PURE_QUANTA.SCONN288_ADR50017P130CC(CHIPS)':
 'CK_C': CDS_PINID='CK_C';
NET_NAME
'M_E_CPU0_CLK_DN<1>'
 '@S9S_MB_2U_LIB.S9S_MB_2U(SCH_1):M_E_CPU0_CLK_DN'<1>:
 C_SIGNAL='@s9s_mb_2u_lib.s9s_mb_2u(sch_1):m_e_cpu0_clk_dn(1)';
NODE_NAME     U2 EE45
 '@S9S_MB_2U_LIB.S9S_MB_2U(SCH_1):PAGE24_I169@PURE_QUANTA.SOCKET4677_AZIF0045P001C01CS(CHIPS)':
 'DDR4_CLK_DN1': CDS_PINID='DDR4_CLK_DN1';
NODE_NAME     J10 218
 '@S9S_MB_2U_LIB.S9S_MB_2U(SCH_1):PAGE91_I13@PURE_QUANTA.SCONN288_ADR50017P087CC(CHIPS)':
 'CK_C': CDS_PINID='CK_C';
NET_NAME
'M_E_CPU0_CLK_DP<0>'
 '@S9S_MB_2U_LIB.S9S_MB_2U(SCH_1):M_E_CPU0_CLK_DP'<0>:
 C_SIGNAL='@s9s_mb_2u_lib.s9s_mb_2u(sch_1):m_e_cpu0_clk_dp(0)';
NODE_NAME     U2 EG45
 '@S9S_MB_2U_LIB.S9S_MB_2U(SCH_1):PAGE24_I169@PURE_QUANTA.SOCKET4677_AZIF0045P001C01CS(CHIPS)':
 'DDR4_CLK_DP0': CDS_PINID='DDR4_CLK_DP0';
NODE_NAME     J9 217
 '@S9S_MB_2U_LIB.S9S_MB_2U(SCH_1):PAGE90_I12@PURE_QUANTA.SCONN288_ADR50017P130CC(CHIPS)':
 'CK_T': CDS_PINID='CK_T';
NET_NAME
'M_E_CPU0_CLK_DP<1>'
 '@S9S_MB_2U_LIB.S9S_MB_2U(SCH_1):M_E_CPU0_CLK_DP'<1>:
 C_SIGNAL='@s9s_mb_2u_lib.s9s_mb_2u(sch_1):m_e_cpu0_clk_dp(1)';
NODE_NAME     U2 EC45
 '@S9S_MB_2U_LIB.S9S_MB_2U(SCH_1):PAGE24_I169@PURE_QUANTA.SOCKET4677_AZIF0045P001C01CS(CHIPS)':
 'DDR4_CLK_DP1': CDS_PINID='DDR4_CLK_DP1';
NODE_NAME     J10 217
 '@S9S_MB_2U_LIB.S9S_MB_2U(SCH_1):PAGE91_I13@PURE_QUANTA.SCONN288_ADR50017P087CC(CHIPS)':
 'CK_T': CDS_PINID='CK_T';
NET_NAME
'M_E_CPU0_SA_CA<0>'
 '@S9S_MB_2U_LIB.S9S_MB_2U(SCH_1):M_E_CPU0_SA_CA'<0>:
 C_SIGNAL='@s9s_mb_2u_lib.s9s_mb_2u(sch_1):m_e_cpu0_sa_ca(0)';
NODE_NAME     U2 EP49
 '@S9S_MB_2U_LIB.S9S_MB_2U(SCH_1):PAGE24_I169@PURE_QUANTA.SOCKET4677_AZIF0045P001C01CS(CHIPS)':
 'DDR4_SA_CA0': CDS_PINID='DDR4_SA_CA0';
NODE_NAME     J9 66
 '@S9S_MB_2U_LIB.S9S_MB_2U(SCH_1):PAGE90_I12@PURE_QUANTA.SCONN288_ADR50017P130CC(CHIPS)':
 'CA0_A': CDS_PINID='CA0_A';
NODE_NAME     J10 66
 '@S9S_MB_2U_LIB.S9S_MB_2U(SCH_1):PAGE91_I13@PURE_QUANTA.SCONN288_ADR50017P087CC(CHIPS)':
 'CA0_A': CDS_PINID='CA0_A';
NET_NAME
'M_E_CPU0_SA_CA<1>'
 '@S9S_MB_2U_LIB.S9S_MB_2U(SCH_1):M_E_CPU0_SA_CA'<1>:
 C_SIGNAL='@s9s_mb_2u_lib.s9s_mb_2u(sch_1):m_e_cpu0_sa_ca(1)';
NODE_NAME     U2 ET49
 '@S9S_MB_2U_LIB.S9S_MB_2U(SCH_1):PAGE24_I169@PURE_QUANTA.SOCKET4677_AZIF0045P001C01CS(CHIPS)':
 'DDR4_SA_CA1': CDS_PINID='DDR4_SA_CA1';
NODE_NAME     J9 211
 '@S9S_MB_2U_LIB.S9S_MB_2U(SCH_1):PAGE90_I12@PURE_QUANTA.SCONN288_ADR50017P130CC(CHIPS)':
 'CA1_A': CDS_PINID='CA1_A';
NODE_NAME     J10 211
 '@S9S_MB_2U_LIB.S9S_MB_2U(SCH_1):PAGE91_I13@PURE_QUANTA.SCONN288_ADR50017P087CC(CHIPS)':
 'CA1_A': CDS_PINID='CA1_A';
NET_NAME
'M_E_CPU0_SA_CA<2>'
 '@S9S_MB_2U_LIB.S9S_MB_2U(SCH_1):M_E_CPU0_SA_CA'<2>:
 C_SIGNAL='@s9s_mb_2u_lib.s9s_mb_2u(sch_1):m_e_cpu0_sa_ca(2)';
NODE_NAME     U2 EK49
 '@S9S_MB_2U_LIB.S9S_MB_2U(SCH_1):PAGE24_I169@PURE_QUANTA.SOCKET4677_AZIF0045P001C01CS(CHIPS)':
 'DDR4_SA_CA2': CDS_PINID='DDR4_SA_CA2';
NODE_NAME     J9 68
 '@S9S_MB_2U_LIB.S9S_MB_2U(SCH_1):PAGE90_I12@PURE_QUANTA.SCONN288_ADR50017P130CC(CHIPS)':
 'CA2_A': CDS_PINID='CA2_A';
NODE_NAME     J10 68
 '@S9S_MB_2U_LIB.S9S_MB_2U(SCH_1):PAGE91_I13@PURE_QUANTA.SCONN288_ADR50017P087CC(CHIPS)':
 'CA2_A': CDS_PINID='CA2_A';
NET_NAME
'M_E_CPU0_SA_CA<3>'
 '@S9S_MB_2U_LIB.S9S_MB_2U(SCH_1):M_E_CPU0_SA_CA'<3>:
 C_SIGNAL='@s9s_mb_2u_lib.s9s_mb_2u(sch_1):m_e_cpu0_sa_ca(3)';
NODE_NAME     U2 EL48
 '@S9S_MB_2U_LIB.S9S_MB_2U(SCH_1):PAGE24_I169@PURE_QUANTA.SOCKET4677_AZIF0045P001C01CS(CHIPS)':
 'DDR4_SA_CA3': CDS_PINID='DDR4_SA_CA3';
NODE_NAME     J9 213
 '@S9S_MB_2U_LIB.S9S_MB_2U(SCH_1):PAGE90_I12@PURE_QUANTA.SCONN288_ADR50017P130CC(CHIPS)':
 'CA3_A': CDS_PINID='CA3_A';
NODE_NAME     J10 213
 '@S9S_MB_2U_LIB.S9S_MB_2U(SCH_1):PAGE91_I13@PURE_QUANTA.SCONN288_ADR50017P087CC(CHIPS)':
 'CA3_A': CDS_PINID='CA3_A';
NET_NAME
'M_E_CPU0_SA_CA<4>'
 '@S9S_MB_2U_LIB.S9S_MB_2U(SCH_1):M_E_CPU0_SA_CA'<4>:
 C_SIGNAL='@s9s_mb_2u_lib.s9s_mb_2u(sch_1):m_e_cpu0_sa_ca(4)';
NODE_NAME     U2 EM47
 '@S9S_MB_2U_LIB.S9S_MB_2U(SCH_1):PAGE24_I169@PURE_QUANTA.SOCKET4677_AZIF0045P001C01CS(CHIPS)':
 'DDR4_SA_CA4': CDS_PINID='DDR4_SA_CA4';
NODE_NAME     J9 70
 '@S9S_MB_2U_LIB.S9S_MB_2U(SCH_1):PAGE90_I12@PURE_QUANTA.SCONN288_ADR50017P130CC(CHIPS)':
 'CA4_A': CDS_PINID='CA4_A';
NODE_NAME     J10 70
 '@S9S_MB_2U_LIB.S9S_MB_2U(SCH_1):PAGE91_I13@PURE_QUANTA.SCONN288_ADR50017P087CC(CHIPS)':
 'CA4_A': CDS_PINID='CA4_A';
NET_NAME
'M_E_CPU0_SA_CA<5>'
 '@S9S_MB_2U_LIB.S9S_MB_2U(SCH_1):M_E_CPU0_SA_CA'<5>:
 C_SIGNAL='@s9s_mb_2u_lib.s9s_mb_2u(sch_1):m_e_cpu0_sa_ca(5)';
NODE_NAME     U2 EP47
 '@S9S_MB_2U_LIB.S9S_MB_2U(SCH_1):PAGE24_I169@PURE_QUANTA.SOCKET4677_AZIF0045P001C01CS(CHIPS)':
 'DDR4_SA_CA5': CDS_PINID='DDR4_SA_CA5';
NODE_NAME     J9 215
 '@S9S_MB_2U_LIB.S9S_MB_2U(SCH_1):PAGE90_I12@PURE_QUANTA.SCONN288_ADR50017P130CC(CHIPS)':
 'CA5_A': CDS_PINID='CA5_A';
NODE_NAME     J10 215
 '@S9S_MB_2U_LIB.S9S_MB_2U(SCH_1):PAGE91_I13@PURE_QUANTA.SCONN288_ADR50017P087CC(CHIPS)':
 'CA5_A': CDS_PINID='CA5_A';
NET_NAME
'M_E_CPU0_SA_CA<6>'
 '@S9S_MB_2U_LIB.S9S_MB_2U(SCH_1):M_E_CPU0_SA_CA'<6>:
 C_SIGNAL='@s9s_mb_2u_lib.s9s_mb_2u(sch_1):m_e_cpu0_sa_ca(6)';
NODE_NAME     U2 ED44
 '@S9S_MB_2U_LIB.S9S_MB_2U(SCH_1):PAGE24_I169@PURE_QUANTA.SOCKET4677_AZIF0045P001C01CS(CHIPS)':
 'DDR4_SA_CA6': CDS_PINID='DDR4_SA_CA6';
NODE_NAME     J9 72
 '@S9S_MB_2U_LIB.S9S_MB_2U(SCH_1):PAGE90_I12@PURE_QUANTA.SCONN288_ADR50017P130CC(CHIPS)':
 'CA6_A': CDS_PINID='CA6_A';
NODE_NAME     J10 72
 '@S9S_MB_2U_LIB.S9S_MB_2U(SCH_1):PAGE91_I13@PURE_QUANTA.SCONN288_ADR50017P087CC(CHIPS)':
 'CA6_A': CDS_PINID='CA6_A';
NET_NAME
'M_E_CPU0_SA_CB<0>'
 '@S9S_MB_2U_LIB.S9S_MB_2U(SCH_1):M_E_CPU0_SA_CB'<0>:
 C_SIGNAL='@s9s_mb_2u_lib.s9s_mb_2u(sch_1):m_e_cpu0_sa_cb(0)';
NODE_NAME     U2 EM57
 '@S9S_MB_2U_LIB.S9S_MB_2U(SCH_1):PAGE24_I169@PURE_QUANTA.SOCKET4677_AZIF0045P001C01CS(CHIPS)':
 'DDR4_SA_ECC0': CDS_PINID='DDR4_SA_ECC0';
NODE_NAME     J9 51
 '@S9S_MB_2U_LIB.S9S_MB_2U(SCH_1):PAGE90_I12@PURE_QUANTA.SCONN288_ADR50017P130CC(CHIPS)':
 'CB0_A': CDS_PINID='CB0_A';
NODE_NAME     J10 51
 '@S9S_MB_2U_LIB.S9S_MB_2U(SCH_1):PAGE91_I13@PURE_QUANTA.SCONN288_ADR50017P087CC(CHIPS)':
 'CB0_A': CDS_PINID='CB0_A';
NET_NAME
'M_E_CPU0_SA_CB<1>'
 '@S9S_MB_2U_LIB.S9S_MB_2U(SCH_1):M_E_CPU0_SA_CB'<1>:
 C_SIGNAL='@s9s_mb_2u_lib.s9s_mb_2u(sch_1):m_e_cpu0_sa_cb(1)';
NODE_NAME     U2 EL56
 '@S9S_MB_2U_LIB.S9S_MB_2U(SCH_1):PAGE24_I169@PURE_QUANTA.SOCKET4677_AZIF0045P001C01CS(CHIPS)':
 'DDR4_SA_ECC1': CDS_PINID='DDR4_SA_ECC1';
NODE_NAME     J9 53
 '@S9S_MB_2U_LIB.S9S_MB_2U(SCH_1):PAGE90_I12@PURE_QUANTA.SCONN288_ADR50017P130CC(CHIPS)':
 'CB1_A': CDS_PINID='CB1_A';
NODE_NAME     J10 53
 '@S9S_MB_2U_LIB.S9S_MB_2U(SCH_1):PAGE91_I13@PURE_QUANTA.SCONN288_ADR50017P087CC(CHIPS)':
 'CB1_A': CDS_PINID='CB1_A';
NET_NAME
'M_E_CPU0_SA_CB<2>'
 '@S9S_MB_2U_LIB.S9S_MB_2U(SCH_1):M_E_CPU0_SA_CB'<2>:
 C_SIGNAL='@s9s_mb_2u_lib.s9s_mb_2u(sch_1):m_e_cpu0_sa_cb(2)';
NODE_NAME     U2 EP57
 '@S9S_MB_2U_LIB.S9S_MB_2U(SCH_1):PAGE24_I169@PURE_QUANTA.SOCKET4677_AZIF0045P001C01CS(CHIPS)':
 'DDR4_SA_ECC2': CDS_PINID='DDR4_SA_ECC2';
NODE_NAME     J9 196
 '@S9S_MB_2U_LIB.S9S_MB_2U(SCH_1):PAGE90_I12@PURE_QUANTA.SCONN288_ADR50017P130CC(CHIPS)':
 'CB2_A': CDS_PINID='CB2_A';
NODE_NAME     J10 196
 '@S9S_MB_2U_LIB.S9S_MB_2U(SCH_1):PAGE91_I13@PURE_QUANTA.SCONN288_ADR50017P087CC(CHIPS)':
 'CB2_A': CDS_PINID='CB2_A';
NET_NAME
'M_E_CPU0_SA_CB<3>'
 '@S9S_MB_2U_LIB.S9S_MB_2U(SCH_1):M_E_CPU0_SA_CB'<3>:
 C_SIGNAL='@s9s_mb_2u_lib.s9s_mb_2u(sch_1):m_e_cpu0_sa_cb(3)';
NODE_NAME     U2 ER56
 '@S9S_MB_2U_LIB.S9S_MB_2U(SCH_1):PAGE24_I169@PURE_QUANTA.SOCKET4677_AZIF0045P001C01CS(CHIPS)':
 'DDR4_SA_ECC3': CDS_PINID='DDR4_SA_ECC3';
NODE_NAME     J9 198
 '@S9S_MB_2U_LIB.S9S_MB_2U(SCH_1):PAGE90_I12@PURE_QUANTA.SCONN288_ADR50017P130CC(CHIPS)':
 'CB3_A': CDS_PINID='CB3_A';
NODE_NAME     J10 198
 '@S9S_MB_2U_LIB.S9S_MB_2U(SCH_1):PAGE91_I13@PURE_QUANTA.SCONN288_ADR50017P087CC(CHIPS)':
 'CB3_A': CDS_PINID='CB3_A';
NET_NAME
'M_E_CPU0_SA_CB<4>'
 '@S9S_MB_2U_LIB.S9S_MB_2U(SCH_1):M_E_CPU0_SA_CB'<4>:
 C_SIGNAL='@s9s_mb_2u_lib.s9s_mb_2u(sch_1):m_e_cpu0_sa_cb(4)';
NODE_NAME     U2 EL54
 '@S9S_MB_2U_LIB.S9S_MB_2U(SCH_1):PAGE24_I169@PURE_QUANTA.SOCKET4677_AZIF0045P001C01CS(CHIPS)':
 'DDR4_SA_ECC4': CDS_PINID='DDR4_SA_ECC4';
NODE_NAME     J9 58
 '@S9S_MB_2U_LIB.S9S_MB_2U(SCH_1):PAGE90_I12@PURE_QUANTA.SCONN288_ADR50017P130CC(CHIPS)':
 'CB4_A': CDS_PINID='CB4_A';
NODE_NAME     J10 58
 '@S9S_MB_2U_LIB.S9S_MB_2U(SCH_1):PAGE91_I13@PURE_QUANTA.SCONN288_ADR50017P087CC(CHIPS)':
 'CB4_A': CDS_PINID='CB4_A';
NET_NAME
'M_E_CPU0_SA_CB<5>'
 '@S9S_MB_2U_LIB.S9S_MB_2U(SCH_1):M_E_CPU0_SA_CB'<5>:
 C_SIGNAL='@s9s_mb_2u_lib.s9s_mb_2u(sch_1):m_e_cpu0_sa_cb(5)';
NODE_NAME     U2 EM53
 '@S9S_MB_2U_LIB.S9S_MB_2U(SCH_1):PAGE24_I169@PURE_QUANTA.SOCKET4677_AZIF0045P001C01CS(CHIPS)':
 'DDR4_SA_ECC5': CDS_PINID='DDR4_SA_ECC5';
NODE_NAME     J9 60
 '@S9S_MB_2U_LIB.S9S_MB_2U(SCH_1):PAGE90_I12@PURE_QUANTA.SCONN288_ADR50017P130CC(CHIPS)':
 'CB5_A': CDS_PINID='CB5_A';
NODE_NAME     J10 60
 '@S9S_MB_2U_LIB.S9S_MB_2U(SCH_1):PAGE91_I13@PURE_QUANTA.SCONN288_ADR50017P087CC(CHIPS)':
 'CB5_A': CDS_PINID='CB5_A';
NET_NAME
'M_E_CPU0_SA_CB<6>'
 '@S9S_MB_2U_LIB.S9S_MB_2U(SCH_1):M_E_CPU0_SA_CB'<6>:
 C_SIGNAL='@s9s_mb_2u_lib.s9s_mb_2u(sch_1):m_e_cpu0_sa_cb(6)';
NODE_NAME     U2 ER54
 '@S9S_MB_2U_LIB.S9S_MB_2U(SCH_1):PAGE24_I169@PURE_QUANTA.SOCKET4677_AZIF0045P001C01CS(CHIPS)':
 'DDR4_SA_ECC6': CDS_PINID='DDR4_SA_ECC6';
NODE_NAME     J9 203
 '@S9S_MB_2U_LIB.S9S_MB_2U(SCH_1):PAGE90_I12@PURE_QUANTA.SCONN288_ADR50017P130CC(CHIPS)':
 'CB6_A': CDS_PINID='CB6_A';
NODE_NAME     J10 203
 '@S9S_MB_2U_LIB.S9S_MB_2U(SCH_1):PAGE91_I13@PURE_QUANTA.SCONN288_ADR50017P087CC(CHIPS)':
 'CB6_A': CDS_PINID='CB6_A';
NET_NAME
'M_E_CPU0_SA_CB<7>'
 '@S9S_MB_2U_LIB.S9S_MB_2U(SCH_1):M_E_CPU0_SA_CB'<7>:
 C_SIGNAL='@s9s_mb_2u_lib.s9s_mb_2u(sch_1):m_e_cpu0_sa_cb(7)';
NODE_NAME     U2 EP53
 '@S9S_MB_2U_LIB.S9S_MB_2U(SCH_1):PAGE24_I169@PURE_QUANTA.SOCKET4677_AZIF0045P001C01CS(CHIPS)':
 'DDR4_SA_ECC7': CDS_PINID='DDR4_SA_ECC7';
NODE_NAME     J9 205
 '@S9S_MB_2U_LIB.S9S_MB_2U(SCH_1):PAGE90_I12@PURE_QUANTA.SCONN288_ADR50017P130CC(CHIPS)':
 'CB7_A': CDS_PINID='CB7_A';
NODE_NAME     J10 205
 '@S9S_MB_2U_LIB.S9S_MB_2U(SCH_1):PAGE91_I13@PURE_QUANTA.SCONN288_ADR50017P087CC(CHIPS)':
 'CB7_A': CDS_PINID='CB7_A';
NET_NAME
'M_E_CPU0_SA_CS_N<0>'
 '@S9S_MB_2U_LIB.S9S_MB_2U(SCH_1):M_E_CPU0_SA_CS_N'<0>:
 C_SIGNAL='@s9s_mb_2u_lib.s9s_mb_2u(sch_1):m_e_cpu0_sa_cs_n(0)';
NODE_NAME     U2 EP51
 '@S9S_MB_2U_LIB.S9S_MB_2U(SCH_1):PAGE24_I169@PURE_QUANTA.SOCKET4677_AZIF0045P001C01CS(CHIPS)':
 'DDR4_SA_CS_N0': CDS_PINID='DDR4_SA_CS_N0';
NODE_NAME     J9 64
 '@S9S_MB_2U_LIB.S9S_MB_2U(SCH_1):PAGE90_I12@PURE_QUANTA.SCONN288_ADR50017P130CC(CHIPS)':
 'CS0_A_N': CDS_PINID='CS0_A_N';
NET_NAME
'M_E_CPU0_SA_CS_N<1>'
 '@S9S_MB_2U_LIB.S9S_MB_2U(SCH_1):M_E_CPU0_SA_CS_N'<1>:
 C_SIGNAL='@s9s_mb_2u_lib.s9s_mb_2u(sch_1):m_e_cpu0_sa_cs_n(1)';
NODE_NAME     U2 ET51
 '@S9S_MB_2U_LIB.S9S_MB_2U(SCH_1):PAGE24_I169@PURE_QUANTA.SOCKET4677_AZIF0045P001C01CS(CHIPS)':
 'DDR4_SA_CS_N1': CDS_PINID='DDR4_SA_CS_N1';
NODE_NAME     J9 209
 '@S9S_MB_2U_LIB.S9S_MB_2U(SCH_1):PAGE90_I12@PURE_QUANTA.SCONN288_ADR50017P130CC(CHIPS)':
 'CS1_A_N': CDS_PINID='CS1_A_N';
NET_NAME
'M_E_CPU0_SA_CS_N<2>'
 '@S9S_MB_2U_LIB.S9S_MB_2U(SCH_1):M_E_CPU0_SA_CS_N'<2>:
 C_SIGNAL='@s9s_mb_2u_lib.s9s_mb_2u(sch_1):m_e_cpu0_sa_cs_n(2)';
NODE_NAME     U2 EM51
 '@S9S_MB_2U_LIB.S9S_MB_2U(SCH_1):PAGE24_I169@PURE_QUANTA.SOCKET4677_AZIF0045P001C01CS(CHIPS)':
 'DDR4_SA_CS_N2': CDS_PINID='DDR4_SA_CS_N2';
NODE_NAME     J10 64
 '@S9S_MB_2U_LIB.S9S_MB_2U(SCH_1):PAGE91_I13@PURE_QUANTA.SCONN288_ADR50017P087CC(CHIPS)':
 'CS0_A_N': CDS_PINID='CS0_A_N';
NET_NAME
'M_E_CPU0_SA_CS_N<3>'
 '@S9S_MB_2U_LIB.S9S_MB_2U(SCH_1):M_E_CPU0_SA_CS_N'<3>:
 C_SIGNAL='@s9s_mb_2u_lib.s9s_mb_2u(sch_1):m_e_cpu0_sa_cs_n(3)';
NODE_NAME     U2 EL50
 '@S9S_MB_2U_LIB.S9S_MB_2U(SCH_1):PAGE24_I169@PURE_QUANTA.SOCKET4677_AZIF0045P001C01CS(CHIPS)':
 'DDR4_SA_CS_N3': CDS_PINID='DDR4_SA_CS_N3';
NODE_NAME     J10 209
 '@S9S_MB_2U_LIB.S9S_MB_2U(SCH_1):PAGE91_I13@PURE_QUANTA.SCONN288_ADR50017P087CC(CHIPS)':
 'CS1_A_N': CDS_PINID='CS1_A_N';
NET_NAME
'M_E_CPU0_SA_DQ<0>'
 '@S9S_MB_2U_LIB.S9S_MB_2U(SCH_1):M_E_CPU0_SA_DQ'<0>:
 C_SIGNAL='@s9s_mb_2u_lib.s9s_mb_2u(sch_1):m_e_cpu0_sa_dq(0)';
NODE_NAME     U2 EL78
 '@S9S_MB_2U_LIB.S9S_MB_2U(SCH_1):PAGE24_I169@PURE_QUANTA.SOCKET4677_AZIF0045P001C01CS(CHIPS)':
 'DDR4_SA_DQ0': CDS_PINID='DDR4_SA_DQ0';
NODE_NAME     J9 7
 '@S9S_MB_2U_LIB.S9S_MB_2U(SCH_1):PAGE90_I12@PURE_QUANTA.SCONN288_ADR50017P130CC(CHIPS)':
 'DQ0_A': CDS_PINID='DQ0_A';
NODE_NAME     J10 7
 '@S9S_MB_2U_LIB.S9S_MB_2U(SCH_1):PAGE91_I13@PURE_QUANTA.SCONN288_ADR50017P087CC(CHIPS)':
 'DQ0_A': CDS_PINID='DQ0_A';
NET_NAME
'M_E_CPU0_SA_DQ<10>'
 '@S9S_MB_2U_LIB.S9S_MB_2U(SCH_1):M_E_CPU0_SA_DQ'<10>:
 C_SIGNAL='@s9s_mb_2u_lib.s9s_mb_2u(sch_1):m_e_cpu0_sa_dq(10)';
NODE_NAME     U2 EG72
 '@S9S_MB_2U_LIB.S9S_MB_2U(SCH_1):PAGE24_I169@PURE_QUANTA.SOCKET4677_AZIF0045P001C01CS(CHIPS)':
 'DDR4_SA_DQ10': CDS_PINID='DDR4_SA_DQ10';
NODE_NAME     J9 163
 '@S9S_MB_2U_LIB.S9S_MB_2U(SCH_1):PAGE90_I12@PURE_QUANTA.SCONN288_ADR50017P130CC(CHIPS)':
 'DQ10_A': CDS_PINID='DQ10_A';
NODE_NAME     J10 163
 '@S9S_MB_2U_LIB.S9S_MB_2U(SCH_1):PAGE91_I13@PURE_QUANTA.SCONN288_ADR50017P087CC(CHIPS)':
 'DQ10_A': CDS_PINID='DQ10_A';
NET_NAME
'M_E_CPU0_SA_DQ<11>'
 '@S9S_MB_2U_LIB.S9S_MB_2U(SCH_1):M_E_CPU0_SA_DQ'<11>:
 C_SIGNAL='@s9s_mb_2u_lib.s9s_mb_2u(sch_1):m_e_cpu0_sa_dq(11)';
NODE_NAME     U2 EH71
 '@S9S_MB_2U_LIB.S9S_MB_2U(SCH_1):PAGE24_I169@PURE_QUANTA.SOCKET4677_AZIF0045P001C01CS(CHIPS)':
 'DDR4_SA_DQ11': CDS_PINID='DDR4_SA_DQ11';
NODE_NAME     J9 165
 '@S9S_MB_2U_LIB.S9S_MB_2U(SCH_1):PAGE90_I12@PURE_QUANTA.SCONN288_ADR50017P130CC(CHIPS)':
 'DQ11_A': CDS_PINID='DQ11_A';
NODE_NAME     J10 165
 '@S9S_MB_2U_LIB.S9S_MB_2U(SCH_1):PAGE91_I13@PURE_QUANTA.SCONN288_ADR50017P087CC(CHIPS)':
 'DQ11_A': CDS_PINID='DQ11_A';
NET_NAME
'M_E_CPU0_SA_DQ<12>'
 '@S9S_MB_2U_LIB.S9S_MB_2U(SCH_1):M_E_CPU0_SA_DQ'<12>:
 C_SIGNAL='@s9s_mb_2u_lib.s9s_mb_2u(sch_1):m_e_cpu0_sa_dq(12)';
NODE_NAME     U2 ED69
 '@S9S_MB_2U_LIB.S9S_MB_2U(SCH_1):PAGE24_I169@PURE_QUANTA.SOCKET4677_AZIF0045P001C01CS(CHIPS)':
 'DDR4_SA_DQ12': CDS_PINID='DDR4_SA_DQ12';
NODE_NAME     J9 25
 '@S9S_MB_2U_LIB.S9S_MB_2U(SCH_1):PAGE90_I12@PURE_QUANTA.SCONN288_ADR50017P130CC(CHIPS)':
 'DQ12_A': CDS_PINID='DQ12_A';
NODE_NAME     J10 25
 '@S9S_MB_2U_LIB.S9S_MB_2U(SCH_1):PAGE91_I13@PURE_QUANTA.SCONN288_ADR50017P087CC(CHIPS)':
 'DQ12_A': CDS_PINID='DQ12_A';
NET_NAME
'M_E_CPU0_SA_DQ<13>'
 '@S9S_MB_2U_LIB.S9S_MB_2U(SCH_1):M_E_CPU0_SA_DQ'<13>:
 C_SIGNAL='@s9s_mb_2u_lib.s9s_mb_2u(sch_1):m_e_cpu0_sa_dq(13)';
NODE_NAME     U2 EE68
 '@S9S_MB_2U_LIB.S9S_MB_2U(SCH_1):PAGE24_I169@PURE_QUANTA.SOCKET4677_AZIF0045P001C01CS(CHIPS)':
 'DDR4_SA_DQ13': CDS_PINID='DDR4_SA_DQ13';
NODE_NAME     J9 27
 '@S9S_MB_2U_LIB.S9S_MB_2U(SCH_1):PAGE90_I12@PURE_QUANTA.SCONN288_ADR50017P130CC(CHIPS)':
 'DQ13_A': CDS_PINID='DQ13_A';
NODE_NAME     J10 27
 '@S9S_MB_2U_LIB.S9S_MB_2U(SCH_1):PAGE91_I13@PURE_QUANTA.SCONN288_ADR50017P087CC(CHIPS)':
 'DQ13_A': CDS_PINID='DQ13_A';
NET_NAME
'M_E_CPU0_SA_DQ<14>'
 '@S9S_MB_2U_LIB.S9S_MB_2U(SCH_1):M_E_CPU0_SA_DQ'<14>:
 C_SIGNAL='@s9s_mb_2u_lib.s9s_mb_2u(sch_1):m_e_cpu0_sa_dq(14)';
NODE_NAME     U2 EH69
 '@S9S_MB_2U_LIB.S9S_MB_2U(SCH_1):PAGE24_I169@PURE_QUANTA.SOCKET4677_AZIF0045P001C01CS(CHIPS)':
 'DDR4_SA_DQ14': CDS_PINID='DDR4_SA_DQ14';
NODE_NAME     J9 170
 '@S9S_MB_2U_LIB.S9S_MB_2U(SCH_1):PAGE90_I12@PURE_QUANTA.SCONN288_ADR50017P130CC(CHIPS)':
 'DQ14_A': CDS_PINID='DQ14_A';
NODE_NAME     J10 170
 '@S9S_MB_2U_LIB.S9S_MB_2U(SCH_1):PAGE91_I13@PURE_QUANTA.SCONN288_ADR50017P087CC(CHIPS)':
 'DQ14_A': CDS_PINID='DQ14_A';
NET_NAME
'M_E_CPU0_SA_DQ<15>'
 '@S9S_MB_2U_LIB.S9S_MB_2U(SCH_1):M_E_CPU0_SA_DQ'<15>:
 C_SIGNAL='@s9s_mb_2u_lib.s9s_mb_2u(sch_1):m_e_cpu0_sa_dq(15)';
NODE_NAME     U2 EG68
 '@S9S_MB_2U_LIB.S9S_MB_2U(SCH_1):PAGE24_I169@PURE_QUANTA.SOCKET4677_AZIF0045P001C01CS(CHIPS)':
 'DDR4_SA_DQ15': CDS_PINID='DDR4_SA_DQ15';
NODE_NAME     J9 172
 '@S9S_MB_2U_LIB.S9S_MB_2U(SCH_1):PAGE90_I12@PURE_QUANTA.SCONN288_ADR50017P130CC(CHIPS)':
 'DQ15_A': CDS_PINID='DQ15_A';
NODE_NAME     J10 172
 '@S9S_MB_2U_LIB.S9S_MB_2U(SCH_1):PAGE91_I13@PURE_QUANTA.SCONN288_ADR50017P087CC(CHIPS)':
 'DQ15_A': CDS_PINID='DQ15_A';
NET_NAME
'M_E_CPU0_SA_DQ<16>'
 '@S9S_MB_2U_LIB.S9S_MB_2U(SCH_1):M_E_CPU0_SA_DQ'<16>:
 C_SIGNAL='@s9s_mb_2u_lib.s9s_mb_2u(sch_1):m_e_cpu0_sa_dq(16)';
NODE_NAME     U2 EM71
 '@S9S_MB_2U_LIB.S9S_MB_2U(SCH_1):PAGE24_I169@PURE_QUANTA.SOCKET4677_AZIF0045P001C01CS(CHIPS)':
 'DDR4_SA_DQ16': CDS_PINID='DDR4_SA_DQ16';
NODE_NAME     J9 29
 '@S9S_MB_2U_LIB.S9S_MB_2U(SCH_1):PAGE90_I12@PURE_QUANTA.SCONN288_ADR50017P130CC(CHIPS)':
 'DQ16_A': CDS_PINID='DQ16_A';
NODE_NAME     J10 29
 '@S9S_MB_2U_LIB.S9S_MB_2U(SCH_1):PAGE91_I13@PURE_QUANTA.SCONN288_ADR50017P087CC(CHIPS)':
 'DQ16_A': CDS_PINID='DQ16_A';
NET_NAME
'M_E_CPU0_SA_DQ<17>'
 '@S9S_MB_2U_LIB.S9S_MB_2U(SCH_1):M_E_CPU0_SA_DQ'<17>:
 C_SIGNAL='@s9s_mb_2u_lib.s9s_mb_2u(sch_1):m_e_cpu0_sa_dq(17)';
NODE_NAME     U2 EM69
 '@S9S_MB_2U_LIB.S9S_MB_2U(SCH_1):PAGE24_I169@PURE_QUANTA.SOCKET4677_AZIF0045P001C01CS(CHIPS)':
 'DDR4_SA_DQ17': CDS_PINID='DDR4_SA_DQ17';
NODE_NAME     J9 31
 '@S9S_MB_2U_LIB.S9S_MB_2U(SCH_1):PAGE90_I12@PURE_QUANTA.SCONN288_ADR50017P130CC(CHIPS)':
 'DQ17_A': CDS_PINID='DQ17_A';
NODE_NAME     J10 31
 '@S9S_MB_2U_LIB.S9S_MB_2U(SCH_1):PAGE91_I13@PURE_QUANTA.SCONN288_ADR50017P087CC(CHIPS)':
 'DQ17_A': CDS_PINID='DQ17_A';
NET_NAME
'M_E_CPU0_SA_DQ<18>'
 '@S9S_MB_2U_LIB.S9S_MB_2U(SCH_1):M_E_CPU0_SA_DQ'<18>:
 C_SIGNAL='@s9s_mb_2u_lib.s9s_mb_2u(sch_1):m_e_cpu0_sa_dq(18)';
NODE_NAME     U2 EN70
 '@S9S_MB_2U_LIB.S9S_MB_2U(SCH_1):PAGE24_I169@PURE_QUANTA.SOCKET4677_AZIF0045P001C01CS(CHIPS)':
 'DDR4_SA_DQ18': CDS_PINID='DDR4_SA_DQ18';
NODE_NAME     J9 174
 '@S9S_MB_2U_LIB.S9S_MB_2U(SCH_1):PAGE90_I12@PURE_QUANTA.SCONN288_ADR50017P130CC(CHIPS)':
 'DQ18_A': CDS_PINID='DQ18_A';
NODE_NAME     J10 174
 '@S9S_MB_2U_LIB.S9S_MB_2U(SCH_1):PAGE91_I13@PURE_QUANTA.SCONN288_ADR50017P087CC(CHIPS)':
 'DQ18_A': CDS_PINID='DQ18_A';
NET_NAME
'M_E_CPU0_SA_DQ<19>'
 '@S9S_MB_2U_LIB.S9S_MB_2U(SCH_1):M_E_CPU0_SA_DQ'<19>:
 C_SIGNAL='@s9s_mb_2u_lib.s9s_mb_2u(sch_1):m_e_cpu0_sa_dq(19)';
NODE_NAME     U2 ER68
 '@S9S_MB_2U_LIB.S9S_MB_2U(SCH_1):PAGE24_I169@PURE_QUANTA.SOCKET4677_AZIF0045P001C01CS(CHIPS)':
 'DDR4_SA_DQ19': CDS_PINID='DDR4_SA_DQ19';
NODE_NAME     J9 176
 '@S9S_MB_2U_LIB.S9S_MB_2U(SCH_1):PAGE90_I12@PURE_QUANTA.SCONN288_ADR50017P130CC(CHIPS)':
 'DQ19_A': CDS_PINID='DQ19_A';
NODE_NAME     J10 176
 '@S9S_MB_2U_LIB.S9S_MB_2U(SCH_1):PAGE91_I13@PURE_QUANTA.SCONN288_ADR50017P087CC(CHIPS)':
 'DQ19_A': CDS_PINID='DQ19_A';
NET_NAME
'M_E_CPU0_SA_DQ<1>'
 '@S9S_MB_2U_LIB.S9S_MB_2U(SCH_1):M_E_CPU0_SA_DQ'<1>:
 C_SIGNAL='@s9s_mb_2u_lib.s9s_mb_2u(sch_1):m_e_cpu0_sa_dq(1)';
NODE_NAME     U2 EM77
 '@S9S_MB_2U_LIB.S9S_MB_2U(SCH_1):PAGE24_I169@PURE_QUANTA.SOCKET4677_AZIF0045P001C01CS(CHIPS)':
 'DDR4_SA_DQ1': CDS_PINID='DDR4_SA_DQ1';
NODE_NAME     J9 9
 '@S9S_MB_2U_LIB.S9S_MB_2U(SCH_1):PAGE90_I12@PURE_QUANTA.SCONN288_ADR50017P130CC(CHIPS)':
 'DQ1_A': CDS_PINID='DQ1_A';
NODE_NAME     J10 9
 '@S9S_MB_2U_LIB.S9S_MB_2U(SCH_1):PAGE91_I13@PURE_QUANTA.SCONN288_ADR50017P087CC(CHIPS)':
 'DQ1_A': CDS_PINID='DQ1_A';
NET_NAME
'M_E_CPU0_SA_DQ<20>'
 '@S9S_MB_2U_LIB.S9S_MB_2U(SCH_1):M_E_CPU0_SA_DQ'<20>:
 C_SIGNAL='@s9s_mb_2u_lib.s9s_mb_2u(sch_1):m_e_cpu0_sa_dq(20)';
NODE_NAME     U2 ER66
 '@S9S_MB_2U_LIB.S9S_MB_2U(SCH_1):PAGE24_I169@PURE_QUANTA.SOCKET4677_AZIF0045P001C01CS(CHIPS)':
 'DDR4_SA_DQ20': CDS_PINID='DDR4_SA_DQ20';
NODE_NAME     J9 36
 '@S9S_MB_2U_LIB.S9S_MB_2U(SCH_1):PAGE90_I12@PURE_QUANTA.SCONN288_ADR50017P130CC(CHIPS)':
 'DQ20_A': CDS_PINID='DQ20_A';
NODE_NAME     J10 36
 '@S9S_MB_2U_LIB.S9S_MB_2U(SCH_1):PAGE91_I13@PURE_QUANTA.SCONN288_ADR50017P087CC(CHIPS)':
 'DQ20_A': CDS_PINID='DQ20_A';
NET_NAME
'M_E_CPU0_SA_DQ<21>'
 '@S9S_MB_2U_LIB.S9S_MB_2U(SCH_1):M_E_CPU0_SA_DQ'<21>:
 C_SIGNAL='@s9s_mb_2u_lib.s9s_mb_2u(sch_1):m_e_cpu0_sa_dq(21)';
NODE_NAME     U2 EM65
 '@S9S_MB_2U_LIB.S9S_MB_2U(SCH_1):PAGE24_I169@PURE_QUANTA.SOCKET4677_AZIF0045P001C01CS(CHIPS)':
 'DDR4_SA_DQ21': CDS_PINID='DDR4_SA_DQ21';
NODE_NAME     J9 38
 '@S9S_MB_2U_LIB.S9S_MB_2U(SCH_1):PAGE90_I12@PURE_QUANTA.SCONN288_ADR50017P130CC(CHIPS)':
 'DQ21_A': CDS_PINID='DQ21_A';
NODE_NAME     J10 38
 '@S9S_MB_2U_LIB.S9S_MB_2U(SCH_1):PAGE91_I13@PURE_QUANTA.SCONN288_ADR50017P087CC(CHIPS)':
 'DQ21_A': CDS_PINID='DQ21_A';
NET_NAME
'M_E_CPU0_SA_DQ<22>'
 '@S9S_MB_2U_LIB.S9S_MB_2U(SCH_1):M_E_CPU0_SA_DQ'<22>:
 C_SIGNAL='@s9s_mb_2u_lib.s9s_mb_2u(sch_1):m_e_cpu0_sa_dq(22)';
NODE_NAME     U2 EL66
 '@S9S_MB_2U_LIB.S9S_MB_2U(SCH_1):PAGE24_I169@PURE_QUANTA.SOCKET4677_AZIF0045P001C01CS(CHIPS)':
 'DDR4_SA_DQ22': CDS_PINID='DDR4_SA_DQ22';
NODE_NAME     J9 181
 '@S9S_MB_2U_LIB.S9S_MB_2U(SCH_1):PAGE90_I12@PURE_QUANTA.SCONN288_ADR50017P130CC(CHIPS)':
 'DQ22_A': CDS_PINID='DQ22_A';
NODE_NAME     J10 181
 '@S9S_MB_2U_LIB.S9S_MB_2U(SCH_1):PAGE91_I13@PURE_QUANTA.SCONN288_ADR50017P087CC(CHIPS)':
 'DQ22_A': CDS_PINID='DQ22_A';
NET_NAME
'M_E_CPU0_SA_DQ<23>'
 '@S9S_MB_2U_LIB.S9S_MB_2U(SCH_1):M_E_CPU0_SA_DQ'<23>:
 C_SIGNAL='@s9s_mb_2u_lib.s9s_mb_2u(sch_1):m_e_cpu0_sa_dq(23)';
NODE_NAME     U2 EP65
 '@S9S_MB_2U_LIB.S9S_MB_2U(SCH_1):PAGE24_I169@PURE_QUANTA.SOCKET4677_AZIF0045P001C01CS(CHIPS)':
 'DDR4_SA_DQ23': CDS_PINID='DDR4_SA_DQ23';
NODE_NAME     J9 183
 '@S9S_MB_2U_LIB.S9S_MB_2U(SCH_1):PAGE90_I12@PURE_QUANTA.SCONN288_ADR50017P130CC(CHIPS)':
 'DQ23_A': CDS_PINID='DQ23_A';
NODE_NAME     J10 183
 '@S9S_MB_2U_LIB.S9S_MB_2U(SCH_1):PAGE91_I13@PURE_QUANTA.SCONN288_ADR50017P087CC(CHIPS)':
 'DQ23_A': CDS_PINID='DQ23_A';
NET_NAME
'M_E_CPU0_SA_DQ<24>'
 '@S9S_MB_2U_LIB.S9S_MB_2U(SCH_1):M_E_CPU0_SA_DQ'<24>:
 C_SIGNAL='@s9s_mb_2u_lib.s9s_mb_2u(sch_1):m_e_cpu0_sa_dq(24)';
NODE_NAME     U2 EM63
 '@S9S_MB_2U_LIB.S9S_MB_2U(SCH_1):PAGE24_I169@PURE_QUANTA.SOCKET4677_AZIF0045P001C01CS(CHIPS)':
 'DDR4_SA_DQ24': CDS_PINID='DDR4_SA_DQ24';
NODE_NAME     J9 40
 '@S9S_MB_2U_LIB.S9S_MB_2U(SCH_1):PAGE90_I12@PURE_QUANTA.SCONN288_ADR50017P130CC(CHIPS)':
 'DQ24_A': CDS_PINID='DQ24_A';
NODE_NAME     J10 40
 '@S9S_MB_2U_LIB.S9S_MB_2U(SCH_1):PAGE91_I13@PURE_QUANTA.SCONN288_ADR50017P087CC(CHIPS)':
 'DQ24_A': CDS_PINID='DQ24_A';
NET_NAME
'M_E_CPU0_SA_DQ<25>'
 '@S9S_MB_2U_LIB.S9S_MB_2U(SCH_1):M_E_CPU0_SA_DQ'<25>:
 C_SIGNAL='@s9s_mb_2u_lib.s9s_mb_2u(sch_1):m_e_cpu0_sa_dq(25)';
NODE_NAME     U2 EL62
 '@S9S_MB_2U_LIB.S9S_MB_2U(SCH_1):PAGE24_I169@PURE_QUANTA.SOCKET4677_AZIF0045P001C01CS(CHIPS)':
 'DDR4_SA_DQ25': CDS_PINID='DDR4_SA_DQ25';
NODE_NAME     J9 42
 '@S9S_MB_2U_LIB.S9S_MB_2U(SCH_1):PAGE90_I12@PURE_QUANTA.SCONN288_ADR50017P130CC(CHIPS)':
 'DQ25_A': CDS_PINID='DQ25_A';
NODE_NAME     J10 42
 '@S9S_MB_2U_LIB.S9S_MB_2U(SCH_1):PAGE91_I13@PURE_QUANTA.SCONN288_ADR50017P087CC(CHIPS)':
 'DQ25_A': CDS_PINID='DQ25_A';
NET_NAME
'M_E_CPU0_SA_DQ<26>'
 '@S9S_MB_2U_LIB.S9S_MB_2U(SCH_1):M_E_CPU0_SA_DQ'<26>:
 C_SIGNAL='@s9s_mb_2u_lib.s9s_mb_2u(sch_1):m_e_cpu0_sa_dq(26)';
NODE_NAME     U2 EP63
 '@S9S_MB_2U_LIB.S9S_MB_2U(SCH_1):PAGE24_I169@PURE_QUANTA.SOCKET4677_AZIF0045P001C01CS(CHIPS)':
 'DDR4_SA_DQ26': CDS_PINID='DDR4_SA_DQ26';
NODE_NAME     J9 185
 '@S9S_MB_2U_LIB.S9S_MB_2U(SCH_1):PAGE90_I12@PURE_QUANTA.SCONN288_ADR50017P130CC(CHIPS)':
 'DQ26_A': CDS_PINID='DQ26_A';
NODE_NAME     J10 185
 '@S9S_MB_2U_LIB.S9S_MB_2U(SCH_1):PAGE91_I13@PURE_QUANTA.SCONN288_ADR50017P087CC(CHIPS)':
 'DQ26_A': CDS_PINID='DQ26_A';
NET_NAME
'M_E_CPU0_SA_DQ<27>'
 '@S9S_MB_2U_LIB.S9S_MB_2U(SCH_1):M_E_CPU0_SA_DQ'<27>:
 C_SIGNAL='@s9s_mb_2u_lib.s9s_mb_2u(sch_1):m_e_cpu0_sa_dq(27)';
NODE_NAME     U2 ER62
 '@S9S_MB_2U_LIB.S9S_MB_2U(SCH_1):PAGE24_I169@PURE_QUANTA.SOCKET4677_AZIF0045P001C01CS(CHIPS)':
 'DDR4_SA_DQ27': CDS_PINID='DDR4_SA_DQ27';
NODE_NAME     J9 187
 '@S9S_MB_2U_LIB.S9S_MB_2U(SCH_1):PAGE90_I12@PURE_QUANTA.SCONN288_ADR50017P130CC(CHIPS)':
 'DQ27_A': CDS_PINID='DQ27_A';
NODE_NAME     J10 187
 '@S9S_MB_2U_LIB.S9S_MB_2U(SCH_1):PAGE91_I13@PURE_QUANTA.SCONN288_ADR50017P087CC(CHIPS)':
 'DQ27_A': CDS_PINID='DQ27_A';
NET_NAME
'M_E_CPU0_SA_DQ<28>'
 '@S9S_MB_2U_LIB.S9S_MB_2U(SCH_1):M_E_CPU0_SA_DQ'<28>:
 C_SIGNAL='@s9s_mb_2u_lib.s9s_mb_2u(sch_1):m_e_cpu0_sa_dq(28)';
NODE_NAME     U2 EL60
 '@S9S_MB_2U_LIB.S9S_MB_2U(SCH_1):PAGE24_I169@PURE_QUANTA.SOCKET4677_AZIF0045P001C01CS(CHIPS)':
 'DDR4_SA_DQ28': CDS_PINID='DDR4_SA_DQ28';
NODE_NAME     J9 47
 '@S9S_MB_2U_LIB.S9S_MB_2U(SCH_1):PAGE90_I12@PURE_QUANTA.SCONN288_ADR50017P130CC(CHIPS)':
 'DQ28_A': CDS_PINID='DQ28_A';
NODE_NAME     J10 47
 '@S9S_MB_2U_LIB.S9S_MB_2U(SCH_1):PAGE91_I13@PURE_QUANTA.SCONN288_ADR50017P087CC(CHIPS)':
 'DQ28_A': CDS_PINID='DQ28_A';
NET_NAME
'M_E_CPU0_SA_DQ<29>'
 '@S9S_MB_2U_LIB.S9S_MB_2U(SCH_1):M_E_CPU0_SA_DQ'<29>:
 C_SIGNAL='@s9s_mb_2u_lib.s9s_mb_2u(sch_1):m_e_cpu0_sa_dq(29)';
NODE_NAME     U2 EM59
 '@S9S_MB_2U_LIB.S9S_MB_2U(SCH_1):PAGE24_I169@PURE_QUANTA.SOCKET4677_AZIF0045P001C01CS(CHIPS)':
 'DDR4_SA_DQ29': CDS_PINID='DDR4_SA_DQ29';
NODE_NAME     J9 49
 '@S9S_MB_2U_LIB.S9S_MB_2U(SCH_1):PAGE90_I12@PURE_QUANTA.SCONN288_ADR50017P130CC(CHIPS)':
 'DQ29_A': CDS_PINID='DQ29_A';
NODE_NAME     J10 49
 '@S9S_MB_2U_LIB.S9S_MB_2U(SCH_1):PAGE91_I13@PURE_QUANTA.SCONN288_ADR50017P087CC(CHIPS)':
 'DQ29_A': CDS_PINID='DQ29_A';
NET_NAME
'M_E_CPU0_SA_DQ<2>'
 '@S9S_MB_2U_LIB.S9S_MB_2U(SCH_1):M_E_CPU0_SA_DQ'<2>:
 C_SIGNAL='@s9s_mb_2u_lib.s9s_mb_2u(sch_1):m_e_cpu0_sa_dq(2)';
NODE_NAME     U2 EP79
 '@S9S_MB_2U_LIB.S9S_MB_2U(SCH_1):PAGE24_I169@PURE_QUANTA.SOCKET4677_AZIF0045P001C01CS(CHIPS)':
 'DDR4_SA_DQ2': CDS_PINID='DDR4_SA_DQ2';
NODE_NAME     J9 152
 '@S9S_MB_2U_LIB.S9S_MB_2U(SCH_1):PAGE90_I12@PURE_QUANTA.SCONN288_ADR50017P130CC(CHIPS)':
 'DQ2_A': CDS_PINID='DQ2_A';
NODE_NAME     J10 152
 '@S9S_MB_2U_LIB.S9S_MB_2U(SCH_1):PAGE91_I13@PURE_QUANTA.SCONN288_ADR50017P087CC(CHIPS)':
 'DQ2_A': CDS_PINID='DQ2_A';
NET_NAME
'M_E_CPU0_SA_DQ<30>'
 '@S9S_MB_2U_LIB.S9S_MB_2U(SCH_1):M_E_CPU0_SA_DQ'<30>:
 C_SIGNAL='@s9s_mb_2u_lib.s9s_mb_2u(sch_1):m_e_cpu0_sa_dq(30)';
NODE_NAME     U2 ER60
 '@S9S_MB_2U_LIB.S9S_MB_2U(SCH_1):PAGE24_I169@PURE_QUANTA.SOCKET4677_AZIF0045P001C01CS(CHIPS)':
 'DDR4_SA_DQ30': CDS_PINID='DDR4_SA_DQ30';
NODE_NAME     J9 192
 '@S9S_MB_2U_LIB.S9S_MB_2U(SCH_1):PAGE90_I12@PURE_QUANTA.SCONN288_ADR50017P130CC(CHIPS)':
 'DQ30_A': CDS_PINID='DQ30_A';
NODE_NAME     J10 192
 '@S9S_MB_2U_LIB.S9S_MB_2U(SCH_1):PAGE91_I13@PURE_QUANTA.SCONN288_ADR50017P087CC(CHIPS)':
 'DQ30_A': CDS_PINID='DQ30_A';
NET_NAME
'M_E_CPU0_SA_DQ<31>'
 '@S9S_MB_2U_LIB.S9S_MB_2U(SCH_1):M_E_CPU0_SA_DQ'<31>:
 C_SIGNAL='@s9s_mb_2u_lib.s9s_mb_2u(sch_1):m_e_cpu0_sa_dq(31)';
NODE_NAME     U2 EP59
 '@S9S_MB_2U_LIB.S9S_MB_2U(SCH_1):PAGE24_I169@PURE_QUANTA.SOCKET4677_AZIF0045P001C01CS(CHIPS)':
 'DDR4_SA_DQ31': CDS_PINID='DDR4_SA_DQ31';
NODE_NAME     J9 194
 '@S9S_MB_2U_LIB.S9S_MB_2U(SCH_1):PAGE90_I12@PURE_QUANTA.SCONN288_ADR50017P130CC(CHIPS)':
 'DQ31_A': CDS_PINID='DQ31_A';
NODE_NAME     J10 194
 '@S9S_MB_2U_LIB.S9S_MB_2U(SCH_1):PAGE91_I13@PURE_QUANTA.SCONN288_ADR50017P087CC(CHIPS)':
 'DQ31_A': CDS_PINID='DQ31_A';
NET_NAME
'M_E_CPU0_SA_DQ<3>'
 '@S9S_MB_2U_LIB.S9S_MB_2U(SCH_1):M_E_CPU0_SA_DQ'<3>:
 C_SIGNAL='@s9s_mb_2u_lib.s9s_mb_2u(sch_1):m_e_cpu0_sa_dq(3)';
NODE_NAME     U2 ER76
 '@S9S_MB_2U_LIB.S9S_MB_2U(SCH_1):PAGE24_I169@PURE_QUANTA.SOCKET4677_AZIF0045P001C01CS(CHIPS)':
 'DDR4_SA_DQ3': CDS_PINID='DDR4_SA_DQ3';
NODE_NAME     J9 154
 '@S9S_MB_2U_LIB.S9S_MB_2U(SCH_1):PAGE90_I12@PURE_QUANTA.SCONN288_ADR50017P130CC(CHIPS)':
 'DQ3_A': CDS_PINID='DQ3_A';
NODE_NAME     J10 154
 '@S9S_MB_2U_LIB.S9S_MB_2U(SCH_1):PAGE91_I13@PURE_QUANTA.SCONN288_ADR50017P087CC(CHIPS)':
 'DQ3_A': CDS_PINID='DQ3_A';
NET_NAME
'M_E_CPU0_SA_DQ<4>'
 '@S9S_MB_2U_LIB.S9S_MB_2U(SCH_1):M_E_CPU0_SA_DQ'<4>:
 C_SIGNAL='@s9s_mb_2u_lib.s9s_mb_2u(sch_1):m_e_cpu0_sa_dq(4)';
NODE_NAME     U2 EL74
 '@S9S_MB_2U_LIB.S9S_MB_2U(SCH_1):PAGE24_I169@PURE_QUANTA.SOCKET4677_AZIF0045P001C01CS(CHIPS)':
 'DDR4_SA_DQ4': CDS_PINID='DDR4_SA_DQ4';
NODE_NAME     J9 14
 '@S9S_MB_2U_LIB.S9S_MB_2U(SCH_1):PAGE90_I12@PURE_QUANTA.SCONN288_ADR50017P130CC(CHIPS)':
 'DQ4_A': CDS_PINID='DQ4_A';
NODE_NAME     J10 14
 '@S9S_MB_2U_LIB.S9S_MB_2U(SCH_1):PAGE91_I13@PURE_QUANTA.SCONN288_ADR50017P087CC(CHIPS)':
 'DQ4_A': CDS_PINID='DQ4_A';
NET_NAME
'M_E_CPU0_SA_DQ<5>'
 '@S9S_MB_2U_LIB.S9S_MB_2U(SCH_1):M_E_CPU0_SA_DQ'<5>:
 C_SIGNAL='@s9s_mb_2u_lib.s9s_mb_2u(sch_1):m_e_cpu0_sa_dq(5)';
NODE_NAME     U2 EK73
 '@S9S_MB_2U_LIB.S9S_MB_2U(SCH_1):PAGE24_I169@PURE_QUANTA.SOCKET4677_AZIF0045P001C01CS(CHIPS)':
 'DDR4_SA_DQ5': CDS_PINID='DDR4_SA_DQ5';
NODE_NAME     J9 16
 '@S9S_MB_2U_LIB.S9S_MB_2U(SCH_1):PAGE90_I12@PURE_QUANTA.SCONN288_ADR50017P130CC(CHIPS)':
 'DQ5_A': CDS_PINID='DQ5_A';
NODE_NAME     J10 16
 '@S9S_MB_2U_LIB.S9S_MB_2U(SCH_1):PAGE91_I13@PURE_QUANTA.SCONN288_ADR50017P087CC(CHIPS)':
 'DQ5_A': CDS_PINID='DQ5_A';
NET_NAME
'M_E_CPU0_SA_DQ<6>'
 '@S9S_MB_2U_LIB.S9S_MB_2U(SCH_1):M_E_CPU0_SA_DQ'<6>:
 C_SIGNAL='@s9s_mb_2u_lib.s9s_mb_2u(sch_1):m_e_cpu0_sa_dq(6)';
NODE_NAME     U2 EP73
 '@S9S_MB_2U_LIB.S9S_MB_2U(SCH_1):PAGE24_I169@PURE_QUANTA.SOCKET4677_AZIF0045P001C01CS(CHIPS)':
 'DDR4_SA_DQ6': CDS_PINID='DDR4_SA_DQ6';
NODE_NAME     J9 159
 '@S9S_MB_2U_LIB.S9S_MB_2U(SCH_1):PAGE90_I12@PURE_QUANTA.SCONN288_ADR50017P130CC(CHIPS)':
 'DQ6_A': CDS_PINID='DQ6_A';
NODE_NAME     J10 159
 '@S9S_MB_2U_LIB.S9S_MB_2U(SCH_1):PAGE91_I13@PURE_QUANTA.SCONN288_ADR50017P087CC(CHIPS)':
 'DQ6_A': CDS_PINID='DQ6_A';
NET_NAME
'M_E_CPU0_SA_DQ<7>'
 '@S9S_MB_2U_LIB.S9S_MB_2U(SCH_1):M_E_CPU0_SA_DQ'<7>:
 C_SIGNAL='@s9s_mb_2u_lib.s9s_mb_2u(sch_1):m_e_cpu0_sa_dq(7)';
NODE_NAME     U2 ER72
 '@S9S_MB_2U_LIB.S9S_MB_2U(SCH_1):PAGE24_I169@PURE_QUANTA.SOCKET4677_AZIF0045P001C01CS(CHIPS)':
 'DDR4_SA_DQ7': CDS_PINID='DDR4_SA_DQ7';
NODE_NAME     J9 161
 '@S9S_MB_2U_LIB.S9S_MB_2U(SCH_1):PAGE90_I12@PURE_QUANTA.SCONN288_ADR50017P130CC(CHIPS)':
 'DQ7_A': CDS_PINID='DQ7_A';
NODE_NAME     J10 161
 '@S9S_MB_2U_LIB.S9S_MB_2U(SCH_1):PAGE91_I13@PURE_QUANTA.SCONN288_ADR50017P087CC(CHIPS)':
 'DQ7_A': CDS_PINID='DQ7_A';
NET_NAME
'M_E_CPU0_SA_DQ<8>'
 '@S9S_MB_2U_LIB.S9S_MB_2U(SCH_1):M_E_CPU0_SA_DQ'<8>:
 C_SIGNAL='@s9s_mb_2u_lib.s9s_mb_2u(sch_1):m_e_cpu0_sa_dq(8)';
NODE_NAME     U2 EE72
 '@S9S_MB_2U_LIB.S9S_MB_2U(SCH_1):PAGE24_I169@PURE_QUANTA.SOCKET4677_AZIF0045P001C01CS(CHIPS)':
 'DDR4_SA_DQ8': CDS_PINID='DDR4_SA_DQ8';
NODE_NAME     J9 18
 '@S9S_MB_2U_LIB.S9S_MB_2U(SCH_1):PAGE90_I12@PURE_QUANTA.SCONN288_ADR50017P130CC(CHIPS)':
 'DQ8_A': CDS_PINID='DQ8_A';
NODE_NAME     J10 18
 '@S9S_MB_2U_LIB.S9S_MB_2U(SCH_1):PAGE91_I13@PURE_QUANTA.SCONN288_ADR50017P087CC(CHIPS)':
 'DQ8_A': CDS_PINID='DQ8_A';
NET_NAME
'M_E_CPU0_SA_DQ<9>'
 '@S9S_MB_2U_LIB.S9S_MB_2U(SCH_1):M_E_CPU0_SA_DQ'<9>:
 C_SIGNAL='@s9s_mb_2u_lib.s9s_mb_2u(sch_1):m_e_cpu0_sa_dq(9)';
NODE_NAME     U2 ED71
 '@S9S_MB_2U_LIB.S9S_MB_2U(SCH_1):PAGE24_I169@PURE_QUANTA.SOCKET4677_AZIF0045P001C01CS(CHIPS)':
 'DDR4_SA_DQ9': CDS_PINID='DDR4_SA_DQ9';
NODE_NAME     J9 20
 '@S9S_MB_2U_LIB.S9S_MB_2U(SCH_1):PAGE90_I12@PURE_QUANTA.SCONN288_ADR50017P130CC(CHIPS)':
 'DQ9_A': CDS_PINID='DQ9_A';
NODE_NAME     J10 20
 '@S9S_MB_2U_LIB.S9S_MB_2U(SCH_1):PAGE91_I13@PURE_QUANTA.SCONN288_ADR50017P087CC(CHIPS)':
 'DQ9_A': CDS_PINID='DQ9_A';
NET_NAME
'M_E_CPU0_SA_DQS_DN<0>'
 '@S9S_MB_2U_LIB.S9S_MB_2U(SCH_1):M_E_CPU0_SA_DQS_DN'<0>:
 C_SIGNAL='@s9s_mb_2u_lib.s9s_mb_2u(sch_1):m_e_cpu0_sa_dqs_dn(0)';
NODE_NAME     U2 EP75
 '@S9S_MB_2U_LIB.S9S_MB_2U(SCH_1):PAGE24_I169@PURE_QUANTA.SOCKET4677_AZIF0045P001C01CS(CHIPS)':
 'DDR4_SA_DQS_DN0': CDS_PINID='DDR4_SA_DQS_DN0';
NODE_NAME     J9 12
 '@S9S_MB_2U_LIB.S9S_MB_2U(SCH_1):PAGE90_I178@PURE_QUANTA.SCONN288_ADR50017P130CC(CHIPS)':
 'DQS0_A_C': CDS_PINID='DQS0_A_C';
NODE_NAME     J10 12
 '@S9S_MB_2U_LIB.S9S_MB_2U(SCH_1):PAGE91_I178@PURE_QUANTA.SCONN288_ADR50017P087CC(CHIPS)':
 'DQS0_A_C': CDS_PINID='DQS0_A_C';
NET_NAME
'M_E_CPU0_SA_DQS_DN<1>'
 '@S9S_MB_2U_LIB.S9S_MB_2U(SCH_1):M_E_CPU0_SA_DQS_DN'<1>:
 C_SIGNAL='@s9s_mb_2u_lib.s9s_mb_2u(sch_1):m_e_cpu0_sa_dqs_dn(1)';
NODE_NAME     U2 EC70
 '@S9S_MB_2U_LIB.S9S_MB_2U(SCH_1):PAGE24_I169@PURE_QUANTA.SOCKET4677_AZIF0045P001C01CS(CHIPS)':
 'DDR4_SA_DQS_DN1': CDS_PINID='DDR4_SA_DQS_DN1';
NODE_NAME     J9 23
 '@S9S_MB_2U_LIB.S9S_MB_2U(SCH_1):PAGE90_I178@PURE_QUANTA.SCONN288_ADR50017P130CC(CHIPS)':
 'DQS1_A_C': CDS_PINID='DQS1_A_C';
NODE_NAME     J10 23
 '@S9S_MB_2U_LIB.S9S_MB_2U(SCH_1):PAGE91_I178@PURE_QUANTA.SCONN288_ADR50017P087CC(CHIPS)':
 'DQS1_A_C': CDS_PINID='DQS1_A_C';
NET_NAME
'M_E_CPU0_SA_DQS_DN<2>'
 '@S9S_MB_2U_LIB.S9S_MB_2U(SCH_1):M_E_CPU0_SA_DQS_DN'<2>:
 C_SIGNAL='@s9s_mb_2u_lib.s9s_mb_2u(sch_1):m_e_cpu0_sa_dqs_dn(2)';
NODE_NAME     U2 EK67
 '@S9S_MB_2U_LIB.S9S_MB_2U(SCH_1):PAGE24_I169@PURE_QUANTA.SOCKET4677_AZIF0045P001C01CS(CHIPS)':
 'DDR4_SA_DQS_DN2': CDS_PINID='DDR4_SA_DQS_DN2';
NODE_NAME     J9 34
 '@S9S_MB_2U_LIB.S9S_MB_2U(SCH_1):PAGE90_I178@PURE_QUANTA.SCONN288_ADR50017P130CC(CHIPS)':
 'DQS2_A_C': CDS_PINID='DQS2_A_C';
NODE_NAME     J10 34
 '@S9S_MB_2U_LIB.S9S_MB_2U(SCH_1):PAGE91_I178@PURE_QUANTA.SCONN288_ADR50017P087CC(CHIPS)':
 'DQS2_A_C': CDS_PINID='DQS2_A_C';
NET_NAME
'M_E_CPU0_SA_DQS_DN<3>'
 '@S9S_MB_2U_LIB.S9S_MB_2U(SCH_1):M_E_CPU0_SA_DQS_DN'<3>:
 C_SIGNAL='@s9s_mb_2u_lib.s9s_mb_2u(sch_1):m_e_cpu0_sa_dqs_dn(3)';
NODE_NAME     U2 EK61
 '@S9S_MB_2U_LIB.S9S_MB_2U(SCH_1):PAGE24_I169@PURE_QUANTA.SOCKET4677_AZIF0045P001C01CS(CHIPS)':
 'DDR4_SA_DQS_DN3': CDS_PINID='DDR4_SA_DQS_DN3';
NODE_NAME     J9 45
 '@S9S_MB_2U_LIB.S9S_MB_2U(SCH_1):PAGE90_I178@PURE_QUANTA.SCONN288_ADR50017P130CC(CHIPS)':
 'DQS3_A_C': CDS_PINID='DQS3_A_C';
NODE_NAME     J10 45
 '@S9S_MB_2U_LIB.S9S_MB_2U(SCH_1):PAGE91_I178@PURE_QUANTA.SCONN288_ADR50017P087CC(CHIPS)':
 'DQS3_A_C': CDS_PINID='DQS3_A_C';
NET_NAME
'M_E_CPU0_SA_DQS_DN<4>'
 '@S9S_MB_2U_LIB.S9S_MB_2U(SCH_1):M_E_CPU0_SA_DQS_DN'<4>:
 C_SIGNAL='@s9s_mb_2u_lib.s9s_mb_2u(sch_1):m_e_cpu0_sa_dqs_dn(4)';
NODE_NAME     U2 EM55
 '@S9S_MB_2U_LIB.S9S_MB_2U(SCH_1):PAGE24_I169@PURE_QUANTA.SOCKET4677_AZIF0045P001C01CS(CHIPS)':
 'DDR4_SA_DQS_DN4': CDS_PINID='DDR4_SA_DQS_DN4';
NODE_NAME     J9 56
 '@S9S_MB_2U_LIB.S9S_MB_2U(SCH_1):PAGE90_I178@PURE_QUANTA.SCONN288_ADR50017P130CC(CHIPS)':
 'DQS4_A_C': CDS_PINID='DQS4_A_C';
NODE_NAME     J10 56
 '@S9S_MB_2U_LIB.S9S_MB_2U(SCH_1):PAGE91_I178@PURE_QUANTA.SCONN288_ADR50017P087CC(CHIPS)':
 'DQS4_A_C': CDS_PINID='DQS4_A_C';
NET_NAME
'M_E_CPU0_SA_DQS_DN<5>'
 '@S9S_MB_2U_LIB.S9S_MB_2U(SCH_1):M_E_CPU0_SA_DQS_DN'<5>:
 C_SIGNAL='@s9s_mb_2u_lib.s9s_mb_2u(sch_1):m_e_cpu0_sa_dqs_dn(5)';
NODE_NAME     U2 EM75
 '@S9S_MB_2U_LIB.S9S_MB_2U(SCH_1):PAGE24_I169@PURE_QUANTA.SOCKET4677_AZIF0045P001C01CS(CHIPS)':
 'DDR4_SA_DQS_DN5': CDS_PINID='DDR4_SA_DQS_DN5';
NODE_NAME     J9 156
 '@S9S_MB_2U_LIB.S9S_MB_2U(SCH_1):PAGE90_I178@PURE_QUANTA.SCONN288_ADR50017P130CC(CHIPS)':
 'DQS5_A_C||TDQS5_A_C||DQS5_A_T||TDQS5_A_T': CDS_PINID='\dqs5_a_c||tdqs5_a_c||dqs5_a_t||tdqs5_a_t\';
NODE_NAME     J10 156
 '@S9S_MB_2U_LIB.S9S_MB_2U(SCH_1):PAGE91_I178@PURE_QUANTA.SCONN288_ADR50017P087CC(CHIPS)':
 'DQS5_A_C||TDQS5_A_C||DQS5_A_T||TDQS5_A_T': CDS_PINID='\dqs5_a_c||tdqs5_a_c||dqs5_a_t||tdqs5_a_t\';
NET_NAME
'M_E_CPU0_SA_DQS_DN<6>'
 '@S9S_MB_2U_LIB.S9S_MB_2U(SCH_1):M_E_CPU0_SA_DQS_DN'<6>:
 C_SIGNAL='@s9s_mb_2u_lib.s9s_mb_2u(sch_1):m_e_cpu0_sa_dqs_dn(6)';
NODE_NAME     U2 EJ70
 '@S9S_MB_2U_LIB.S9S_MB_2U(SCH_1):PAGE24_I169@PURE_QUANTA.SOCKET4677_AZIF0045P001C01CS(CHIPS)':
 'DDR4_SA_DQS_DN6': CDS_PINID='DDR4_SA_DQS_DN6';
NODE_NAME     J9 167
 '@S9S_MB_2U_LIB.S9S_MB_2U(SCH_1):PAGE90_I178@PURE_QUANTA.SCONN288_ADR50017P130CC(CHIPS)':
 'DQS6_A_C||TDQS6_A_C||DQS6_A_T||TDQS6_A_T': CDS_PINID='\dqs6_a_c||tdqs6_a_c||dqs6_a_t||tdqs6_a_t\';
NODE_NAME     J10 167
 '@S9S_MB_2U_LIB.S9S_MB_2U(SCH_1):PAGE91_I178@PURE_QUANTA.SCONN288_ADR50017P087CC(CHIPS)':
 'DQS6_A_C||TDQS6_A_C||DQS6_A_T||TDQS6_A_T': CDS_PINID='\dqs6_a_c||tdqs6_a_c||dqs6_a_t||tdqs6_a_t\';
NET_NAME
'M_E_CPU0_SA_DQS_DN<7>'
 '@S9S_MB_2U_LIB.S9S_MB_2U(SCH_1):M_E_CPU0_SA_DQS_DN'<7>:
 C_SIGNAL='@s9s_mb_2u_lib.s9s_mb_2u(sch_1):m_e_cpu0_sa_dqs_dn(7)';
NODE_NAME     U2 EN68
 '@S9S_MB_2U_LIB.S9S_MB_2U(SCH_1):PAGE24_I169@PURE_QUANTA.SOCKET4677_AZIF0045P001C01CS(CHIPS)':
 'DDR4_SA_DQS_DN7': CDS_PINID='DDR4_SA_DQS_DN7';
NODE_NAME     J9 178
 '@S9S_MB_2U_LIB.S9S_MB_2U(SCH_1):PAGE90_I178@PURE_QUANTA.SCONN288_ADR50017P130CC(CHIPS)':
 'DQS7_A_C||TDQS7_A_C': CDS_PINID='\dqs7_a_c||tdqs7_a_c\';
NODE_NAME     J10 178
 '@S9S_MB_2U_LIB.S9S_MB_2U(SCH_1):PAGE91_I178@PURE_QUANTA.SCONN288_ADR50017P087CC(CHIPS)':
 'DQS7_A_C||TDQS7_A_C': CDS_PINID='\dqs7_a_c||tdqs7_a_c\';
NET_NAME
'M_E_CPU0_SA_DQS_DN<8>'
 '@S9S_MB_2U_LIB.S9S_MB_2U(SCH_1):M_E_CPU0_SA_DQS_DN'<8>:
 C_SIGNAL='@s9s_mb_2u_lib.s9s_mb_2u(sch_1):m_e_cpu0_sa_dqs_dn(8)';
NODE_NAME     U2 ET61
 '@S9S_MB_2U_LIB.S9S_MB_2U(SCH_1):PAGE24_I169@PURE_QUANTA.SOCKET4677_AZIF0045P001C01CS(CHIPS)':
 'DDR4_SA_DQS_DN8': CDS_PINID='DDR4_SA_DQS_DN8';
NODE_NAME     J9 189
 '@S9S_MB_2U_LIB.S9S_MB_2U(SCH_1):PAGE90_I178@PURE_QUANTA.SCONN288_ADR50017P130CC(CHIPS)':
 'DQS8_A_C||TDQS8_A_C': CDS_PINID='\dqs8_a_c||tdqs8_a_c\';
NODE_NAME     J10 189
 '@S9S_MB_2U_LIB.S9S_MB_2U(SCH_1):PAGE91_I178@PURE_QUANTA.SCONN288_ADR50017P087CC(CHIPS)':
 'DQS8_A_C||TDQS8_A_C': CDS_PINID='\dqs8_a_c||tdqs8_a_c\';
NET_NAME
'M_E_CPU0_SA_DQS_DN<9>'
 '@S9S_MB_2U_LIB.S9S_MB_2U(SCH_1):M_E_CPU0_SA_DQS_DN'<9>:
 C_SIGNAL='@s9s_mb_2u_lib.s9s_mb_2u(sch_1):m_e_cpu0_sa_dqs_dn(9)';
NODE_NAME     U2 ET55
 '@S9S_MB_2U_LIB.S9S_MB_2U(SCH_1):PAGE24_I169@PURE_QUANTA.SOCKET4677_AZIF0045P001C01CS(CHIPS)':
 'DDR4_SA_DQS_DN9': CDS_PINID='DDR4_SA_DQS_DN9';
NODE_NAME     J9 200
 '@S9S_MB_2U_LIB.S9S_MB_2U(SCH_1):PAGE90_I178@PURE_QUANTA.SCONN288_ADR50017P130CC(CHIPS)':
 'DQS9_A_C||TDQS9_A_C': CDS_PINID='\dqs9_a_c||tdqs9_a_c\';
NODE_NAME     J10 200
 '@S9S_MB_2U_LIB.S9S_MB_2U(SCH_1):PAGE91_I178@PURE_QUANTA.SCONN288_ADR50017P087CC(CHIPS)':
 'DQS9_A_C||TDQS9_A_C': CDS_PINID='\dqs9_a_c||tdqs9_a_c\';
NET_NAME
'M_E_CPU0_SA_DQS_DP<0>'
 '@S9S_MB_2U_LIB.S9S_MB_2U(SCH_1):M_E_CPU0_SA_DQS_DP'<0>:
 C_SIGNAL='@s9s_mb_2u_lib.s9s_mb_2u(sch_1):m_e_cpu0_sa_dqs_dp(0)';
NODE_NAME     U2 EN76
 '@S9S_MB_2U_LIB.S9S_MB_2U(SCH_1):PAGE24_I169@PURE_QUANTA.SOCKET4677_AZIF0045P001C01CS(CHIPS)':
 'DDR4_SA_DQS_DP0': CDS_PINID='DDR4_SA_DQS_DP0';
NODE_NAME     J9 11
 '@S9S_MB_2U_LIB.S9S_MB_2U(SCH_1):PAGE90_I178@PURE_QUANTA.SCONN288_ADR50017P130CC(CHIPS)':
 'DQS0_A_T': CDS_PINID='DQS0_A_T';
NODE_NAME     J10 11
 '@S9S_MB_2U_LIB.S9S_MB_2U(SCH_1):PAGE91_I178@PURE_QUANTA.SCONN288_ADR50017P087CC(CHIPS)':
 'DQS0_A_T': CDS_PINID='DQS0_A_T';
NET_NAME
'M_E_CPU0_SA_DQS_DP<1>'
 '@S9S_MB_2U_LIB.S9S_MB_2U(SCH_1):M_E_CPU0_SA_DQS_DP'<1>:
 C_SIGNAL='@s9s_mb_2u_lib.s9s_mb_2u(sch_1):m_e_cpu0_sa_dqs_dp(1)';
NODE_NAME     U2 EE70
 '@S9S_MB_2U_LIB.S9S_MB_2U(SCH_1):PAGE24_I169@PURE_QUANTA.SOCKET4677_AZIF0045P001C01CS(CHIPS)':
 'DDR4_SA_DQS_DP1': CDS_PINID='DDR4_SA_DQS_DP1';
NODE_NAME     J9 22
 '@S9S_MB_2U_LIB.S9S_MB_2U(SCH_1):PAGE90_I178@PURE_QUANTA.SCONN288_ADR50017P130CC(CHIPS)':
 'DQS1_A_T': CDS_PINID='DQS1_A_T';
NODE_NAME     J10 22
 '@S9S_MB_2U_LIB.S9S_MB_2U(SCH_1):PAGE91_I178@PURE_QUANTA.SCONN288_ADR50017P087CC(CHIPS)':
 'DQS1_A_T': CDS_PINID='DQS1_A_T';
NET_NAME
'M_E_CPU0_SA_DQS_DP<2>'
 '@S9S_MB_2U_LIB.S9S_MB_2U(SCH_1):M_E_CPU0_SA_DQS_DP'<2>:
 C_SIGNAL='@s9s_mb_2u_lib.s9s_mb_2u(sch_1):m_e_cpu0_sa_dqs_dp(2)';
NODE_NAME     U2 EL68
 '@S9S_MB_2U_LIB.S9S_MB_2U(SCH_1):PAGE24_I169@PURE_QUANTA.SOCKET4677_AZIF0045P001C01CS(CHIPS)':
 'DDR4_SA_DQS_DP2': CDS_PINID='DDR4_SA_DQS_DP2';
NODE_NAME     J9 33
 '@S9S_MB_2U_LIB.S9S_MB_2U(SCH_1):PAGE90_I178@PURE_QUANTA.SCONN288_ADR50017P130CC(CHIPS)':
 'DQS2_A_T': CDS_PINID='DQS2_A_T';
NODE_NAME     J10 33
 '@S9S_MB_2U_LIB.S9S_MB_2U(SCH_1):PAGE91_I178@PURE_QUANTA.SCONN288_ADR50017P087CC(CHIPS)':
 'DQS2_A_T': CDS_PINID='DQS2_A_T';
NET_NAME
'M_E_CPU0_SA_DQS_DP<3>'
 '@S9S_MB_2U_LIB.S9S_MB_2U(SCH_1):M_E_CPU0_SA_DQS_DP'<3>:
 C_SIGNAL='@s9s_mb_2u_lib.s9s_mb_2u(sch_1):m_e_cpu0_sa_dqs_dp(3)';
NODE_NAME     U2 EM61
 '@S9S_MB_2U_LIB.S9S_MB_2U(SCH_1):PAGE24_I169@PURE_QUANTA.SOCKET4677_AZIF0045P001C01CS(CHIPS)':
 'DDR4_SA_DQS_DP3': CDS_PINID='DDR4_SA_DQS_DP3';
NODE_NAME     J9 44
 '@S9S_MB_2U_LIB.S9S_MB_2U(SCH_1):PAGE90_I178@PURE_QUANTA.SCONN288_ADR50017P130CC(CHIPS)':
 'DQS3_A_T': CDS_PINID='DQS3_A_T';
NODE_NAME     J10 44
 '@S9S_MB_2U_LIB.S9S_MB_2U(SCH_1):PAGE91_I178@PURE_QUANTA.SCONN288_ADR50017P087CC(CHIPS)':
 'DQS3_A_T': CDS_PINID='DQS3_A_T';
NET_NAME
'M_E_CPU0_SA_DQS_DP<4>'
 '@S9S_MB_2U_LIB.S9S_MB_2U(SCH_1):M_E_CPU0_SA_DQS_DP'<4>:
 C_SIGNAL='@s9s_mb_2u_lib.s9s_mb_2u(sch_1):m_e_cpu0_sa_dqs_dp(4)';
NODE_NAME     U2 EK55
 '@S9S_MB_2U_LIB.S9S_MB_2U(SCH_1):PAGE24_I169@PURE_QUANTA.SOCKET4677_AZIF0045P001C01CS(CHIPS)':
 'DDR4_SA_DQS_DP4': CDS_PINID='DDR4_SA_DQS_DP4';
NODE_NAME     J9 55
 '@S9S_MB_2U_LIB.S9S_MB_2U(SCH_1):PAGE90_I178@PURE_QUANTA.SCONN288_ADR50017P130CC(CHIPS)':
 'DQS4_A_T': CDS_PINID='DQS4_A_T';
NODE_NAME     J10 55
 '@S9S_MB_2U_LIB.S9S_MB_2U(SCH_1):PAGE91_I178@PURE_QUANTA.SCONN288_ADR50017P087CC(CHIPS)':
 'DQS4_A_T': CDS_PINID='DQS4_A_T';
NET_NAME
'M_E_CPU0_SA_DQS_DP<5>'
 '@S9S_MB_2U_LIB.S9S_MB_2U(SCH_1):M_E_CPU0_SA_DQS_DP'<5>:
 C_SIGNAL='@s9s_mb_2u_lib.s9s_mb_2u(sch_1):m_e_cpu0_sa_dqs_dp(5)';
NODE_NAME     U2 EN74
 '@S9S_MB_2U_LIB.S9S_MB_2U(SCH_1):PAGE24_I169@PURE_QUANTA.SOCKET4677_AZIF0045P001C01CS(CHIPS)':
 'DDR4_SA_DQS_DP5': CDS_PINID='DDR4_SA_DQS_DP5';
NODE_NAME     J9 157
 '@S9S_MB_2U_LIB.S9S_MB_2U(SCH_1):PAGE90_I178@PURE_QUANTA.SCONN288_ADR50017P130CC(CHIPS)':
 'DQS5_A_T||TDQS5_A_T': CDS_PINID='\dqs5_a_t||tdqs5_a_t\';
NODE_NAME     J10 157
 '@S9S_MB_2U_LIB.S9S_MB_2U(SCH_1):PAGE91_I178@PURE_QUANTA.SCONN288_ADR50017P087CC(CHIPS)':
 'DQS5_A_T||TDQS5_A_T': CDS_PINID='\dqs5_a_t||tdqs5_a_t\';
NET_NAME
'M_E_CPU0_SA_DQS_DP<6>'
 '@S9S_MB_2U_LIB.S9S_MB_2U(SCH_1):M_E_CPU0_SA_DQS_DP'<6>:
 C_SIGNAL='@s9s_mb_2u_lib.s9s_mb_2u(sch_1):m_e_cpu0_sa_dqs_dp(6)';
NODE_NAME     U2 EG70
 '@S9S_MB_2U_LIB.S9S_MB_2U(SCH_1):PAGE24_I169@PURE_QUANTA.SOCKET4677_AZIF0045P001C01CS(CHIPS)':
 'DDR4_SA_DQS_DP6': CDS_PINID='DDR4_SA_DQS_DP6';
NODE_NAME     J9 168
 '@S9S_MB_2U_LIB.S9S_MB_2U(SCH_1):PAGE90_I178@PURE_QUANTA.SCONN288_ADR50017P130CC(CHIPS)':
 'DQS6_A_T||TDQS6_A_T': CDS_PINID='\dqs6_a_t||tdqs6_a_t\';
NODE_NAME     J10 168
 '@S9S_MB_2U_LIB.S9S_MB_2U(SCH_1):PAGE91_I178@PURE_QUANTA.SCONN288_ADR50017P087CC(CHIPS)':
 'DQS6_A_T||TDQS6_A_T': CDS_PINID='\dqs6_a_t||tdqs6_a_t\';
NET_NAME
'M_E_CPU0_SA_DQS_DP<7>'
 '@S9S_MB_2U_LIB.S9S_MB_2U(SCH_1):M_E_CPU0_SA_DQS_DP'<7>:
 C_SIGNAL='@s9s_mb_2u_lib.s9s_mb_2u(sch_1):m_e_cpu0_sa_dqs_dp(7)';
NODE_NAME     U2 EM67
 '@S9S_MB_2U_LIB.S9S_MB_2U(SCH_1):PAGE24_I169@PURE_QUANTA.SOCKET4677_AZIF0045P001C01CS(CHIPS)':
 'DDR4_SA_DQS_DP7': CDS_PINID='DDR4_SA_DQS_DP7';
NODE_NAME     J9 179
 '@S9S_MB_2U_LIB.S9S_MB_2U(SCH_1):PAGE90_I178@PURE_QUANTA.SCONN288_ADR50017P130CC(CHIPS)':
 'DQS7_A_T||TDQS7_A_T': CDS_PINID='\dqs7_a_t||tdqs7_a_t\';
NODE_NAME     J10 179
 '@S9S_MB_2U_LIB.S9S_MB_2U(SCH_1):PAGE91_I178@PURE_QUANTA.SCONN288_ADR50017P087CC(CHIPS)':
 'DQS7_A_T||TDQS7_A_T': CDS_PINID='\dqs7_a_t||tdqs7_a_t\';
NET_NAME
'M_E_CPU0_SA_DQS_DP<8>'
 '@S9S_MB_2U_LIB.S9S_MB_2U(SCH_1):M_E_CPU0_SA_DQS_DP'<8>:
 C_SIGNAL='@s9s_mb_2u_lib.s9s_mb_2u(sch_1):m_e_cpu0_sa_dqs_dp(8)';
NODE_NAME     U2 EP61
 '@S9S_MB_2U_LIB.S9S_MB_2U(SCH_1):PAGE24_I169@PURE_QUANTA.SOCKET4677_AZIF0045P001C01CS(CHIPS)':
 'DDR4_SA_DQS_DP8': CDS_PINID='DDR4_SA_DQS_DP8';
NODE_NAME     J9 190
 '@S9S_MB_2U_LIB.S9S_MB_2U(SCH_1):PAGE90_I178@PURE_QUANTA.SCONN288_ADR50017P130CC(CHIPS)':
 'DQS8_A_T||TDQS8_A_T': CDS_PINID='\dqs8_a_t||tdqs8_a_t\';
NODE_NAME     J10 190
 '@S9S_MB_2U_LIB.S9S_MB_2U(SCH_1):PAGE91_I178@PURE_QUANTA.SCONN288_ADR50017P087CC(CHIPS)':
 'DQS8_A_T||TDQS8_A_T': CDS_PINID='\dqs8_a_t||tdqs8_a_t\';
NET_NAME
'M_E_CPU0_SA_DQS_DP<9>'
 '@S9S_MB_2U_LIB.S9S_MB_2U(SCH_1):M_E_CPU0_SA_DQS_DP'<9>:
 C_SIGNAL='@s9s_mb_2u_lib.s9s_mb_2u(sch_1):m_e_cpu0_sa_dqs_dp(9)';
NODE_NAME     U2 EP55
 '@S9S_MB_2U_LIB.S9S_MB_2U(SCH_1):PAGE24_I169@PURE_QUANTA.SOCKET4677_AZIF0045P001C01CS(CHIPS)':
 'DDR4_SA_DQS_DP9': CDS_PINID='DDR4_SA_DQS_DP9';
NODE_NAME     J9 201
 '@S9S_MB_2U_LIB.S9S_MB_2U(SCH_1):PAGE90_I178@PURE_QUANTA.SCONN288_ADR50017P130CC(CHIPS)':
 'DQS9_A_T||TDQS9_A_T': CDS_PINID='\dqs9_a_t||tdqs9_a_t\';
NODE_NAME     J10 201
 '@S9S_MB_2U_LIB.S9S_MB_2U(SCH_1):PAGE91_I178@PURE_QUANTA.SCONN288_ADR50017P087CC(CHIPS)':
 'DQS9_A_T||TDQS9_A_T': CDS_PINID='\dqs9_a_t||tdqs9_a_t\';
NET_NAME
'M_E_CPU0_SA_PAR'
 '@S9S_MB_2U_LIB.S9S_MB_2U(SCH_1):M_E_CPU0_SA_PAR':
 C_SIGNAL='@s9s_mb_2u_lib.s9s_mb_2u(sch_1):m_e_cpu0_sa_par';
NODE_NAME     U2 EE43
 '@S9S_MB_2U_LIB.S9S_MB_2U(SCH_1):PAGE24_I169@PURE_QUANTA.SOCKET4677_AZIF0045P001C01CS(CHIPS)':
 'DDR4_SA_PAR': CDS_PINID='DDR4_SA_PAR';
NODE_NAME     J9 74
 '@S9S_MB_2U_LIB.S9S_MB_2U(SCH_1):PAGE90_I12@PURE_QUANTA.SCONN288_ADR50017P130CC(CHIPS)':
 'PAR_A': CDS_PINID='PAR_A';
NODE_NAME     J10 74
 '@S9S_MB_2U_LIB.S9S_MB_2U(SCH_1):PAGE91_I13@PURE_QUANTA.SCONN288_ADR50017P087CC(CHIPS)':
 'PAR_A': CDS_PINID='PAR_A';
NET_NAME
'M_E_CPU0_SA_RSP<0>'
 '@S9S_MB_2U_LIB.S9S_MB_2U(SCH_1):M_E_CPU0_SA_RSP'<0>:
 C_SIGNAL='@s9s_mb_2u_lib.s9s_mb_2u(sch_1):m_e_cpu0_sa_rsp(0)';
NODE_NAME     U2 DD44
 '@S9S_MB_2U_LIB.S9S_MB_2U(SCH_1):PAGE24_I169@PURE_QUANTA.SOCKET4677_AZIF0045P001C01CS(CHIPS)':
 'DDR4_A_RSP0': CDS_PINID='DDR4_A_RSP0';
NODE_NAME     J9 86
 '@S9S_MB_2U_LIB.S9S_MB_2U(SCH_1):PAGE90_I12@PURE_QUANTA.SCONN288_ADR50017P130CC(CHIPS)':
 'LBD||RSP_A_N': CDS_PINID='\lbd||rsp_a_n\';
NET_NAME
'M_E_CPU0_SA_RSP<1>'
 '@S9S_MB_2U_LIB.S9S_MB_2U(SCH_1):M_E_CPU0_SA_RSP'<1>:
 C_SIGNAL='@s9s_mb_2u_lib.s9s_mb_2u(sch_1):m_e_cpu0_sa_rsp(1)';
NODE_NAME     U2 DC43
 '@S9S_MB_2U_LIB.S9S_MB_2U(SCH_1):PAGE24_I169@PURE_QUANTA.SOCKET4677_AZIF0045P001C01CS(CHIPS)':
 'DDR4_A_RSP1': CDS_PINID='DDR4_A_RSP1';
NODE_NAME     J10 86
 '@S9S_MB_2U_LIB.S9S_MB_2U(SCH_1):PAGE91_I13@PURE_QUANTA.SCONN288_ADR50017P087CC(CHIPS)':
 'LBD||RSP_A_N': CDS_PINID='\lbd||rsp_a_n\';
NET_NAME
'M_E_CPU0_SB_CA<0>'
 '@S9S_MB_2U_LIB.S9S_MB_2U(SCH_1):M_E_CPU0_SB_CA'<0>:
 C_SIGNAL='@s9s_mb_2u_lib.s9s_mb_2u(sch_1):m_e_cpu0_sb_ca(0)';
NODE_NAME     U2 EG43
 '@S9S_MB_2U_LIB.S9S_MB_2U(SCH_1):PAGE24_I169@PURE_QUANTA.SOCKET4677_AZIF0045P001C01CS(CHIPS)':
 'DDR4_SB_CA0': CDS_PINID='DDR4_SB_CA0';
NODE_NAME     J9 76
 '@S9S_MB_2U_LIB.S9S_MB_2U(SCH_1):PAGE90_I12@PURE_QUANTA.SCONN288_ADR50017P130CC(CHIPS)':
 'CA0_B': CDS_PINID='CA0_B';
NODE_NAME     J10 76
 '@S9S_MB_2U_LIB.S9S_MB_2U(SCH_1):PAGE91_I13@PURE_QUANTA.SCONN288_ADR50017P087CC(CHIPS)':
 'CA0_B': CDS_PINID='CA0_B';
NET_NAME
'M_E_CPU0_SB_CA<1>'
 '@S9S_MB_2U_LIB.S9S_MB_2U(SCH_1):M_E_CPU0_SB_CA'<1>:
 C_SIGNAL='@s9s_mb_2u_lib.s9s_mb_2u(sch_1):m_e_cpu0_sb_ca(1)';
NODE_NAME     U2 EH44
 '@S9S_MB_2U_LIB.S9S_MB_2U(SCH_1):PAGE24_I169@PURE_QUANTA.SOCKET4677_AZIF0045P001C01CS(CHIPS)':
 'DDR4_SB_CA1': CDS_PINID='DDR4_SB_CA1';
NODE_NAME     J9 221
 '@S9S_MB_2U_LIB.S9S_MB_2U(SCH_1):PAGE90_I12@PURE_QUANTA.SCONN288_ADR50017P130CC(CHIPS)':
 'CA1_B': CDS_PINID='CA1_B';
NODE_NAME     J10 221
 '@S9S_MB_2U_LIB.S9S_MB_2U(SCH_1):PAGE91_I13@PURE_QUANTA.SCONN288_ADR50017P087CC(CHIPS)':
 'CA1_B': CDS_PINID='CA1_B';
NET_NAME
'M_E_CPU0_SB_CA<2>'
 '@S9S_MB_2U_LIB.S9S_MB_2U(SCH_1):M_E_CPU0_SB_CA'<2>:
 C_SIGNAL='@s9s_mb_2u_lib.s9s_mb_2u(sch_1):m_e_cpu0_sb_ca(2)';
NODE_NAME     U2 EM44
 '@S9S_MB_2U_LIB.S9S_MB_2U(SCH_1):PAGE24_I169@PURE_QUANTA.SOCKET4677_AZIF0045P001C01CS(CHIPS)':
 'DDR4_SB_CA2': CDS_PINID='DDR4_SB_CA2';
NODE_NAME     J9 78
 '@S9S_MB_2U_LIB.S9S_MB_2U(SCH_1):PAGE90_I12@PURE_QUANTA.SCONN288_ADR50017P130CC(CHIPS)':
 'CA2_B': CDS_PINID='CA2_B';
NODE_NAME     J10 78
 '@S9S_MB_2U_LIB.S9S_MB_2U(SCH_1):PAGE91_I13@PURE_QUANTA.SCONN288_ADR50017P087CC(CHIPS)':
 'CA2_B': CDS_PINID='CA2_B';
NET_NAME
'M_E_CPU0_SB_CA<3>'
 '@S9S_MB_2U_LIB.S9S_MB_2U(SCH_1):M_E_CPU0_SB_CA'<3>:
 C_SIGNAL='@s9s_mb_2u_lib.s9s_mb_2u(sch_1):m_e_cpu0_sb_ca(3)';
NODE_NAME     U2 EP44
 '@S9S_MB_2U_LIB.S9S_MB_2U(SCH_1):PAGE24_I169@PURE_QUANTA.SOCKET4677_AZIF0045P001C01CS(CHIPS)':
 'DDR4_SB_CA3': CDS_PINID='DDR4_SB_CA3';
NODE_NAME     J9 223
 '@S9S_MB_2U_LIB.S9S_MB_2U(SCH_1):PAGE90_I12@PURE_QUANTA.SCONN288_ADR50017P130CC(CHIPS)':
 'CA3_B': CDS_PINID='CA3_B';
NODE_NAME     J10 223
 '@S9S_MB_2U_LIB.S9S_MB_2U(SCH_1):PAGE91_I13@PURE_QUANTA.SCONN288_ADR50017P087CC(CHIPS)':
 'CA3_B': CDS_PINID='CA3_B';
NET_NAME
'M_E_CPU0_SB_CA<4>'
 '@S9S_MB_2U_LIB.S9S_MB_2U(SCH_1):M_E_CPU0_SB_CA'<4>:
 C_SIGNAL='@s9s_mb_2u_lib.s9s_mb_2u(sch_1):m_e_cpu0_sb_ca(4)';
NODE_NAME     U2 EL43
 '@S9S_MB_2U_LIB.S9S_MB_2U(SCH_1):PAGE24_I169@PURE_QUANTA.SOCKET4677_AZIF0045P001C01CS(CHIPS)':
 'DDR4_SB_CA4': CDS_PINID='DDR4_SB_CA4';
NODE_NAME     J9 80
 '@S9S_MB_2U_LIB.S9S_MB_2U(SCH_1):PAGE90_I12@PURE_QUANTA.SCONN288_ADR50017P130CC(CHIPS)':
 'CA4_B': CDS_PINID='CA4_B';
NODE_NAME     J10 80
 '@S9S_MB_2U_LIB.S9S_MB_2U(SCH_1):PAGE91_I13@PURE_QUANTA.SCONN288_ADR50017P087CC(CHIPS)':
 'CA4_B': CDS_PINID='CA4_B';
NET_NAME
'M_E_CPU0_SB_CA<5>'
 '@S9S_MB_2U_LIB.S9S_MB_2U(SCH_1):M_E_CPU0_SB_CA'<5>:
 C_SIGNAL='@s9s_mb_2u_lib.s9s_mb_2u(sch_1):m_e_cpu0_sb_ca(5)';
NODE_NAME     U2 ET42
 '@S9S_MB_2U_LIB.S9S_MB_2U(SCH_1):PAGE24_I169@PURE_QUANTA.SOCKET4677_AZIF0045P001C01CS(CHIPS)':
 'DDR4_SB_CA5': CDS_PINID='DDR4_SB_CA5';
NODE_NAME     J9 225
 '@S9S_MB_2U_LIB.S9S_MB_2U(SCH_1):PAGE90_I12@PURE_QUANTA.SCONN288_ADR50017P130CC(CHIPS)':
 'CA5_B': CDS_PINID='CA5_B';
NODE_NAME     J10 225
 '@S9S_MB_2U_LIB.S9S_MB_2U(SCH_1):PAGE91_I13@PURE_QUANTA.SCONN288_ADR50017P087CC(CHIPS)':
 'CA5_B': CDS_PINID='CA5_B';
NET_NAME
'M_E_CPU0_SB_CA<6>'
 '@S9S_MB_2U_LIB.S9S_MB_2U(SCH_1):M_E_CPU0_SB_CA'<6>:
 C_SIGNAL='@s9s_mb_2u_lib.s9s_mb_2u(sch_1):m_e_cpu0_sb_ca(6)';
NODE_NAME     U2 EK42
 '@S9S_MB_2U_LIB.S9S_MB_2U(SCH_1):PAGE24_I169@PURE_QUANTA.SOCKET4677_AZIF0045P001C01CS(CHIPS)':
 'DDR4_SB_CA6': CDS_PINID='DDR4_SB_CA6';
NODE_NAME     J9 82
 '@S9S_MB_2U_LIB.S9S_MB_2U(SCH_1):PAGE90_I12@PURE_QUANTA.SCONN288_ADR50017P130CC(CHIPS)':
 'CA6_B': CDS_PINID='CA6_B';
NODE_NAME     J10 82
 '@S9S_MB_2U_LIB.S9S_MB_2U(SCH_1):PAGE91_I13@PURE_QUANTA.SCONN288_ADR50017P087CC(CHIPS)':
 'CA6_B': CDS_PINID='CA6_B';
NET_NAME
'M_E_CPU0_SB_CB<0>'
 '@S9S_MB_2U_LIB.S9S_MB_2U(SCH_1):M_E_CPU0_SB_CB'<0>:
 C_SIGNAL='@s9s_mb_2u_lib.s9s_mb_2u(sch_1):m_e_cpu0_sb_cb(0)';
NODE_NAME     U2 EL35
 '@S9S_MB_2U_LIB.S9S_MB_2U(SCH_1):PAGE24_I169@PURE_QUANTA.SOCKET4677_AZIF0045P001C01CS(CHIPS)':
 'DDR4_SB_ECC0': CDS_PINID='DDR4_SB_ECC0';
NODE_NAME     J9 96
 '@S9S_MB_2U_LIB.S9S_MB_2U(SCH_1):PAGE90_I12@PURE_QUANTA.SCONN288_ADR50017P130CC(CHIPS)':
 'CB0_B': CDS_PINID='CB0_B';
NODE_NAME     J10 96
 '@S9S_MB_2U_LIB.S9S_MB_2U(SCH_1):PAGE91_I13@PURE_QUANTA.SCONN288_ADR50017P087CC(CHIPS)':
 'CB0_B': CDS_PINID='CB0_B';
NET_NAME
'M_E_CPU0_SB_CB<1>'
 '@S9S_MB_2U_LIB.S9S_MB_2U(SCH_1):M_E_CPU0_SB_CB'<1>:
 C_SIGNAL='@s9s_mb_2u_lib.s9s_mb_2u(sch_1):m_e_cpu0_sb_cb(1)';
NODE_NAME     U2 EM34
 '@S9S_MB_2U_LIB.S9S_MB_2U(SCH_1):PAGE24_I169@PURE_QUANTA.SOCKET4677_AZIF0045P001C01CS(CHIPS)':
 'DDR4_SB_ECC1': CDS_PINID='DDR4_SB_ECC1';
NODE_NAME     J9 98
 '@S9S_MB_2U_LIB.S9S_MB_2U(SCH_1):PAGE90_I12@PURE_QUANTA.SCONN288_ADR50017P130CC(CHIPS)':
 'CB1_B': CDS_PINID='CB1_B';
NODE_NAME     J10 98
 '@S9S_MB_2U_LIB.S9S_MB_2U(SCH_1):PAGE91_I13@PURE_QUANTA.SCONN288_ADR50017P087CC(CHIPS)':
 'CB1_B': CDS_PINID='CB1_B';
NET_NAME
'M_E_CPU0_SB_CB<2>'
 '@S9S_MB_2U_LIB.S9S_MB_2U(SCH_1):M_E_CPU0_SB_CB'<2>:
 C_SIGNAL='@s9s_mb_2u_lib.s9s_mb_2u(sch_1):m_e_cpu0_sb_cb(2)';
NODE_NAME     U2 ER35
 '@S9S_MB_2U_LIB.S9S_MB_2U(SCH_1):PAGE24_I169@PURE_QUANTA.SOCKET4677_AZIF0045P001C01CS(CHIPS)':
 'DDR4_SB_ECC2': CDS_PINID='DDR4_SB_ECC2';
NODE_NAME     J9 241
 '@S9S_MB_2U_LIB.S9S_MB_2U(SCH_1):PAGE90_I12@PURE_QUANTA.SCONN288_ADR50017P130CC(CHIPS)':
 'CB2_B': CDS_PINID='CB2_B';
NODE_NAME     J10 241
 '@S9S_MB_2U_LIB.S9S_MB_2U(SCH_1):PAGE91_I13@PURE_QUANTA.SCONN288_ADR50017P087CC(CHIPS)':
 'CB2_B': CDS_PINID='CB2_B';
NET_NAME
'M_E_CPU0_SB_CB<3>'
 '@S9S_MB_2U_LIB.S9S_MB_2U(SCH_1):M_E_CPU0_SB_CB'<3>:
 C_SIGNAL='@s9s_mb_2u_lib.s9s_mb_2u(sch_1):m_e_cpu0_sb_cb(3)';
NODE_NAME     U2 EP34
 '@S9S_MB_2U_LIB.S9S_MB_2U(SCH_1):PAGE24_I169@PURE_QUANTA.SOCKET4677_AZIF0045P001C01CS(CHIPS)':
 'DDR4_SB_ECC3': CDS_PINID='DDR4_SB_ECC3';
NODE_NAME     J9 243
 '@S9S_MB_2U_LIB.S9S_MB_2U(SCH_1):PAGE90_I12@PURE_QUANTA.SCONN288_ADR50017P130CC(CHIPS)':
 'CB3_B': CDS_PINID='CB3_B';
NODE_NAME     J10 243
 '@S9S_MB_2U_LIB.S9S_MB_2U(SCH_1):PAGE91_I13@PURE_QUANTA.SCONN288_ADR50017P087CC(CHIPS)':
 'CB3_B': CDS_PINID='CB3_B';
NET_NAME
'M_E_CPU0_SB_CB<4>'
 '@S9S_MB_2U_LIB.S9S_MB_2U(SCH_1):M_E_CPU0_SB_CB'<4>:
 C_SIGNAL='@s9s_mb_2u_lib.s9s_mb_2u(sch_1):m_e_cpu0_sb_cb(4)';
NODE_NAME     U2 EM38
 '@S9S_MB_2U_LIB.S9S_MB_2U(SCH_1):PAGE24_I169@PURE_QUANTA.SOCKET4677_AZIF0045P001C01CS(CHIPS)':
 'DDR4_SB_ECC4': CDS_PINID='DDR4_SB_ECC4';
NODE_NAME     J9 89
 '@S9S_MB_2U_LIB.S9S_MB_2U(SCH_1):PAGE90_I12@PURE_QUANTA.SCONN288_ADR50017P130CC(CHIPS)':
 'CB4_B': CDS_PINID='CB4_B';
NODE_NAME     J10 89
 '@S9S_MB_2U_LIB.S9S_MB_2U(SCH_1):PAGE91_I13@PURE_QUANTA.SCONN288_ADR50017P087CC(CHIPS)':
 'CB4_B': CDS_PINID='CB4_B';
NET_NAME
'M_E_CPU0_SB_CB<5>'
 '@S9S_MB_2U_LIB.S9S_MB_2U(SCH_1):M_E_CPU0_SB_CB'<5>:
 C_SIGNAL='@s9s_mb_2u_lib.s9s_mb_2u(sch_1):m_e_cpu0_sb_cb(5)';
NODE_NAME     U2 EL37
 '@S9S_MB_2U_LIB.S9S_MB_2U(SCH_1):PAGE24_I169@PURE_QUANTA.SOCKET4677_AZIF0045P001C01CS(CHIPS)':
 'DDR4_SB_ECC5': CDS_PINID='DDR4_SB_ECC5';
NODE_NAME     J9 91
 '@S9S_MB_2U_LIB.S9S_MB_2U(SCH_1):PAGE90_I12@PURE_QUANTA.SCONN288_ADR50017P130CC(CHIPS)':
 'CB5_B': CDS_PINID='CB5_B';
NODE_NAME     J10 91
 '@S9S_MB_2U_LIB.S9S_MB_2U(SCH_1):PAGE91_I13@PURE_QUANTA.SCONN288_ADR50017P087CC(CHIPS)':
 'CB5_B': CDS_PINID='CB5_B';
NET_NAME
'M_E_CPU0_SB_CB<6>'
 '@S9S_MB_2U_LIB.S9S_MB_2U(SCH_1):M_E_CPU0_SB_CB'<6>:
 C_SIGNAL='@s9s_mb_2u_lib.s9s_mb_2u(sch_1):m_e_cpu0_sb_cb(6)';
NODE_NAME     U2 EP38
 '@S9S_MB_2U_LIB.S9S_MB_2U(SCH_1):PAGE24_I169@PURE_QUANTA.SOCKET4677_AZIF0045P001C01CS(CHIPS)':
 'DDR4_SB_ECC6': CDS_PINID='DDR4_SB_ECC6';
NODE_NAME     J9 234
 '@S9S_MB_2U_LIB.S9S_MB_2U(SCH_1):PAGE90_I12@PURE_QUANTA.SCONN288_ADR50017P130CC(CHIPS)':
 'CB6_B': CDS_PINID='CB6_B';
NODE_NAME     J10 234
 '@S9S_MB_2U_LIB.S9S_MB_2U(SCH_1):PAGE91_I13@PURE_QUANTA.SCONN288_ADR50017P087CC(CHIPS)':
 'CB6_B': CDS_PINID='CB6_B';
NET_NAME
'M_E_CPU0_SB_CB<7>'
 '@S9S_MB_2U_LIB.S9S_MB_2U(SCH_1):M_E_CPU0_SB_CB'<7>:
 C_SIGNAL='@s9s_mb_2u_lib.s9s_mb_2u(sch_1):m_e_cpu0_sb_cb(7)';
NODE_NAME     U2 ER37
 '@S9S_MB_2U_LIB.S9S_MB_2U(SCH_1):PAGE24_I169@PURE_QUANTA.SOCKET4677_AZIF0045P001C01CS(CHIPS)':
 'DDR4_SB_ECC7': CDS_PINID='DDR4_SB_ECC7';
NODE_NAME     J9 236
 '@S9S_MB_2U_LIB.S9S_MB_2U(SCH_1):PAGE90_I12@PURE_QUANTA.SCONN288_ADR50017P130CC(CHIPS)':
 'CB7_B': CDS_PINID='CB7_B';
NODE_NAME     J10 236
 '@S9S_MB_2U_LIB.S9S_MB_2U(SCH_1):PAGE91_I13@PURE_QUANTA.SCONN288_ADR50017P087CC(CHIPS)':
 'CB7_B': CDS_PINID='CB7_B';
NET_NAME
'M_E_CPU0_SB_CS_N<0>'
 '@S9S_MB_2U_LIB.S9S_MB_2U(SCH_1):M_E_CPU0_SB_CS_N'<0>:
 C_SIGNAL='@s9s_mb_2u_lib.s9s_mb_2u(sch_1):m_e_cpu0_sb_cs_n(0)';
NODE_NAME     U2 EP40
 '@S9S_MB_2U_LIB.S9S_MB_2U(SCH_1):PAGE24_I169@PURE_QUANTA.SOCKET4677_AZIF0045P001C01CS(CHIPS)':
 'DDR4_SB_CS_N0': CDS_PINID='DDR4_SB_CS_N0';
NODE_NAME     J9 84
 '@S9S_MB_2U_LIB.S9S_MB_2U(SCH_1):PAGE90_I12@PURE_QUANTA.SCONN288_ADR50017P130CC(CHIPS)':
 'CS0_B_N': CDS_PINID='CS0_B_N';
NET_NAME
'M_E_CPU0_SB_CS_N<1>'
 '@S9S_MB_2U_LIB.S9S_MB_2U(SCH_1):M_E_CPU0_SB_CS_N'<1>:
 C_SIGNAL='@s9s_mb_2u_lib.s9s_mb_2u(sch_1):m_e_cpu0_sb_cs_n(1)';
NODE_NAME     U2 ET40
 '@S9S_MB_2U_LIB.S9S_MB_2U(SCH_1):PAGE24_I169@PURE_QUANTA.SOCKET4677_AZIF0045P001C01CS(CHIPS)':
 'DDR4_SB_CS_N1': CDS_PINID='DDR4_SB_CS_N1';
NODE_NAME     J9 229
 '@S9S_MB_2U_LIB.S9S_MB_2U(SCH_1):PAGE90_I12@PURE_QUANTA.SCONN288_ADR50017P130CC(CHIPS)':
 'CS1_B_N': CDS_PINID='CS1_B_N';
NET_NAME
'M_E_CPU0_SB_CS_N<2>'
 '@S9S_MB_2U_LIB.S9S_MB_2U(SCH_1):M_E_CPU0_SB_CS_N'<2>:
 C_SIGNAL='@s9s_mb_2u_lib.s9s_mb_2u(sch_1):m_e_cpu0_sb_cs_n(2)';
NODE_NAME     U2 EM40
 '@S9S_MB_2U_LIB.S9S_MB_2U(SCH_1):PAGE24_I169@PURE_QUANTA.SOCKET4677_AZIF0045P001C01CS(CHIPS)':
 'DDR4_SB_CS_N2': CDS_PINID='DDR4_SB_CS_N2';
NODE_NAME     J10 84
 '@S9S_MB_2U_LIB.S9S_MB_2U(SCH_1):PAGE91_I13@PURE_QUANTA.SCONN288_ADR50017P087CC(CHIPS)':
 'CS0_B_N': CDS_PINID='CS0_B_N';
NET_NAME
'M_E_CPU0_SB_CS_N<3>'
 '@S9S_MB_2U_LIB.S9S_MB_2U(SCH_1):M_E_CPU0_SB_CS_N'<3>:
 C_SIGNAL='@s9s_mb_2u_lib.s9s_mb_2u(sch_1):m_e_cpu0_sb_cs_n(3)';
NODE_NAME     U2 EL41
 '@S9S_MB_2U_LIB.S9S_MB_2U(SCH_1):PAGE24_I169@PURE_QUANTA.SOCKET4677_AZIF0045P001C01CS(CHIPS)':
 'DDR4_SB_CS_N3': CDS_PINID='DDR4_SB_CS_N3';
NODE_NAME     J10 229
 '@S9S_MB_2U_LIB.S9S_MB_2U(SCH_1):PAGE91_I13@PURE_QUANTA.SCONN288_ADR50017P087CC(CHIPS)':
 'CS1_B_N': CDS_PINID='CS1_B_N';
NET_NAME
'M_E_CPU0_SB_DQ<0>'
 '@S9S_MB_2U_LIB.S9S_MB_2U(SCH_1):M_E_CPU0_SB_DQ'<0>:
 C_SIGNAL='@s9s_mb_2u_lib.s9s_mb_2u(sch_1):m_e_cpu0_sb_dq(0)';
NODE_NAME     U2 EE29
 '@S9S_MB_2U_LIB.S9S_MB_2U(SCH_1):PAGE24_I169@PURE_QUANTA.SOCKET4677_AZIF0045P001C01CS(CHIPS)':
 'DDR4_SB_DQ0': CDS_PINID='DDR4_SB_DQ0';
NODE_NAME     J9 100
 '@S9S_MB_2U_LIB.S9S_MB_2U(SCH_1):PAGE90_I12@PURE_QUANTA.SCONN288_ADR50017P130CC(CHIPS)':
 'DQ0_B': CDS_PINID='DQ0_B';
NODE_NAME     J10 100
 '@S9S_MB_2U_LIB.S9S_MB_2U(SCH_1):PAGE91_I13@PURE_QUANTA.SCONN288_ADR50017P087CC(CHIPS)':
 'DQ0_B': CDS_PINID='DQ0_B';
NET_NAME
'M_E_CPU0_SB_DQ<10>'
 '@S9S_MB_2U_LIB.S9S_MB_2U(SCH_1):M_E_CPU0_SB_DQ'<10>:
 C_SIGNAL='@s9s_mb_2u_lib.s9s_mb_2u(sch_1):m_e_cpu0_sb_dq(10)';
NODE_NAME     U2 EP32
 '@S9S_MB_2U_LIB.S9S_MB_2U(SCH_1):PAGE24_I169@PURE_QUANTA.SOCKET4677_AZIF0045P001C01CS(CHIPS)':
 'DDR4_SB_DQ10': CDS_PINID='DDR4_SB_DQ10';
NODE_NAME     J9 256
 '@S9S_MB_2U_LIB.S9S_MB_2U(SCH_1):PAGE90_I12@PURE_QUANTA.SCONN288_ADR50017P130CC(CHIPS)':
 'DQ10_B': CDS_PINID='DQ10_B';
NODE_NAME     J10 256
 '@S9S_MB_2U_LIB.S9S_MB_2U(SCH_1):PAGE91_I13@PURE_QUANTA.SCONN288_ADR50017P087CC(CHIPS)':
 'DQ10_B': CDS_PINID='DQ10_B';
NET_NAME
'M_E_CPU0_SB_DQ<11>'
 '@S9S_MB_2U_LIB.S9S_MB_2U(SCH_1):M_E_CPU0_SB_DQ'<11>:
 C_SIGNAL='@s9s_mb_2u_lib.s9s_mb_2u(sch_1):m_e_cpu0_sb_dq(11)';
NODE_NAME     U2 ER31
 '@S9S_MB_2U_LIB.S9S_MB_2U(SCH_1):PAGE24_I169@PURE_QUANTA.SOCKET4677_AZIF0045P001C01CS(CHIPS)':
 'DDR4_SB_DQ11': CDS_PINID='DDR4_SB_DQ11';
NODE_NAME     J9 258
 '@S9S_MB_2U_LIB.S9S_MB_2U(SCH_1):PAGE90_I12@PURE_QUANTA.SCONN288_ADR50017P130CC(CHIPS)':
 'DQ11_B': CDS_PINID='DQ11_B';
NODE_NAME     J10 258
 '@S9S_MB_2U_LIB.S9S_MB_2U(SCH_1):PAGE91_I13@PURE_QUANTA.SCONN288_ADR50017P087CC(CHIPS)':
 'DQ11_B': CDS_PINID='DQ11_B';
NET_NAME
'M_E_CPU0_SB_DQ<12>'
 '@S9S_MB_2U_LIB.S9S_MB_2U(SCH_1):M_E_CPU0_SB_DQ'<12>:
 C_SIGNAL='@s9s_mb_2u_lib.s9s_mb_2u(sch_1):m_e_cpu0_sb_dq(12)';
NODE_NAME     U2 EL29
 '@S9S_MB_2U_LIB.S9S_MB_2U(SCH_1):PAGE24_I169@PURE_QUANTA.SOCKET4677_AZIF0045P001C01CS(CHIPS)':
 'DDR4_SB_DQ12': CDS_PINID='DDR4_SB_DQ12';
NODE_NAME     J9 118
 '@S9S_MB_2U_LIB.S9S_MB_2U(SCH_1):PAGE90_I12@PURE_QUANTA.SCONN288_ADR50017P130CC(CHIPS)':
 'DQ12_B': CDS_PINID='DQ12_B';
NODE_NAME     J10 118
 '@S9S_MB_2U_LIB.S9S_MB_2U(SCH_1):PAGE91_I13@PURE_QUANTA.SCONN288_ADR50017P087CC(CHIPS)':
 'DQ12_B': CDS_PINID='DQ12_B';
NET_NAME
'M_E_CPU0_SB_DQ<13>'
 '@S9S_MB_2U_LIB.S9S_MB_2U(SCH_1):M_E_CPU0_SB_DQ'<13>:
 C_SIGNAL='@s9s_mb_2u_lib.s9s_mb_2u(sch_1):m_e_cpu0_sb_dq(13)';
NODE_NAME     U2 EM28
 '@S9S_MB_2U_LIB.S9S_MB_2U(SCH_1):PAGE24_I169@PURE_QUANTA.SOCKET4677_AZIF0045P001C01CS(CHIPS)':
 'DDR4_SB_DQ13': CDS_PINID='DDR4_SB_DQ13';
NODE_NAME     J9 120
 '@S9S_MB_2U_LIB.S9S_MB_2U(SCH_1):PAGE90_I12@PURE_QUANTA.SCONN288_ADR50017P130CC(CHIPS)':
 'DQ13_B': CDS_PINID='DQ13_B';
NODE_NAME     J10 120
 '@S9S_MB_2U_LIB.S9S_MB_2U(SCH_1):PAGE91_I13@PURE_QUANTA.SCONN288_ADR50017P087CC(CHIPS)':
 'DQ13_B': CDS_PINID='DQ13_B';
NET_NAME
'M_E_CPU0_SB_DQ<14>'
 '@S9S_MB_2U_LIB.S9S_MB_2U(SCH_1):M_E_CPU0_SB_DQ'<14>:
 C_SIGNAL='@s9s_mb_2u_lib.s9s_mb_2u(sch_1):m_e_cpu0_sb_dq(14)';
NODE_NAME     U2 ER29
 '@S9S_MB_2U_LIB.S9S_MB_2U(SCH_1):PAGE24_I169@PURE_QUANTA.SOCKET4677_AZIF0045P001C01CS(CHIPS)':
 'DDR4_SB_DQ14': CDS_PINID='DDR4_SB_DQ14';
NODE_NAME     J9 263
 '@S9S_MB_2U_LIB.S9S_MB_2U(SCH_1):PAGE90_I12@PURE_QUANTA.SCONN288_ADR50017P130CC(CHIPS)':
 'DQ14_B': CDS_PINID='DQ14_B';
NODE_NAME     J10 263
 '@S9S_MB_2U_LIB.S9S_MB_2U(SCH_1):PAGE91_I13@PURE_QUANTA.SCONN288_ADR50017P087CC(CHIPS)':
 'DQ14_B': CDS_PINID='DQ14_B';
NET_NAME
'M_E_CPU0_SB_DQ<15>'
 '@S9S_MB_2U_LIB.S9S_MB_2U(SCH_1):M_E_CPU0_SB_DQ'<15>:
 C_SIGNAL='@s9s_mb_2u_lib.s9s_mb_2u(sch_1):m_e_cpu0_sb_dq(15)';
NODE_NAME     U2 EP28
 '@S9S_MB_2U_LIB.S9S_MB_2U(SCH_1):PAGE24_I169@PURE_QUANTA.SOCKET4677_AZIF0045P001C01CS(CHIPS)':
 'DDR4_SB_DQ15': CDS_PINID='DDR4_SB_DQ15';
NODE_NAME     J9 265
 '@S9S_MB_2U_LIB.S9S_MB_2U(SCH_1):PAGE90_I12@PURE_QUANTA.SCONN288_ADR50017P130CC(CHIPS)':
 'DQ15_B': CDS_PINID='DQ15_B';
NODE_NAME     J10 265
 '@S9S_MB_2U_LIB.S9S_MB_2U(SCH_1):PAGE91_I13@PURE_QUANTA.SCONN288_ADR50017P087CC(CHIPS)':
 'DQ15_B': CDS_PINID='DQ15_B';
NET_NAME
'M_E_CPU0_SB_DQ<16>'
 '@S9S_MB_2U_LIB.S9S_MB_2U(SCH_1):M_E_CPU0_SB_DQ'<16>:
 C_SIGNAL='@s9s_mb_2u_lib.s9s_mb_2u(sch_1):m_e_cpu0_sb_dq(16)';
NODE_NAME     U2 EM26
 '@S9S_MB_2U_LIB.S9S_MB_2U(SCH_1):PAGE24_I169@PURE_QUANTA.SOCKET4677_AZIF0045P001C01CS(CHIPS)':
 'DDR4_SB_DQ16': CDS_PINID='DDR4_SB_DQ16';
NODE_NAME     J9 122
 '@S9S_MB_2U_LIB.S9S_MB_2U(SCH_1):PAGE90_I12@PURE_QUANTA.SCONN288_ADR50017P130CC(CHIPS)':
 'DQ16_B': CDS_PINID='DQ16_B';
NODE_NAME     J10 122
 '@S9S_MB_2U_LIB.S9S_MB_2U(SCH_1):PAGE91_I13@PURE_QUANTA.SCONN288_ADR50017P087CC(CHIPS)':
 'DQ16_B': CDS_PINID='DQ16_B';
NET_NAME
'M_E_CPU0_SB_DQ<17>'
 '@S9S_MB_2U_LIB.S9S_MB_2U(SCH_1):M_E_CPU0_SB_DQ'<17>:
 C_SIGNAL='@s9s_mb_2u_lib.s9s_mb_2u(sch_1):m_e_cpu0_sb_dq(17)';
NODE_NAME     U2 EL25
 '@S9S_MB_2U_LIB.S9S_MB_2U(SCH_1):PAGE24_I169@PURE_QUANTA.SOCKET4677_AZIF0045P001C01CS(CHIPS)':
 'DDR4_SB_DQ17': CDS_PINID='DDR4_SB_DQ17';
NODE_NAME     J9 124
 '@S9S_MB_2U_LIB.S9S_MB_2U(SCH_1):PAGE90_I12@PURE_QUANTA.SCONN288_ADR50017P130CC(CHIPS)':
 'DQ17_B': CDS_PINID='DQ17_B';
NODE_NAME     J10 124
 '@S9S_MB_2U_LIB.S9S_MB_2U(SCH_1):PAGE91_I13@PURE_QUANTA.SCONN288_ADR50017P087CC(CHIPS)':
 'DQ17_B': CDS_PINID='DQ17_B';
NET_NAME
'M_E_CPU0_SB_DQ<18>'
 '@S9S_MB_2U_LIB.S9S_MB_2U(SCH_1):M_E_CPU0_SB_DQ'<18>:
 C_SIGNAL='@s9s_mb_2u_lib.s9s_mb_2u(sch_1):m_e_cpu0_sb_dq(18)';
NODE_NAME     U2 EP26
 '@S9S_MB_2U_LIB.S9S_MB_2U(SCH_1):PAGE24_I169@PURE_QUANTA.SOCKET4677_AZIF0045P001C01CS(CHIPS)':
 'DDR4_SB_DQ18': CDS_PINID='DDR4_SB_DQ18';
NODE_NAME     J9 267
 '@S9S_MB_2U_LIB.S9S_MB_2U(SCH_1):PAGE90_I12@PURE_QUANTA.SCONN288_ADR50017P130CC(CHIPS)':
 'DQ18_B': CDS_PINID='DQ18_B';
NODE_NAME     J10 267
 '@S9S_MB_2U_LIB.S9S_MB_2U(SCH_1):PAGE91_I13@PURE_QUANTA.SCONN288_ADR50017P087CC(CHIPS)':
 'DQ18_B': CDS_PINID='DQ18_B';
NET_NAME
'M_E_CPU0_SB_DQ<19>'
 '@S9S_MB_2U_LIB.S9S_MB_2U(SCH_1):M_E_CPU0_SB_DQ'<19>:
 C_SIGNAL='@s9s_mb_2u_lib.s9s_mb_2u(sch_1):m_e_cpu0_sb_dq(19)';
NODE_NAME     U2 ER25
 '@S9S_MB_2U_LIB.S9S_MB_2U(SCH_1):PAGE24_I169@PURE_QUANTA.SOCKET4677_AZIF0045P001C01CS(CHIPS)':
 'DDR4_SB_DQ19': CDS_PINID='DDR4_SB_DQ19';
NODE_NAME     J9 269
 '@S9S_MB_2U_LIB.S9S_MB_2U(SCH_1):PAGE90_I12@PURE_QUANTA.SCONN288_ADR50017P130CC(CHIPS)':
 'DQ19_B': CDS_PINID='DQ19_B';
NODE_NAME     J10 269
 '@S9S_MB_2U_LIB.S9S_MB_2U(SCH_1):PAGE91_I13@PURE_QUANTA.SCONN288_ADR50017P087CC(CHIPS)':
 'DQ19_B': CDS_PINID='DQ19_B';
NET_NAME
'M_E_CPU0_SB_DQ<1>'
 '@S9S_MB_2U_LIB.S9S_MB_2U(SCH_1):M_E_CPU0_SB_DQ'<1>:
 C_SIGNAL='@s9s_mb_2u_lib.s9s_mb_2u(sch_1):m_e_cpu0_sb_dq(1)';
NODE_NAME     U2 ED28
 '@S9S_MB_2U_LIB.S9S_MB_2U(SCH_1):PAGE24_I169@PURE_QUANTA.SOCKET4677_AZIF0045P001C01CS(CHIPS)':
 'DDR4_SB_DQ1': CDS_PINID='DDR4_SB_DQ1';
NODE_NAME     J9 102
 '@S9S_MB_2U_LIB.S9S_MB_2U(SCH_1):PAGE90_I12@PURE_QUANTA.SCONN288_ADR50017P130CC(CHIPS)':
 'DQ1_B': CDS_PINID='DQ1_B';
NODE_NAME     J10 102
 '@S9S_MB_2U_LIB.S9S_MB_2U(SCH_1):PAGE91_I13@PURE_QUANTA.SCONN288_ADR50017P087CC(CHIPS)':
 'DQ1_B': CDS_PINID='DQ1_B';
NET_NAME
'M_E_CPU0_SB_DQ<20>'
 '@S9S_MB_2U_LIB.S9S_MB_2U(SCH_1):M_E_CPU0_SB_DQ'<20>:
 C_SIGNAL='@s9s_mb_2u_lib.s9s_mb_2u(sch_1):m_e_cpu0_sb_dq(20)';
NODE_NAME     U2 EL23
 '@S9S_MB_2U_LIB.S9S_MB_2U(SCH_1):PAGE24_I169@PURE_QUANTA.SOCKET4677_AZIF0045P001C01CS(CHIPS)':
 'DDR4_SB_DQ20': CDS_PINID='DDR4_SB_DQ20';
NODE_NAME     J9 129
 '@S9S_MB_2U_LIB.S9S_MB_2U(SCH_1):PAGE90_I12@PURE_QUANTA.SCONN288_ADR50017P130CC(CHIPS)':
 'DQ20_B': CDS_PINID='DQ20_B';
NODE_NAME     J10 129
 '@S9S_MB_2U_LIB.S9S_MB_2U(SCH_1):PAGE91_I13@PURE_QUANTA.SCONN288_ADR50017P087CC(CHIPS)':
 'DQ20_B': CDS_PINID='DQ20_B';
NET_NAME
'M_E_CPU0_SB_DQ<21>'
 '@S9S_MB_2U_LIB.S9S_MB_2U(SCH_1):M_E_CPU0_SB_DQ'<21>:
 C_SIGNAL='@s9s_mb_2u_lib.s9s_mb_2u(sch_1):m_e_cpu0_sb_dq(21)';
NODE_NAME     U2 EM22
 '@S9S_MB_2U_LIB.S9S_MB_2U(SCH_1):PAGE24_I169@PURE_QUANTA.SOCKET4677_AZIF0045P001C01CS(CHIPS)':
 'DDR4_SB_DQ21': CDS_PINID='DDR4_SB_DQ21';
NODE_NAME     J9 131
 '@S9S_MB_2U_LIB.S9S_MB_2U(SCH_1):PAGE90_I12@PURE_QUANTA.SCONN288_ADR50017P130CC(CHIPS)':
 'DQ21_B': CDS_PINID='DQ21_B';
NODE_NAME     J10 131
 '@S9S_MB_2U_LIB.S9S_MB_2U(SCH_1):PAGE91_I13@PURE_QUANTA.SCONN288_ADR50017P087CC(CHIPS)':
 'DQ21_B': CDS_PINID='DQ21_B';
NET_NAME
'M_E_CPU0_SB_DQ<22>'
 '@S9S_MB_2U_LIB.S9S_MB_2U(SCH_1):M_E_CPU0_SB_DQ'<22>:
 C_SIGNAL='@s9s_mb_2u_lib.s9s_mb_2u(sch_1):m_e_cpu0_sb_dq(22)';
NODE_NAME     U2 ER23
 '@S9S_MB_2U_LIB.S9S_MB_2U(SCH_1):PAGE24_I169@PURE_QUANTA.SOCKET4677_AZIF0045P001C01CS(CHIPS)':
 'DDR4_SB_DQ22': CDS_PINID='DDR4_SB_DQ22';
NODE_NAME     J9 274
 '@S9S_MB_2U_LIB.S9S_MB_2U(SCH_1):PAGE90_I12@PURE_QUANTA.SCONN288_ADR50017P130CC(CHIPS)':
 'DQ22_B': CDS_PINID='DQ22_B';
NODE_NAME     J10 274
 '@S9S_MB_2U_LIB.S9S_MB_2U(SCH_1):PAGE91_I13@PURE_QUANTA.SCONN288_ADR50017P087CC(CHIPS)':
 'DQ22_B': CDS_PINID='DQ22_B';
NET_NAME
'M_E_CPU0_SB_DQ<23>'
 '@S9S_MB_2U_LIB.S9S_MB_2U(SCH_1):M_E_CPU0_SB_DQ'<23>:
 C_SIGNAL='@s9s_mb_2u_lib.s9s_mb_2u(sch_1):m_e_cpu0_sb_dq(23)';
NODE_NAME     U2 EP22
 '@S9S_MB_2U_LIB.S9S_MB_2U(SCH_1):PAGE24_I169@PURE_QUANTA.SOCKET4677_AZIF0045P001C01CS(CHIPS)':
 'DDR4_SB_DQ23': CDS_PINID='DDR4_SB_DQ23';
NODE_NAME     J9 276
 '@S9S_MB_2U_LIB.S9S_MB_2U(SCH_1):PAGE90_I12@PURE_QUANTA.SCONN288_ADR50017P130CC(CHIPS)':
 'DQ23_B': CDS_PINID='DQ23_B';
NODE_NAME     J10 276
 '@S9S_MB_2U_LIB.S9S_MB_2U(SCH_1):PAGE91_I13@PURE_QUANTA.SCONN288_ADR50017P087CC(CHIPS)':
 'DQ23_B': CDS_PINID='DQ23_B';
NET_NAME
'M_E_CPU0_SB_DQ<24>'
 '@S9S_MB_2U_LIB.S9S_MB_2U(SCH_1):M_E_CPU0_SB_DQ'<24>:
 C_SIGNAL='@s9s_mb_2u_lib.s9s_mb_2u(sch_1):m_e_cpu0_sb_dq(24)';
NODE_NAME     U2 EM20
 '@S9S_MB_2U_LIB.S9S_MB_2U(SCH_1):PAGE24_I169@PURE_QUANTA.SOCKET4677_AZIF0045P001C01CS(CHIPS)':
 'DDR4_SB_DQ24': CDS_PINID='DDR4_SB_DQ24';
NODE_NAME     J9 133
 '@S9S_MB_2U_LIB.S9S_MB_2U(SCH_1):PAGE90_I12@PURE_QUANTA.SCONN288_ADR50017P130CC(CHIPS)':
 'DQ24_B': CDS_PINID='DQ24_B';
NODE_NAME     J10 133
 '@S9S_MB_2U_LIB.S9S_MB_2U(SCH_1):PAGE91_I13@PURE_QUANTA.SCONN288_ADR50017P087CC(CHIPS)':
 'DQ24_B': CDS_PINID='DQ24_B';
NET_NAME
'M_E_CPU0_SB_DQ<25>'
 '@S9S_MB_2U_LIB.S9S_MB_2U(SCH_1):M_E_CPU0_SB_DQ'<25>:
 C_SIGNAL='@s9s_mb_2u_lib.s9s_mb_2u(sch_1):m_e_cpu0_sb_dq(25)';
NODE_NAME     U2 EL19
 '@S9S_MB_2U_LIB.S9S_MB_2U(SCH_1):PAGE24_I169@PURE_QUANTA.SOCKET4677_AZIF0045P001C01CS(CHIPS)':
 'DDR4_SB_DQ25': CDS_PINID='DDR4_SB_DQ25';
NODE_NAME     J9 135
 '@S9S_MB_2U_LIB.S9S_MB_2U(SCH_1):PAGE90_I12@PURE_QUANTA.SCONN288_ADR50017P130CC(CHIPS)':
 'DQ25_B': CDS_PINID='DQ25_B';
NODE_NAME     J10 135
 '@S9S_MB_2U_LIB.S9S_MB_2U(SCH_1):PAGE91_I13@PURE_QUANTA.SCONN288_ADR50017P087CC(CHIPS)':
 'DQ25_B': CDS_PINID='DQ25_B';
NET_NAME
'M_E_CPU0_SB_DQ<26>'
 '@S9S_MB_2U_LIB.S9S_MB_2U(SCH_1):M_E_CPU0_SB_DQ'<26>:
 C_SIGNAL='@s9s_mb_2u_lib.s9s_mb_2u(sch_1):m_e_cpu0_sb_dq(26)';
NODE_NAME     U2 EP20
 '@S9S_MB_2U_LIB.S9S_MB_2U(SCH_1):PAGE24_I169@PURE_QUANTA.SOCKET4677_AZIF0045P001C01CS(CHIPS)':
 'DDR4_SB_DQ26': CDS_PINID='DDR4_SB_DQ26';
NODE_NAME     J9 278
 '@S9S_MB_2U_LIB.S9S_MB_2U(SCH_1):PAGE90_I12@PURE_QUANTA.SCONN288_ADR50017P130CC(CHIPS)':
 'DQ26_B': CDS_PINID='DQ26_B';
NODE_NAME     J10 278
 '@S9S_MB_2U_LIB.S9S_MB_2U(SCH_1):PAGE91_I13@PURE_QUANTA.SCONN288_ADR50017P087CC(CHIPS)':
 'DQ26_B': CDS_PINID='DQ26_B';
NET_NAME
'M_E_CPU0_SB_DQ<27>'
 '@S9S_MB_2U_LIB.S9S_MB_2U(SCH_1):M_E_CPU0_SB_DQ'<27>:
 C_SIGNAL='@s9s_mb_2u_lib.s9s_mb_2u(sch_1):m_e_cpu0_sb_dq(27)';
NODE_NAME     U2 ER19
 '@S9S_MB_2U_LIB.S9S_MB_2U(SCH_1):PAGE24_I169@PURE_QUANTA.SOCKET4677_AZIF0045P001C01CS(CHIPS)':
 'DDR4_SB_DQ27': CDS_PINID='DDR4_SB_DQ27';
NODE_NAME     J9 280
 '@S9S_MB_2U_LIB.S9S_MB_2U(SCH_1):PAGE90_I12@PURE_QUANTA.SCONN288_ADR50017P130CC(CHIPS)':
 'DQ27_B': CDS_PINID='DQ27_B';
NODE_NAME     J10 280
 '@S9S_MB_2U_LIB.S9S_MB_2U(SCH_1):PAGE91_I13@PURE_QUANTA.SCONN288_ADR50017P087CC(CHIPS)':
 'DQ27_B': CDS_PINID='DQ27_B';
NET_NAME
'M_E_CPU0_SB_DQ<28>'
 '@S9S_MB_2U_LIB.S9S_MB_2U(SCH_1):M_E_CPU0_SB_DQ'<28>:
 C_SIGNAL='@s9s_mb_2u_lib.s9s_mb_2u(sch_1):m_e_cpu0_sb_dq(28)';
NODE_NAME     U2 EL17
 '@S9S_MB_2U_LIB.S9S_MB_2U(SCH_1):PAGE24_I169@PURE_QUANTA.SOCKET4677_AZIF0045P001C01CS(CHIPS)':
 'DDR4_SB_DQ28': CDS_PINID='DDR4_SB_DQ28';
NODE_NAME     J9 140
 '@S9S_MB_2U_LIB.S9S_MB_2U(SCH_1):PAGE90_I12@PURE_QUANTA.SCONN288_ADR50017P130CC(CHIPS)':
 'DQ28_B': CDS_PINID='DQ28_B';
NODE_NAME     J10 140
 '@S9S_MB_2U_LIB.S9S_MB_2U(SCH_1):PAGE91_I13@PURE_QUANTA.SCONN288_ADR50017P087CC(CHIPS)':
 'DQ28_B': CDS_PINID='DQ28_B';
NET_NAME
'M_E_CPU0_SB_DQ<29>'
 '@S9S_MB_2U_LIB.S9S_MB_2U(SCH_1):M_E_CPU0_SB_DQ'<29>:
 C_SIGNAL='@s9s_mb_2u_lib.s9s_mb_2u(sch_1):m_e_cpu0_sb_dq(29)';
NODE_NAME     U2 EM16
 '@S9S_MB_2U_LIB.S9S_MB_2U(SCH_1):PAGE24_I169@PURE_QUANTA.SOCKET4677_AZIF0045P001C01CS(CHIPS)':
 'DDR4_SB_DQ29': CDS_PINID='DDR4_SB_DQ29';
NODE_NAME     J9 142
 '@S9S_MB_2U_LIB.S9S_MB_2U(SCH_1):PAGE90_I12@PURE_QUANTA.SCONN288_ADR50017P130CC(CHIPS)':
 'DQ29_B': CDS_PINID='DQ29_B';
NODE_NAME     J10 142
 '@S9S_MB_2U_LIB.S9S_MB_2U(SCH_1):PAGE91_I13@PURE_QUANTA.SCONN288_ADR50017P087CC(CHIPS)':
 'DQ29_B': CDS_PINID='DQ29_B';
NET_NAME
'M_E_CPU0_SB_DQ<2>'
 '@S9S_MB_2U_LIB.S9S_MB_2U(SCH_1):M_E_CPU0_SB_DQ'<2>:
 C_SIGNAL='@s9s_mb_2u_lib.s9s_mb_2u(sch_1):m_e_cpu0_sb_dq(2)';
NODE_NAME     U2 EG29
 '@S9S_MB_2U_LIB.S9S_MB_2U(SCH_1):PAGE24_I169@PURE_QUANTA.SOCKET4677_AZIF0045P001C01CS(CHIPS)':
 'DDR4_SB_DQ2': CDS_PINID='DDR4_SB_DQ2';
NODE_NAME     J9 245
 '@S9S_MB_2U_LIB.S9S_MB_2U(SCH_1):PAGE90_I12@PURE_QUANTA.SCONN288_ADR50017P130CC(CHIPS)':
 'DQ2_B': CDS_PINID='DQ2_B';
NODE_NAME     J10 245
 '@S9S_MB_2U_LIB.S9S_MB_2U(SCH_1):PAGE91_I13@PURE_QUANTA.SCONN288_ADR50017P087CC(CHIPS)':
 'DQ2_B': CDS_PINID='DQ2_B';
NET_NAME
'M_E_CPU0_SB_DQ<30>'
 '@S9S_MB_2U_LIB.S9S_MB_2U(SCH_1):M_E_CPU0_SB_DQ'<30>:
 C_SIGNAL='@s9s_mb_2u_lib.s9s_mb_2u(sch_1):m_e_cpu0_sb_dq(30)';
NODE_NAME     U2 ER17
 '@S9S_MB_2U_LIB.S9S_MB_2U(SCH_1):PAGE24_I169@PURE_QUANTA.SOCKET4677_AZIF0045P001C01CS(CHIPS)':
 'DDR4_SB_DQ30': CDS_PINID='DDR4_SB_DQ30';
NODE_NAME     J9 285
 '@S9S_MB_2U_LIB.S9S_MB_2U(SCH_1):PAGE90_I12@PURE_QUANTA.SCONN288_ADR50017P130CC(CHIPS)':
 'DQ30_B': CDS_PINID='DQ30_B';
NODE_NAME     J10 285
 '@S9S_MB_2U_LIB.S9S_MB_2U(SCH_1):PAGE91_I13@PURE_QUANTA.SCONN288_ADR50017P087CC(CHIPS)':
 'DQ30_B': CDS_PINID='DQ30_B';
NET_NAME
'M_E_CPU0_SB_DQ<31>'
 '@S9S_MB_2U_LIB.S9S_MB_2U(SCH_1):M_E_CPU0_SB_DQ'<31>:
 C_SIGNAL='@s9s_mb_2u_lib.s9s_mb_2u(sch_1):m_e_cpu0_sb_dq(31)';
NODE_NAME     U2 EP16
 '@S9S_MB_2U_LIB.S9S_MB_2U(SCH_1):PAGE24_I169@PURE_QUANTA.SOCKET4677_AZIF0045P001C01CS(CHIPS)':
 'DDR4_SB_DQ31': CDS_PINID='DDR4_SB_DQ31';
NODE_NAME     J9 287
 '@S9S_MB_2U_LIB.S9S_MB_2U(SCH_1):PAGE90_I12@PURE_QUANTA.SCONN288_ADR50017P130CC(CHIPS)':
 'DQ31_B': CDS_PINID='DQ31_B';
NODE_NAME     J10 287
 '@S9S_MB_2U_LIB.S9S_MB_2U(SCH_1):PAGE91_I13@PURE_QUANTA.SCONN288_ADR50017P087CC(CHIPS)':
 'DQ31_B': CDS_PINID='DQ31_B';
NET_NAME
'M_E_CPU0_SB_DQ<3>'
 '@S9S_MB_2U_LIB.S9S_MB_2U(SCH_1):M_E_CPU0_SB_DQ'<3>:
 C_SIGNAL='@s9s_mb_2u_lib.s9s_mb_2u(sch_1):m_e_cpu0_sb_dq(3)';
NODE_NAME     U2 EH28
 '@S9S_MB_2U_LIB.S9S_MB_2U(SCH_1):PAGE24_I169@PURE_QUANTA.SOCKET4677_AZIF0045P001C01CS(CHIPS)':
 'DDR4_SB_DQ3': CDS_PINID='DDR4_SB_DQ3';
NODE_NAME     J9 247
 '@S9S_MB_2U_LIB.S9S_MB_2U(SCH_1):PAGE90_I12@PURE_QUANTA.SCONN288_ADR50017P130CC(CHIPS)':
 'DQ3_B': CDS_PINID='DQ3_B';
NODE_NAME     J10 247
 '@S9S_MB_2U_LIB.S9S_MB_2U(SCH_1):PAGE91_I13@PURE_QUANTA.SCONN288_ADR50017P087CC(CHIPS)':
 'DQ3_B': CDS_PINID='DQ3_B';
NET_NAME
'M_E_CPU0_SB_DQ<4>'
 '@S9S_MB_2U_LIB.S9S_MB_2U(SCH_1):M_E_CPU0_SB_DQ'<4>:
 C_SIGNAL='@s9s_mb_2u_lib.s9s_mb_2u(sch_1):m_e_cpu0_sb_dq(4)';
NODE_NAME     U2 ED26
 '@S9S_MB_2U_LIB.S9S_MB_2U(SCH_1):PAGE24_I169@PURE_QUANTA.SOCKET4677_AZIF0045P001C01CS(CHIPS)':
 'DDR4_SB_DQ4': CDS_PINID='DDR4_SB_DQ4';
NODE_NAME     J9 107
 '@S9S_MB_2U_LIB.S9S_MB_2U(SCH_1):PAGE90_I12@PURE_QUANTA.SCONN288_ADR50017P130CC(CHIPS)':
 'DQ4_B': CDS_PINID='DQ4_B';
NODE_NAME     J10 107
 '@S9S_MB_2U_LIB.S9S_MB_2U(SCH_1):PAGE91_I13@PURE_QUANTA.SCONN288_ADR50017P087CC(CHIPS)':
 'DQ4_B': CDS_PINID='DQ4_B';
NET_NAME
'M_E_CPU0_SB_DQ<5>'
 '@S9S_MB_2U_LIB.S9S_MB_2U(SCH_1):M_E_CPU0_SB_DQ'<5>:
 C_SIGNAL='@s9s_mb_2u_lib.s9s_mb_2u(sch_1):m_e_cpu0_sb_dq(5)';
NODE_NAME     U2 EE25
 '@S9S_MB_2U_LIB.S9S_MB_2U(SCH_1):PAGE24_I169@PURE_QUANTA.SOCKET4677_AZIF0045P001C01CS(CHIPS)':
 'DDR4_SB_DQ5': CDS_PINID='DDR4_SB_DQ5';
NODE_NAME     J9 109
 '@S9S_MB_2U_LIB.S9S_MB_2U(SCH_1):PAGE90_I12@PURE_QUANTA.SCONN288_ADR50017P130CC(CHIPS)':
 'DQ5_B': CDS_PINID='DQ5_B';
NODE_NAME     J10 109
 '@S9S_MB_2U_LIB.S9S_MB_2U(SCH_1):PAGE91_I13@PURE_QUANTA.SCONN288_ADR50017P087CC(CHIPS)':
 'DQ5_B': CDS_PINID='DQ5_B';
NET_NAME
'M_E_CPU0_SB_DQ<6>'
 '@S9S_MB_2U_LIB.S9S_MB_2U(SCH_1):M_E_CPU0_SB_DQ'<6>:
 C_SIGNAL='@s9s_mb_2u_lib.s9s_mb_2u(sch_1):m_e_cpu0_sb_dq(6)';
NODE_NAME     U2 EH26
 '@S9S_MB_2U_LIB.S9S_MB_2U(SCH_1):PAGE24_I169@PURE_QUANTA.SOCKET4677_AZIF0045P001C01CS(CHIPS)':
 'DDR4_SB_DQ6': CDS_PINID='DDR4_SB_DQ6';
NODE_NAME     J9 252
 '@S9S_MB_2U_LIB.S9S_MB_2U(SCH_1):PAGE90_I12@PURE_QUANTA.SCONN288_ADR50017P130CC(CHIPS)':
 'DQ6_B': CDS_PINID='DQ6_B';
NODE_NAME     J10 252
 '@S9S_MB_2U_LIB.S9S_MB_2U(SCH_1):PAGE91_I13@PURE_QUANTA.SCONN288_ADR50017P087CC(CHIPS)':
 'DQ6_B': CDS_PINID='DQ6_B';
NET_NAME
'M_E_CPU0_SB_DQ<7>'
 '@S9S_MB_2U_LIB.S9S_MB_2U(SCH_1):M_E_CPU0_SB_DQ'<7>:
 C_SIGNAL='@s9s_mb_2u_lib.s9s_mb_2u(sch_1):m_e_cpu0_sb_dq(7)';
NODE_NAME     U2 EG25
 '@S9S_MB_2U_LIB.S9S_MB_2U(SCH_1):PAGE24_I169@PURE_QUANTA.SOCKET4677_AZIF0045P001C01CS(CHIPS)':
 'DDR4_SB_DQ7': CDS_PINID='DDR4_SB_DQ7';
NODE_NAME     J9 254
 '@S9S_MB_2U_LIB.S9S_MB_2U(SCH_1):PAGE90_I12@PURE_QUANTA.SCONN288_ADR50017P130CC(CHIPS)':
 'DQ7_B': CDS_PINID='DQ7_B';
NODE_NAME     J10 254
 '@S9S_MB_2U_LIB.S9S_MB_2U(SCH_1):PAGE91_I13@PURE_QUANTA.SCONN288_ADR50017P087CC(CHIPS)':
 'DQ7_B': CDS_PINID='DQ7_B';
NET_NAME
'M_E_CPU0_SB_DQ<8>'
 '@S9S_MB_2U_LIB.S9S_MB_2U(SCH_1):M_E_CPU0_SB_DQ'<8>:
 C_SIGNAL='@s9s_mb_2u_lib.s9s_mb_2u(sch_1):m_e_cpu0_sb_dq(8)';
NODE_NAME     U2 EM32
 '@S9S_MB_2U_LIB.S9S_MB_2U(SCH_1):PAGE24_I169@PURE_QUANTA.SOCKET4677_AZIF0045P001C01CS(CHIPS)':
 'DDR4_SB_DQ8': CDS_PINID='DDR4_SB_DQ8';
NODE_NAME     J9 111
 '@S9S_MB_2U_LIB.S9S_MB_2U(SCH_1):PAGE90_I12@PURE_QUANTA.SCONN288_ADR50017P130CC(CHIPS)':
 'DQ8_B': CDS_PINID='DQ8_B';
NODE_NAME     J10 111
 '@S9S_MB_2U_LIB.S9S_MB_2U(SCH_1):PAGE91_I13@PURE_QUANTA.SCONN288_ADR50017P087CC(CHIPS)':
 'DQ8_B': CDS_PINID='DQ8_B';
NET_NAME
'M_E_CPU0_SB_DQ<9>'
 '@S9S_MB_2U_LIB.S9S_MB_2U(SCH_1):M_E_CPU0_SB_DQ'<9>:
 C_SIGNAL='@s9s_mb_2u_lib.s9s_mb_2u(sch_1):m_e_cpu0_sb_dq(9)';
NODE_NAME     U2 EL31
 '@S9S_MB_2U_LIB.S9S_MB_2U(SCH_1):PAGE24_I169@PURE_QUANTA.SOCKET4677_AZIF0045P001C01CS(CHIPS)':
 'DDR4_SB_DQ9': CDS_PINID='DDR4_SB_DQ9';
NODE_NAME     J9 113
 '@S9S_MB_2U_LIB.S9S_MB_2U(SCH_1):PAGE90_I12@PURE_QUANTA.SCONN288_ADR50017P130CC(CHIPS)':
 'DQ9_B': CDS_PINID='DQ9_B';
NODE_NAME     J10 113
 '@S9S_MB_2U_LIB.S9S_MB_2U(SCH_1):PAGE91_I13@PURE_QUANTA.SCONN288_ADR50017P087CC(CHIPS)':
 'DQ9_B': CDS_PINID='DQ9_B';
NET_NAME
'M_E_CPU0_SB_DQS_DN<0>'
 '@S9S_MB_2U_LIB.S9S_MB_2U(SCH_1):M_E_CPU0_SB_DQS_DN'<0>:
 C_SIGNAL='@s9s_mb_2u_lib.s9s_mb_2u(sch_1):m_e_cpu0_sb_dqs_dn(0)';
NODE_NAME     U2 EE27
 '@S9S_MB_2U_LIB.S9S_MB_2U(SCH_1):PAGE24_I169@PURE_QUANTA.SOCKET4677_AZIF0045P001C01CS(CHIPS)':
 'DDR4_SB_DQS_DN0': CDS_PINID='DDR4_SB_DQS_DN0';
NODE_NAME     J9 105
 '@S9S_MB_2U_LIB.S9S_MB_2U(SCH_1):PAGE90_I178@PURE_QUANTA.SCONN288_ADR50017P130CC(CHIPS)':
 'DQS0_B_C': CDS_PINID='DQS0_B_C';
NODE_NAME     J10 105
 '@S9S_MB_2U_LIB.S9S_MB_2U(SCH_1):PAGE91_I178@PURE_QUANTA.SCONN288_ADR50017P087CC(CHIPS)':
 'DQS0_B_C': CDS_PINID='DQS0_B_C';
NET_NAME
'M_E_CPU0_SB_DQS_DN<1>'
 '@S9S_MB_2U_LIB.S9S_MB_2U(SCH_1):M_E_CPU0_SB_DQS_DN'<1>:
 C_SIGNAL='@s9s_mb_2u_lib.s9s_mb_2u(sch_1):m_e_cpu0_sb_dqs_dn(1)';
NODE_NAME     U2 EK30
 '@S9S_MB_2U_LIB.S9S_MB_2U(SCH_1):PAGE24_I169@PURE_QUANTA.SOCKET4677_AZIF0045P001C01CS(CHIPS)':
 'DDR4_SB_DQS_DN1': CDS_PINID='DDR4_SB_DQS_DN1';
NODE_NAME     J9 116
 '@S9S_MB_2U_LIB.S9S_MB_2U(SCH_1):PAGE90_I178@PURE_QUANTA.SCONN288_ADR50017P130CC(CHIPS)':
 'DQS1_B_C': CDS_PINID='DQS1_B_C';
NODE_NAME     J10 116
 '@S9S_MB_2U_LIB.S9S_MB_2U(SCH_1):PAGE91_I178@PURE_QUANTA.SCONN288_ADR50017P087CC(CHIPS)':
 'DQS1_B_C': CDS_PINID='DQS1_B_C';
NET_NAME
'M_E_CPU0_SB_DQS_DN<2>'
 '@S9S_MB_2U_LIB.S9S_MB_2U(SCH_1):M_E_CPU0_SB_DQS_DN'<2>:
 C_SIGNAL='@s9s_mb_2u_lib.s9s_mb_2u(sch_1):m_e_cpu0_sb_dqs_dn(2)';
NODE_NAME     U2 EK24
 '@S9S_MB_2U_LIB.S9S_MB_2U(SCH_1):PAGE24_I169@PURE_QUANTA.SOCKET4677_AZIF0045P001C01CS(CHIPS)':
 'DDR4_SB_DQS_DN2': CDS_PINID='DDR4_SB_DQS_DN2';
NODE_NAME     J9 127
 '@S9S_MB_2U_LIB.S9S_MB_2U(SCH_1):PAGE90_I178@PURE_QUANTA.SCONN288_ADR50017P130CC(CHIPS)':
 'DQS2_B_C': CDS_PINID='DQS2_B_C';
NODE_NAME     J10 127
 '@S9S_MB_2U_LIB.S9S_MB_2U(SCH_1):PAGE91_I178@PURE_QUANTA.SCONN288_ADR50017P087CC(CHIPS)':
 'DQS2_B_C': CDS_PINID='DQS2_B_C';
NET_NAME
'M_E_CPU0_SB_DQS_DN<3>'
 '@S9S_MB_2U_LIB.S9S_MB_2U(SCH_1):M_E_CPU0_SB_DQS_DN'<3>:
 C_SIGNAL='@s9s_mb_2u_lib.s9s_mb_2u(sch_1):m_e_cpu0_sb_dqs_dn(3)';
NODE_NAME     U2 EK18
 '@S9S_MB_2U_LIB.S9S_MB_2U(SCH_1):PAGE24_I169@PURE_QUANTA.SOCKET4677_AZIF0045P001C01CS(CHIPS)':
 'DDR4_SB_DQS_DN3': CDS_PINID='DDR4_SB_DQS_DN3';
NODE_NAME     J9 138
 '@S9S_MB_2U_LIB.S9S_MB_2U(SCH_1):PAGE90_I178@PURE_QUANTA.SCONN288_ADR50017P130CC(CHIPS)':
 'DQS3_B_C': CDS_PINID='DQS3_B_C';
NODE_NAME     J10 138
 '@S9S_MB_2U_LIB.S9S_MB_2U(SCH_1):PAGE91_I178@PURE_QUANTA.SCONN288_ADR50017P087CC(CHIPS)':
 'DQS3_B_C': CDS_PINID='DQS3_B_C';
NET_NAME
'M_E_CPU0_SB_DQS_DN<4>'
 '@S9S_MB_2U_LIB.S9S_MB_2U(SCH_1):M_E_CPU0_SB_DQS_DN'<4>:
 C_SIGNAL='@s9s_mb_2u_lib.s9s_mb_2u(sch_1):m_e_cpu0_sb_dqs_dn(4)';
NODE_NAME     U2 ET36
 '@S9S_MB_2U_LIB.S9S_MB_2U(SCH_1):PAGE24_I169@PURE_QUANTA.SOCKET4677_AZIF0045P001C01CS(CHIPS)':
 'DDR4_SB_DQS_DN4': CDS_PINID='DDR4_SB_DQS_DN4';
NODE_NAME     J9 238
 '@S9S_MB_2U_LIB.S9S_MB_2U(SCH_1):PAGE90_I178@PURE_QUANTA.SCONN288_ADR50017P130CC(CHIPS)':
 'DQS4_B_C': CDS_PINID='DQS4_B_C';
NODE_NAME     J10 238
 '@S9S_MB_2U_LIB.S9S_MB_2U(SCH_1):PAGE91_I178@PURE_QUANTA.SCONN288_ADR50017P087CC(CHIPS)':
 'DQS4_B_C': CDS_PINID='DQS4_B_C';
NET_NAME
'M_E_CPU0_SB_DQS_DN<5>'
 '@S9S_MB_2U_LIB.S9S_MB_2U(SCH_1):M_E_CPU0_SB_DQS_DN'<5>:
 C_SIGNAL='@s9s_mb_2u_lib.s9s_mb_2u(sch_1):m_e_cpu0_sb_dqs_dn(5)';
NODE_NAME     U2 EJ27
 '@S9S_MB_2U_LIB.S9S_MB_2U(SCH_1):PAGE24_I169@PURE_QUANTA.SOCKET4677_AZIF0045P001C01CS(CHIPS)':
 'DDR4_SB_DQS_DN5': CDS_PINID='DDR4_SB_DQS_DN5';
NODE_NAME     J9 249
 '@S9S_MB_2U_LIB.S9S_MB_2U(SCH_1):PAGE90_I178@PURE_QUANTA.SCONN288_ADR50017P130CC(CHIPS)':
 'DQS5_B_C||TDQS5_B_C': CDS_PINID='\dqs5_b_c||tdqs5_b_c\';
NODE_NAME     J10 249
 '@S9S_MB_2U_LIB.S9S_MB_2U(SCH_1):PAGE91_I178@PURE_QUANTA.SCONN288_ADR50017P087CC(CHIPS)':
 'DQS5_B_C||TDQS5_B_C': CDS_PINID='\dqs5_b_c||tdqs5_b_c\';
NET_NAME
'M_E_CPU0_SB_DQS_DN<6>'
 '@S9S_MB_2U_LIB.S9S_MB_2U(SCH_1):M_E_CPU0_SB_DQS_DN'<6>:
 C_SIGNAL='@s9s_mb_2u_lib.s9s_mb_2u(sch_1):m_e_cpu0_sb_dqs_dn(6)';
NODE_NAME     U2 ET30
 '@S9S_MB_2U_LIB.S9S_MB_2U(SCH_1):PAGE24_I169@PURE_QUANTA.SOCKET4677_AZIF0045P001C01CS(CHIPS)':
 'DDR4_SB_DQS_DN6': CDS_PINID='DDR4_SB_DQS_DN6';
NODE_NAME     J9 260
 '@S9S_MB_2U_LIB.S9S_MB_2U(SCH_1):PAGE90_I178@PURE_QUANTA.SCONN288_ADR50017P130CC(CHIPS)':
 'DQS6_B_C||TDQS6_B_C': CDS_PINID='\dqs6_b_c||tdqs6_b_c\';
NODE_NAME     J10 260
 '@S9S_MB_2U_LIB.S9S_MB_2U(SCH_1):PAGE91_I178@PURE_QUANTA.SCONN288_ADR50017P087CC(CHIPS)':
 'DQS6_B_C||TDQS6_B_C': CDS_PINID='\dqs6_b_c||tdqs6_b_c\';
NET_NAME
'M_E_CPU0_SB_DQS_DN<7>'
 '@S9S_MB_2U_LIB.S9S_MB_2U(SCH_1):M_E_CPU0_SB_DQS_DN'<7>:
 C_SIGNAL='@s9s_mb_2u_lib.s9s_mb_2u(sch_1):m_e_cpu0_sb_dqs_dn(7)';
NODE_NAME     U2 ET24
 '@S9S_MB_2U_LIB.S9S_MB_2U(SCH_1):PAGE24_I169@PURE_QUANTA.SOCKET4677_AZIF0045P001C01CS(CHIPS)':
 'DDR4_SB_DQS_DN7': CDS_PINID='DDR4_SB_DQS_DN7';
NODE_NAME     J9 271
 '@S9S_MB_2U_LIB.S9S_MB_2U(SCH_1):PAGE90_I178@PURE_QUANTA.SCONN288_ADR50017P130CC(CHIPS)':
 'DQS7_B_C||TDQS7_B_C': CDS_PINID='\dqs7_b_c||tdqs7_b_c\';
NODE_NAME     J10 271
 '@S9S_MB_2U_LIB.S9S_MB_2U(SCH_1):PAGE91_I178@PURE_QUANTA.SCONN288_ADR50017P087CC(CHIPS)':
 'DQS7_B_C||TDQS7_B_C': CDS_PINID='\dqs7_b_c||tdqs7_b_c\';
NET_NAME
'M_E_CPU0_SB_DQS_DN<8>'
 '@S9S_MB_2U_LIB.S9S_MB_2U(SCH_1):M_E_CPU0_SB_DQS_DN'<8>:
 C_SIGNAL='@s9s_mb_2u_lib.s9s_mb_2u(sch_1):m_e_cpu0_sb_dqs_dn(8)';
NODE_NAME     U2 ET18
 '@S9S_MB_2U_LIB.S9S_MB_2U(SCH_1):PAGE24_I169@PURE_QUANTA.SOCKET4677_AZIF0045P001C01CS(CHIPS)':
 'DDR4_SB_DQS_DN8': CDS_PINID='DDR4_SB_DQS_DN8';
NODE_NAME     J9 282
 '@S9S_MB_2U_LIB.S9S_MB_2U(SCH_1):PAGE90_I178@PURE_QUANTA.SCONN288_ADR50017P130CC(CHIPS)':
 'DQS8_B_C||TDQS8_B_C': CDS_PINID='\dqs8_b_c||tdqs8_b_c\';
NODE_NAME     J10 282
 '@S9S_MB_2U_LIB.S9S_MB_2U(SCH_1):PAGE91_I178@PURE_QUANTA.SCONN288_ADR50017P087CC(CHIPS)':
 'DQS8_B_C||TDQS8_B_C': CDS_PINID='\dqs8_b_c||tdqs8_b_c\';
NET_NAME
'M_E_CPU0_SB_DQS_DN<9>'
 '@S9S_MB_2U_LIB.S9S_MB_2U(SCH_1):M_E_CPU0_SB_DQS_DN'<9>:
 C_SIGNAL='@s9s_mb_2u_lib.s9s_mb_2u(sch_1):m_e_cpu0_sb_dqs_dn(9)';
NODE_NAME     U2 EK36
 '@S9S_MB_2U_LIB.S9S_MB_2U(SCH_1):PAGE24_I169@PURE_QUANTA.SOCKET4677_AZIF0045P001C01CS(CHIPS)':
 'DDR4_SB_DQS_DN9': CDS_PINID='DDR4_SB_DQS_DN9';
NODE_NAME     J9 94
 '@S9S_MB_2U_LIB.S9S_MB_2U(SCH_1):PAGE90_I178@PURE_QUANTA.SCONN288_ADR50017P130CC(CHIPS)':
 'DQS9_B_C||TDQS9_B_C': CDS_PINID='\dqs9_b_c||tdqs9_b_c\';
NODE_NAME     J10 94
 '@S9S_MB_2U_LIB.S9S_MB_2U(SCH_1):PAGE91_I178@PURE_QUANTA.SCONN288_ADR50017P087CC(CHIPS)':
 'DQS9_B_C||TDQS9_B_C': CDS_PINID='\dqs9_b_c||tdqs9_b_c\';
NET_NAME
'M_E_CPU0_SB_DQS_DP<0>'
 '@S9S_MB_2U_LIB.S9S_MB_2U(SCH_1):M_E_CPU0_SB_DQS_DP'<0>:
 C_SIGNAL='@s9s_mb_2u_lib.s9s_mb_2u(sch_1):m_e_cpu0_sb_dqs_dp(0)';
NODE_NAME     U2 EC27
 '@S9S_MB_2U_LIB.S9S_MB_2U(SCH_1):PAGE24_I169@PURE_QUANTA.SOCKET4677_AZIF0045P001C01CS(CHIPS)':
 'DDR4_SB_DQS_DP0': CDS_PINID='DDR4_SB_DQS_DP0';
NODE_NAME     J9 104
 '@S9S_MB_2U_LIB.S9S_MB_2U(SCH_1):PAGE90_I178@PURE_QUANTA.SCONN288_ADR50017P130CC(CHIPS)':
 'DQS0_B_T': CDS_PINID='DQS0_B_T';
NODE_NAME     J10 104
 '@S9S_MB_2U_LIB.S9S_MB_2U(SCH_1):PAGE91_I178@PURE_QUANTA.SCONN288_ADR50017P087CC(CHIPS)':
 'DQS0_B_T': CDS_PINID='DQS0_B_T';
NET_NAME
'M_E_CPU0_SB_DQS_DP<1>'
 '@S9S_MB_2U_LIB.S9S_MB_2U(SCH_1):M_E_CPU0_SB_DQS_DP'<1>:
 C_SIGNAL='@s9s_mb_2u_lib.s9s_mb_2u(sch_1):m_e_cpu0_sb_dqs_dp(1)';
NODE_NAME     U2 EM30
 '@S9S_MB_2U_LIB.S9S_MB_2U(SCH_1):PAGE24_I169@PURE_QUANTA.SOCKET4677_AZIF0045P001C01CS(CHIPS)':
 'DDR4_SB_DQS_DP1': CDS_PINID='DDR4_SB_DQS_DP1';
NODE_NAME     J9 115
 '@S9S_MB_2U_LIB.S9S_MB_2U(SCH_1):PAGE90_I178@PURE_QUANTA.SCONN288_ADR50017P130CC(CHIPS)':
 'DQS1_B_T': CDS_PINID='DQS1_B_T';
NODE_NAME     J10 115
 '@S9S_MB_2U_LIB.S9S_MB_2U(SCH_1):PAGE91_I178@PURE_QUANTA.SCONN288_ADR50017P087CC(CHIPS)':
 'DQS1_B_T': CDS_PINID='DQS1_B_T';
NET_NAME
'M_E_CPU0_SB_DQS_DP<2>'
 '@S9S_MB_2U_LIB.S9S_MB_2U(SCH_1):M_E_CPU0_SB_DQS_DP'<2>:
 C_SIGNAL='@s9s_mb_2u_lib.s9s_mb_2u(sch_1):m_e_cpu0_sb_dqs_dp(2)';
NODE_NAME     U2 EM24
 '@S9S_MB_2U_LIB.S9S_MB_2U(SCH_1):PAGE24_I169@PURE_QUANTA.SOCKET4677_AZIF0045P001C01CS(CHIPS)':
 'DDR4_SB_DQS_DP2': CDS_PINID='DDR4_SB_DQS_DP2';
NODE_NAME     J9 126
 '@S9S_MB_2U_LIB.S9S_MB_2U(SCH_1):PAGE90_I178@PURE_QUANTA.SCONN288_ADR50017P130CC(CHIPS)':
 'DQS2_B_T': CDS_PINID='DQS2_B_T';
NODE_NAME     J10 126
 '@S9S_MB_2U_LIB.S9S_MB_2U(SCH_1):PAGE91_I178@PURE_QUANTA.SCONN288_ADR50017P087CC(CHIPS)':
 'DQS2_B_T': CDS_PINID='DQS2_B_T';
NET_NAME
'M_E_CPU0_SB_DQS_DP<3>'
 '@S9S_MB_2U_LIB.S9S_MB_2U(SCH_1):M_E_CPU0_SB_DQS_DP'<3>:
 C_SIGNAL='@s9s_mb_2u_lib.s9s_mb_2u(sch_1):m_e_cpu0_sb_dqs_dp(3)';
NODE_NAME     U2 EM18
 '@S9S_MB_2U_LIB.S9S_MB_2U(SCH_1):PAGE24_I169@PURE_QUANTA.SOCKET4677_AZIF0045P001C01CS(CHIPS)':
 'DDR4_SB_DQS_DP3': CDS_PINID='DDR4_SB_DQS_DP3';
NODE_NAME     J9 137
 '@S9S_MB_2U_LIB.S9S_MB_2U(SCH_1):PAGE90_I178@PURE_QUANTA.SCONN288_ADR50017P130CC(CHIPS)':
 'DQS3_B_T': CDS_PINID='DQS3_B_T';
NODE_NAME     J10 137
 '@S9S_MB_2U_LIB.S9S_MB_2U(SCH_1):PAGE91_I178@PURE_QUANTA.SCONN288_ADR50017P087CC(CHIPS)':
 'DQS3_B_T': CDS_PINID='DQS3_B_T';
NET_NAME
'M_E_CPU0_SB_DQS_DP<4>'
 '@S9S_MB_2U_LIB.S9S_MB_2U(SCH_1):M_E_CPU0_SB_DQS_DP'<4>:
 C_SIGNAL='@s9s_mb_2u_lib.s9s_mb_2u(sch_1):m_e_cpu0_sb_dqs_dp(4)';
NODE_NAME     U2 EP36
 '@S9S_MB_2U_LIB.S9S_MB_2U(SCH_1):PAGE24_I169@PURE_QUANTA.SOCKET4677_AZIF0045P001C01CS(CHIPS)':
 'DDR4_SB_DQS_DP4': CDS_PINID='DDR4_SB_DQS_DP4';
NODE_NAME     J9 239
 '@S9S_MB_2U_LIB.S9S_MB_2U(SCH_1):PAGE90_I178@PURE_QUANTA.SCONN288_ADR50017P130CC(CHIPS)':
 'DQS4_B_T': CDS_PINID='DQS4_B_T';
NODE_NAME     J10 239
 '@S9S_MB_2U_LIB.S9S_MB_2U(SCH_1):PAGE91_I178@PURE_QUANTA.SCONN288_ADR50017P087CC(CHIPS)':
 'DQS4_B_T': CDS_PINID='DQS4_B_T';
NET_NAME
'M_E_CPU0_SB_DQS_DP<5>'
 '@S9S_MB_2U_LIB.S9S_MB_2U(SCH_1):M_E_CPU0_SB_DQS_DP'<5>:
 C_SIGNAL='@s9s_mb_2u_lib.s9s_mb_2u(sch_1):m_e_cpu0_sb_dqs_dp(5)';
NODE_NAME     U2 EG27
 '@S9S_MB_2U_LIB.S9S_MB_2U(SCH_1):PAGE24_I169@PURE_QUANTA.SOCKET4677_AZIF0045P001C01CS(CHIPS)':
 'DDR4_SB_DQS_DP5': CDS_PINID='DDR4_SB_DQS_DP5';
NODE_NAME     J9 250
 '@S9S_MB_2U_LIB.S9S_MB_2U(SCH_1):PAGE90_I178@PURE_QUANTA.SCONN288_ADR50017P130CC(CHIPS)':
 'DQS5_B_T||TDQS5_B_T': CDS_PINID='\dqs5_b_t||tdqs5_b_t\';
NODE_NAME     J10 250
 '@S9S_MB_2U_LIB.S9S_MB_2U(SCH_1):PAGE91_I178@PURE_QUANTA.SCONN288_ADR50017P087CC(CHIPS)':
 'DQS5_B_T||TDQS5_B_T': CDS_PINID='\dqs5_b_t||tdqs5_b_t\';
NET_NAME
'M_E_CPU0_SB_DQS_DP<6>'
 '@S9S_MB_2U_LIB.S9S_MB_2U(SCH_1):M_E_CPU0_SB_DQS_DP'<6>:
 C_SIGNAL='@s9s_mb_2u_lib.s9s_mb_2u(sch_1):m_e_cpu0_sb_dqs_dp(6)';
NODE_NAME     U2 EP30
 '@S9S_MB_2U_LIB.S9S_MB_2U(SCH_1):PAGE24_I169@PURE_QUANTA.SOCKET4677_AZIF0045P001C01CS(CHIPS)':
 'DDR4_SB_DQS_DP6': CDS_PINID='DDR4_SB_DQS_DP6';
NODE_NAME     J9 261
 '@S9S_MB_2U_LIB.S9S_MB_2U(SCH_1):PAGE90_I178@PURE_QUANTA.SCONN288_ADR50017P130CC(CHIPS)':
 'DQS6_B_T||TDQS6_B_T': CDS_PINID='\dqs6_b_t||tdqs6_b_t\';
NODE_NAME     J10 261
 '@S9S_MB_2U_LIB.S9S_MB_2U(SCH_1):PAGE91_I178@PURE_QUANTA.SCONN288_ADR50017P087CC(CHIPS)':
 'DQS6_B_T||TDQS6_B_T': CDS_PINID='\dqs6_b_t||tdqs6_b_t\';
NET_NAME
'M_E_CPU0_SB_DQS_DP<7>'
 '@S9S_MB_2U_LIB.S9S_MB_2U(SCH_1):M_E_CPU0_SB_DQS_DP'<7>:
 C_SIGNAL='@s9s_mb_2u_lib.s9s_mb_2u(sch_1):m_e_cpu0_sb_dqs_dp(7)';
NODE_NAME     U2 EP24
 '@S9S_MB_2U_LIB.S9S_MB_2U(SCH_1):PAGE24_I169@PURE_QUANTA.SOCKET4677_AZIF0045P001C01CS(CHIPS)':
 'DDR4_SB_DQS_DP7': CDS_PINID='DDR4_SB_DQS_DP7';
NODE_NAME     J9 272
 '@S9S_MB_2U_LIB.S9S_MB_2U(SCH_1):PAGE90_I178@PURE_QUANTA.SCONN288_ADR50017P130CC(CHIPS)':
 'DQS7_B_T||TDQS7_B_T': CDS_PINID='\dqs7_b_t||tdqs7_b_t\';
NODE_NAME     J10 272
 '@S9S_MB_2U_LIB.S9S_MB_2U(SCH_1):PAGE91_I178@PURE_QUANTA.SCONN288_ADR50017P087CC(CHIPS)':
 'DQS7_B_T||TDQS7_B_T': CDS_PINID='\dqs7_b_t||tdqs7_b_t\';
NET_NAME
'M_E_CPU0_SB_DQS_DP<8>'
 '@S9S_MB_2U_LIB.S9S_MB_2U(SCH_1):M_E_CPU0_SB_DQS_DP'<8>:
 C_SIGNAL='@s9s_mb_2u_lib.s9s_mb_2u(sch_1):m_e_cpu0_sb_dqs_dp(8)';
NODE_NAME     U2 EP18
 '@S9S_MB_2U_LIB.S9S_MB_2U(SCH_1):PAGE24_I169@PURE_QUANTA.SOCKET4677_AZIF0045P001C01CS(CHIPS)':
 'DDR4_SB_DQS_DP8': CDS_PINID='DDR4_SB_DQS_DP8';
NODE_NAME     J9 283
 '@S9S_MB_2U_LIB.S9S_MB_2U(SCH_1):PAGE90_I178@PURE_QUANTA.SCONN288_ADR50017P130CC(CHIPS)':
 'DQS8_B_T||TDQS8_B_T': CDS_PINID='\dqs8_b_t||tdqs8_b_t\';
NODE_NAME     J10 283
 '@S9S_MB_2U_LIB.S9S_MB_2U(SCH_1):PAGE91_I178@PURE_QUANTA.SCONN288_ADR50017P087CC(CHIPS)':
 'DQS8_B_T||TDQS8_B_T': CDS_PINID='\dqs8_b_t||tdqs8_b_t\';
NET_NAME
'M_E_CPU0_SB_DQS_DP<9>'
 '@S9S_MB_2U_LIB.S9S_MB_2U(SCH_1):M_E_CPU0_SB_DQS_DP'<9>:
 C_SIGNAL='@s9s_mb_2u_lib.s9s_mb_2u(sch_1):m_e_cpu0_sb_dqs_dp(9)';
NODE_NAME     U2 EM36
 '@S9S_MB_2U_LIB.S9S_MB_2U(SCH_1):PAGE24_I169@PURE_QUANTA.SOCKET4677_AZIF0045P001C01CS(CHIPS)':
 'DDR4_SB_DQS_DP9': CDS_PINID='DDR4_SB_DQS_DP9';
NODE_NAME     J9 93
 '@S9S_MB_2U_LIB.S9S_MB_2U(SCH_1):PAGE90_I178@PURE_QUANTA.SCONN288_ADR50017P130CC(CHIPS)':
 'DQS9_B_T||TDQS9_B_T||DBI4_B_N': CDS_PINID='\dqs9_b_t||tdqs9_b_t||dbi4_b_n\';
NODE_NAME     J10 93
 '@S9S_MB_2U_LIB.S9S_MB_2U(SCH_1):PAGE91_I178@PURE_QUANTA.SCONN288_ADR50017P087CC(CHIPS)':
 'DQS9_B_T||TDQS9_B_T||DBI4_B_N': CDS_PINID='\dqs9_b_t||tdqs9_b_t||dbi4_b_n\';
NET_NAME
'M_E_CPU0_SB_PAR'
 '@S9S_MB_2U_LIB.S9S_MB_2U(SCH_1):M_E_CPU0_SB_PAR':
 C_SIGNAL='@s9s_mb_2u_lib.s9s_mb_2u(sch_1):m_e_cpu0_sb_par';
NODE_NAME     U2 EP42
 '@S9S_MB_2U_LIB.S9S_MB_2U(SCH_1):PAGE24_I169@PURE_QUANTA.SOCKET4677_AZIF0045P001C01CS(CHIPS)':
 'DDR4_SB_PAR': CDS_PINID='DDR4_SB_PAR';
NODE_NAME     J9 227
 '@S9S_MB_2U_LIB.S9S_MB_2U(SCH_1):PAGE90_I12@PURE_QUANTA.SCONN288_ADR50017P130CC(CHIPS)':
 'PAR_B': CDS_PINID='PAR_B';
NODE_NAME     J10 227
 '@S9S_MB_2U_LIB.S9S_MB_2U(SCH_1):PAGE91_I13@PURE_QUANTA.SCONN288_ADR50017P087CC(CHIPS)':
 'PAR_B': CDS_PINID='PAR_B';
NET_NAME
'M_E_CPU0_SB_RSP<0>'
 '@S9S_MB_2U_LIB.S9S_MB_2U(SCH_1):M_E_CPU0_SB_RSP'<0>:
 C_SIGNAL='@s9s_mb_2u_lib.s9s_mb_2u(sch_1):m_e_cpu0_sb_rsp(0)';
NODE_NAME     U2 DF44
 '@S9S_MB_2U_LIB.S9S_MB_2U(SCH_1):PAGE24_I169@PURE_QUANTA.SOCKET4677_AZIF0045P001C01CS(CHIPS)':
 'DDR4_B_RSP0': CDS_PINID='DDR4_B_RSP0';
NODE_NAME     J9 87
 '@S9S_MB_2U_LIB.S9S_MB_2U(SCH_1):PAGE90_I12@PURE_QUANTA.SCONN288_ADR50017P130CC(CHIPS)':
 'LBS||RSP_B_N': CDS_PINID='\lbs||rsp_b_n\';
NET_NAME
'M_E_CPU0_SB_RSP<1>'
 '@S9S_MB_2U_LIB.S9S_MB_2U(SCH_1):M_E_CPU0_SB_RSP'<1>:
 C_SIGNAL='@s9s_mb_2u_lib.s9s_mb_2u(sch_1):m_e_cpu0_sb_rsp(1)';
NODE_NAME     U2 DG43
 '@S9S_MB_2U_LIB.S9S_MB_2U(SCH_1):PAGE24_I169@PURE_QUANTA.SOCKET4677_AZIF0045P001C01CS(CHIPS)':
 'DDR4_B_RSP1': CDS_PINID='DDR4_B_RSP1';
NODE_NAME     J10 87
 '@S9S_MB_2U_LIB.S9S_MB_2U(SCH_1):PAGE91_I13@PURE_QUANTA.SCONN288_ADR50017P087CC(CHIPS)':
 'LBS||RSP_B_N': CDS_PINID='\lbs||rsp_b_n\';
NET_NAME
'M_E_CPU1_ALERT_N'
 '@S9S_MB_2U_LIB.S9S_MB_2U(SCH_1):M_E_CPU1_ALERT_N':
 C_SIGNAL='@s9s_mb_2u_lib.s9s_mb_2u(sch_1):m_e_cpu1_alert_n';
NODE_NAME     U1 CY47
 '@S9S_MB_2U_LIB.S9S_MB_2U(SCH_1):PAGE55_I7@PURE_QUANTA.SOCKET4677_AZIF0045P001C01CS(CHIPS)':
 'DDR4_ALERT_N': CDS_PINID='DDR4_ALERT_N';
NODE_NAME     J25 62
 '@S9S_MB_2U_LIB.S9S_MB_2U(SCH_1):PAGE106_I180@PURE_QUANTA.SCONN288_ADR50017P130CC(CHIPS)':
 'ALERT_N': CDS_PINID='ALERT_N';
NODE_NAME     J26 62
 '@S9S_MB_2U_LIB.S9S_MB_2U(SCH_1):PAGE107_I180@PURE_QUANTA.SCONN288_ADR50017P087CC(CHIPS)':
 'ALERT_N': CDS_PINID='ALERT_N';
NET_NAME
'M_E_CPU1_CLK_DN<0>'
 '@S9S_MB_2U_LIB.S9S_MB_2U(SCH_1):M_E_CPU1_CLK_DN'<0>:
 C_SIGNAL='@s9s_mb_2u_lib.s9s_mb_2u(sch_1):m_e_cpu1_clk_dn(0)';
NODE_NAME     U1 EJ45
 '@S9S_MB_2U_LIB.S9S_MB_2U(SCH_1):PAGE55_I7@PURE_QUANTA.SOCKET4677_AZIF0045P001C01CS(CHIPS)':
 'DDR4_CLK_DN0': CDS_PINID='DDR4_CLK_DN0';
NODE_NAME     J25 218
 '@S9S_MB_2U_LIB.S9S_MB_2U(SCH_1):PAGE106_I180@PURE_QUANTA.SCONN288_ADR50017P130CC(CHIPS)':
 'CK_C': CDS_PINID='CK_C';
NET_NAME
'M_E_CPU1_CLK_DN<1>'
 '@S9S_MB_2U_LIB.S9S_MB_2U(SCH_1):M_E_CPU1_CLK_DN'<1>:
 C_SIGNAL='@s9s_mb_2u_lib.s9s_mb_2u(sch_1):m_e_cpu1_clk_dn(1)';
NODE_NAME     U1 EE45
 '@S9S_MB_2U_LIB.S9S_MB_2U(SCH_1):PAGE55_I7@PURE_QUANTA.SOCKET4677_AZIF0045P001C01CS(CHIPS)':
 'DDR4_CLK_DN1': CDS_PINID='DDR4_CLK_DN1';
NODE_NAME     J26 218
 '@S9S_MB_2U_LIB.S9S_MB_2U(SCH_1):PAGE107_I180@PURE_QUANTA.SCONN288_ADR50017P087CC(CHIPS)':
 'CK_C': CDS_PINID='CK_C';
NET_NAME
'M_E_CPU1_CLK_DP<0>'
 '@S9S_MB_2U_LIB.S9S_MB_2U(SCH_1):M_E_CPU1_CLK_DP'<0>:
 C_SIGNAL='@s9s_mb_2u_lib.s9s_mb_2u(sch_1):m_e_cpu1_clk_dp(0)';
NODE_NAME     U1 EG45
 '@S9S_MB_2U_LIB.S9S_MB_2U(SCH_1):PAGE55_I7@PURE_QUANTA.SOCKET4677_AZIF0045P001C01CS(CHIPS)':
 'DDR4_CLK_DP0': CDS_PINID='DDR4_CLK_DP0';
NODE_NAME     J25 217
 '@S9S_MB_2U_LIB.S9S_MB_2U(SCH_1):PAGE106_I180@PURE_QUANTA.SCONN288_ADR50017P130CC(CHIPS)':
 'CK_T': CDS_PINID='CK_T';
NET_NAME
'M_E_CPU1_CLK_DP<1>'
 '@S9S_MB_2U_LIB.S9S_MB_2U(SCH_1):M_E_CPU1_CLK_DP'<1>:
 C_SIGNAL='@s9s_mb_2u_lib.s9s_mb_2u(sch_1):m_e_cpu1_clk_dp(1)';
NODE_NAME     U1 EC45
 '@S9S_MB_2U_LIB.S9S_MB_2U(SCH_1):PAGE55_I7@PURE_QUANTA.SOCKET4677_AZIF0045P001C01CS(CHIPS)':
 'DDR4_CLK_DP1': CDS_PINID='DDR4_CLK_DP1';
NODE_NAME     J26 217
 '@S9S_MB_2U_LIB.S9S_MB_2U(SCH_1):PAGE107_I180@PURE_QUANTA.SCONN288_ADR50017P087CC(CHIPS)':
 'CK_T': CDS_PINID='CK_T';
NET_NAME
'M_E_CPU1_SA_CA<0>'
 '@S9S_MB_2U_LIB.S9S_MB_2U(SCH_1):M_E_CPU1_SA_CA'<0>:
 C_SIGNAL='@s9s_mb_2u_lib.s9s_mb_2u(sch_1):m_e_cpu1_sa_ca(0)';
NODE_NAME     U1 EP49
 '@S9S_MB_2U_LIB.S9S_MB_2U(SCH_1):PAGE55_I7@PURE_QUANTA.SOCKET4677_AZIF0045P001C01CS(CHIPS)':
 'DDR4_SA_CA0': CDS_PINID='DDR4_SA_CA0';
NODE_NAME     J25 66
 '@S9S_MB_2U_LIB.S9S_MB_2U(SCH_1):PAGE106_I180@PURE_QUANTA.SCONN288_ADR50017P130CC(CHIPS)':
 'CA0_A': CDS_PINID='CA0_A';
NODE_NAME     J26 66
 '@S9S_MB_2U_LIB.S9S_MB_2U(SCH_1):PAGE107_I180@PURE_QUANTA.SCONN288_ADR50017P087CC(CHIPS)':
 'CA0_A': CDS_PINID='CA0_A';
NET_NAME
'M_E_CPU1_SA_CA<1>'
 '@S9S_MB_2U_LIB.S9S_MB_2U(SCH_1):M_E_CPU1_SA_CA'<1>:
 C_SIGNAL='@s9s_mb_2u_lib.s9s_mb_2u(sch_1):m_e_cpu1_sa_ca(1)';
NODE_NAME     U1 ET49
 '@S9S_MB_2U_LIB.S9S_MB_2U(SCH_1):PAGE55_I7@PURE_QUANTA.SOCKET4677_AZIF0045P001C01CS(CHIPS)':
 'DDR4_SA_CA1': CDS_PINID='DDR4_SA_CA1';
NODE_NAME     J25 211
 '@S9S_MB_2U_LIB.S9S_MB_2U(SCH_1):PAGE106_I180@PURE_QUANTA.SCONN288_ADR50017P130CC(CHIPS)':
 'CA1_A': CDS_PINID='CA1_A';
NODE_NAME     J26 211
 '@S9S_MB_2U_LIB.S9S_MB_2U(SCH_1):PAGE107_I180@PURE_QUANTA.SCONN288_ADR50017P087CC(CHIPS)':
 'CA1_A': CDS_PINID='CA1_A';
NET_NAME
'M_E_CPU1_SA_CA<2>'
 '@S9S_MB_2U_LIB.S9S_MB_2U(SCH_1):M_E_CPU1_SA_CA'<2>:
 C_SIGNAL='@s9s_mb_2u_lib.s9s_mb_2u(sch_1):m_e_cpu1_sa_ca(2)';
NODE_NAME     U1 EK49
 '@S9S_MB_2U_LIB.S9S_MB_2U(SCH_1):PAGE55_I7@PURE_QUANTA.SOCKET4677_AZIF0045P001C01CS(CHIPS)':
 'DDR4_SA_CA2': CDS_PINID='DDR4_SA_CA2';
NODE_NAME     J25 68
 '@S9S_MB_2U_LIB.S9S_MB_2U(SCH_1):PAGE106_I180@PURE_QUANTA.SCONN288_ADR50017P130CC(CHIPS)':
 'CA2_A': CDS_PINID='CA2_A';
NODE_NAME     J26 68
 '@S9S_MB_2U_LIB.S9S_MB_2U(SCH_1):PAGE107_I180@PURE_QUANTA.SCONN288_ADR50017P087CC(CHIPS)':
 'CA2_A': CDS_PINID='CA2_A';
NET_NAME
'M_E_CPU1_SA_CA<3>'
 '@S9S_MB_2U_LIB.S9S_MB_2U(SCH_1):M_E_CPU1_SA_CA'<3>:
 C_SIGNAL='@s9s_mb_2u_lib.s9s_mb_2u(sch_1):m_e_cpu1_sa_ca(3)';
NODE_NAME     U1 EL48
 '@S9S_MB_2U_LIB.S9S_MB_2U(SCH_1):PAGE55_I7@PURE_QUANTA.SOCKET4677_AZIF0045P001C01CS(CHIPS)':
 'DDR4_SA_CA3': CDS_PINID='DDR4_SA_CA3';
NODE_NAME     J25 213
 '@S9S_MB_2U_LIB.S9S_MB_2U(SCH_1):PAGE106_I180@PURE_QUANTA.SCONN288_ADR50017P130CC(CHIPS)':
 'CA3_A': CDS_PINID='CA3_A';
NODE_NAME     J26 213
 '@S9S_MB_2U_LIB.S9S_MB_2U(SCH_1):PAGE107_I180@PURE_QUANTA.SCONN288_ADR50017P087CC(CHIPS)':
 'CA3_A': CDS_PINID='CA3_A';
NET_NAME
'M_E_CPU1_SA_CA<4>'
 '@S9S_MB_2U_LIB.S9S_MB_2U(SCH_1):M_E_CPU1_SA_CA'<4>:
 C_SIGNAL='@s9s_mb_2u_lib.s9s_mb_2u(sch_1):m_e_cpu1_sa_ca(4)';
NODE_NAME     U1 EM47
 '@S9S_MB_2U_LIB.S9S_MB_2U(SCH_1):PAGE55_I7@PURE_QUANTA.SOCKET4677_AZIF0045P001C01CS(CHIPS)':
 'DDR4_SA_CA4': CDS_PINID='DDR4_SA_CA4';
NODE_NAME     J25 70
 '@S9S_MB_2U_LIB.S9S_MB_2U(SCH_1):PAGE106_I180@PURE_QUANTA.SCONN288_ADR50017P130CC(CHIPS)':
 'CA4_A': CDS_PINID='CA4_A';
NODE_NAME     J26 70
 '@S9S_MB_2U_LIB.S9S_MB_2U(SCH_1):PAGE107_I180@PURE_QUANTA.SCONN288_ADR50017P087CC(CHIPS)':
 'CA4_A': CDS_PINID='CA4_A';
NET_NAME
'M_E_CPU1_SA_CA<5>'
 '@S9S_MB_2U_LIB.S9S_MB_2U(SCH_1):M_E_CPU1_SA_CA'<5>:
 C_SIGNAL='@s9s_mb_2u_lib.s9s_mb_2u(sch_1):m_e_cpu1_sa_ca(5)';
NODE_NAME     U1 EP47
 '@S9S_MB_2U_LIB.S9S_MB_2U(SCH_1):PAGE55_I7@PURE_QUANTA.SOCKET4677_AZIF0045P001C01CS(CHIPS)':
 'DDR4_SA_CA5': CDS_PINID='DDR4_SA_CA5';
NODE_NAME     J25 215
 '@S9S_MB_2U_LIB.S9S_MB_2U(SCH_1):PAGE106_I180@PURE_QUANTA.SCONN288_ADR50017P130CC(CHIPS)':
 'CA5_A': CDS_PINID='CA5_A';
NODE_NAME     J26 215
 '@S9S_MB_2U_LIB.S9S_MB_2U(SCH_1):PAGE107_I180@PURE_QUANTA.SCONN288_ADR50017P087CC(CHIPS)':
 'CA5_A': CDS_PINID='CA5_A';
NET_NAME
'M_E_CPU1_SA_CA<6>'
 '@S9S_MB_2U_LIB.S9S_MB_2U(SCH_1):M_E_CPU1_SA_CA'<6>:
 C_SIGNAL='@s9s_mb_2u_lib.s9s_mb_2u(sch_1):m_e_cpu1_sa_ca(6)';
NODE_NAME     U1 ED44
 '@S9S_MB_2U_LIB.S9S_MB_2U(SCH_1):PAGE55_I7@PURE_QUANTA.SOCKET4677_AZIF0045P001C01CS(CHIPS)':
 'DDR4_SA_CA6': CDS_PINID='DDR4_SA_CA6';
NODE_NAME     J25 72
 '@S9S_MB_2U_LIB.S9S_MB_2U(SCH_1):PAGE106_I180@PURE_QUANTA.SCONN288_ADR50017P130CC(CHIPS)':
 'CA6_A': CDS_PINID='CA6_A';
NODE_NAME     J26 72
 '@S9S_MB_2U_LIB.S9S_MB_2U(SCH_1):PAGE107_I180@PURE_QUANTA.SCONN288_ADR50017P087CC(CHIPS)':
 'CA6_A': CDS_PINID='CA6_A';
NET_NAME
'M_E_CPU1_SA_CB<0>'
 '@S9S_MB_2U_LIB.S9S_MB_2U(SCH_1):M_E_CPU1_SA_CB'<0>:
 C_SIGNAL='@s9s_mb_2u_lib.s9s_mb_2u(sch_1):m_e_cpu1_sa_cb(0)';
NODE_NAME     U1 EM57
 '@S9S_MB_2U_LIB.S9S_MB_2U(SCH_1):PAGE55_I7@PURE_QUANTA.SOCKET4677_AZIF0045P001C01CS(CHIPS)':
 'DDR4_SA_ECC0': CDS_PINID='DDR4_SA_ECC0';
NODE_NAME     J25 51
 '@S9S_MB_2U_LIB.S9S_MB_2U(SCH_1):PAGE106_I180@PURE_QUANTA.SCONN288_ADR50017P130CC(CHIPS)':
 'CB0_A': CDS_PINID='CB0_A';
NODE_NAME     J26 51
 '@S9S_MB_2U_LIB.S9S_MB_2U(SCH_1):PAGE107_I180@PURE_QUANTA.SCONN288_ADR50017P087CC(CHIPS)':
 'CB0_A': CDS_PINID='CB0_A';
NET_NAME
'M_E_CPU1_SA_CB<1>'
 '@S9S_MB_2U_LIB.S9S_MB_2U(SCH_1):M_E_CPU1_SA_CB'<1>:
 C_SIGNAL='@s9s_mb_2u_lib.s9s_mb_2u(sch_1):m_e_cpu1_sa_cb(1)';
NODE_NAME     U1 EL56
 '@S9S_MB_2U_LIB.S9S_MB_2U(SCH_1):PAGE55_I7@PURE_QUANTA.SOCKET4677_AZIF0045P001C01CS(CHIPS)':
 'DDR4_SA_ECC1': CDS_PINID='DDR4_SA_ECC1';
NODE_NAME     J25 53
 '@S9S_MB_2U_LIB.S9S_MB_2U(SCH_1):PAGE106_I180@PURE_QUANTA.SCONN288_ADR50017P130CC(CHIPS)':
 'CB1_A': CDS_PINID='CB1_A';
NODE_NAME     J26 53
 '@S9S_MB_2U_LIB.S9S_MB_2U(SCH_1):PAGE107_I180@PURE_QUANTA.SCONN288_ADR50017P087CC(CHIPS)':
 'CB1_A': CDS_PINID='CB1_A';
NET_NAME
'M_E_CPU1_SA_CB<2>'
 '@S9S_MB_2U_LIB.S9S_MB_2U(SCH_1):M_E_CPU1_SA_CB'<2>:
 C_SIGNAL='@s9s_mb_2u_lib.s9s_mb_2u(sch_1):m_e_cpu1_sa_cb(2)';
NODE_NAME     U1 EP57
 '@S9S_MB_2U_LIB.S9S_MB_2U(SCH_1):PAGE55_I7@PURE_QUANTA.SOCKET4677_AZIF0045P001C01CS(CHIPS)':
 'DDR4_SA_ECC2': CDS_PINID='DDR4_SA_ECC2';
NODE_NAME     J25 196
 '@S9S_MB_2U_LIB.S9S_MB_2U(SCH_1):PAGE106_I180@PURE_QUANTA.SCONN288_ADR50017P130CC(CHIPS)':
 'CB2_A': CDS_PINID='CB2_A';
NODE_NAME     J26 196
 '@S9S_MB_2U_LIB.S9S_MB_2U(SCH_1):PAGE107_I180@PURE_QUANTA.SCONN288_ADR50017P087CC(CHIPS)':
 'CB2_A': CDS_PINID='CB2_A';
NET_NAME
'M_E_CPU1_SA_CB<3>'
 '@S9S_MB_2U_LIB.S9S_MB_2U(SCH_1):M_E_CPU1_SA_CB'<3>:
 C_SIGNAL='@s9s_mb_2u_lib.s9s_mb_2u(sch_1):m_e_cpu1_sa_cb(3)';
NODE_NAME     U1 ER56
 '@S9S_MB_2U_LIB.S9S_MB_2U(SCH_1):PAGE55_I7@PURE_QUANTA.SOCKET4677_AZIF0045P001C01CS(CHIPS)':
 'DDR4_SA_ECC3': CDS_PINID='DDR4_SA_ECC3';
NODE_NAME     J25 198
 '@S9S_MB_2U_LIB.S9S_MB_2U(SCH_1):PAGE106_I180@PURE_QUANTA.SCONN288_ADR50017P130CC(CHIPS)':
 'CB3_A': CDS_PINID='CB3_A';
NODE_NAME     J26 198
 '@S9S_MB_2U_LIB.S9S_MB_2U(SCH_1):PAGE107_I180@PURE_QUANTA.SCONN288_ADR50017P087CC(CHIPS)':
 'CB3_A': CDS_PINID='CB3_A';
NET_NAME
'M_E_CPU1_SA_CB<4>'
 '@S9S_MB_2U_LIB.S9S_MB_2U(SCH_1):M_E_CPU1_SA_CB'<4>:
 C_SIGNAL='@s9s_mb_2u_lib.s9s_mb_2u(sch_1):m_e_cpu1_sa_cb(4)';
NODE_NAME     U1 EL54
 '@S9S_MB_2U_LIB.S9S_MB_2U(SCH_1):PAGE55_I7@PURE_QUANTA.SOCKET4677_AZIF0045P001C01CS(CHIPS)':
 'DDR4_SA_ECC4': CDS_PINID='DDR4_SA_ECC4';
NODE_NAME     J25 58
 '@S9S_MB_2U_LIB.S9S_MB_2U(SCH_1):PAGE106_I180@PURE_QUANTA.SCONN288_ADR50017P130CC(CHIPS)':
 'CB4_A': CDS_PINID='CB4_A';
NODE_NAME     J26 58
 '@S9S_MB_2U_LIB.S9S_MB_2U(SCH_1):PAGE107_I180@PURE_QUANTA.SCONN288_ADR50017P087CC(CHIPS)':
 'CB4_A': CDS_PINID='CB4_A';
NET_NAME
'M_E_CPU1_SA_CB<5>'
 '@S9S_MB_2U_LIB.S9S_MB_2U(SCH_1):M_E_CPU1_SA_CB'<5>:
 C_SIGNAL='@s9s_mb_2u_lib.s9s_mb_2u(sch_1):m_e_cpu1_sa_cb(5)';
NODE_NAME     U1 EM53
 '@S9S_MB_2U_LIB.S9S_MB_2U(SCH_1):PAGE55_I7@PURE_QUANTA.SOCKET4677_AZIF0045P001C01CS(CHIPS)':
 'DDR4_SA_ECC5': CDS_PINID='DDR4_SA_ECC5';
NODE_NAME     J25 60
 '@S9S_MB_2U_LIB.S9S_MB_2U(SCH_1):PAGE106_I180@PURE_QUANTA.SCONN288_ADR50017P130CC(CHIPS)':
 'CB5_A': CDS_PINID='CB5_A';
NODE_NAME     J26 60
 '@S9S_MB_2U_LIB.S9S_MB_2U(SCH_1):PAGE107_I180@PURE_QUANTA.SCONN288_ADR50017P087CC(CHIPS)':
 'CB5_A': CDS_PINID='CB5_A';
NET_NAME
'M_E_CPU1_SA_CB<6>'
 '@S9S_MB_2U_LIB.S9S_MB_2U(SCH_1):M_E_CPU1_SA_CB'<6>:
 C_SIGNAL='@s9s_mb_2u_lib.s9s_mb_2u(sch_1):m_e_cpu1_sa_cb(6)';
NODE_NAME     U1 ER54
 '@S9S_MB_2U_LIB.S9S_MB_2U(SCH_1):PAGE55_I7@PURE_QUANTA.SOCKET4677_AZIF0045P001C01CS(CHIPS)':
 'DDR4_SA_ECC6': CDS_PINID='DDR4_SA_ECC6';
NODE_NAME     J25 203
 '@S9S_MB_2U_LIB.S9S_MB_2U(SCH_1):PAGE106_I180@PURE_QUANTA.SCONN288_ADR50017P130CC(CHIPS)':
 'CB6_A': CDS_PINID='CB6_A';
NODE_NAME     J26 203
 '@S9S_MB_2U_LIB.S9S_MB_2U(SCH_1):PAGE107_I180@PURE_QUANTA.SCONN288_ADR50017P087CC(CHIPS)':
 'CB6_A': CDS_PINID='CB6_A';
NET_NAME
'M_E_CPU1_SA_CB<7>'
 '@S9S_MB_2U_LIB.S9S_MB_2U(SCH_1):M_E_CPU1_SA_CB'<7>:
 C_SIGNAL='@s9s_mb_2u_lib.s9s_mb_2u(sch_1):m_e_cpu1_sa_cb(7)';
NODE_NAME     U1 EP53
 '@S9S_MB_2U_LIB.S9S_MB_2U(SCH_1):PAGE55_I7@PURE_QUANTA.SOCKET4677_AZIF0045P001C01CS(CHIPS)':
 'DDR4_SA_ECC7': CDS_PINID='DDR4_SA_ECC7';
NODE_NAME     J25 205
 '@S9S_MB_2U_LIB.S9S_MB_2U(SCH_1):PAGE106_I180@PURE_QUANTA.SCONN288_ADR50017P130CC(CHIPS)':
 'CB7_A': CDS_PINID='CB7_A';
NODE_NAME     J26 205
 '@S9S_MB_2U_LIB.S9S_MB_2U(SCH_1):PAGE107_I180@PURE_QUANTA.SCONN288_ADR50017P087CC(CHIPS)':
 'CB7_A': CDS_PINID='CB7_A';
NET_NAME
'M_E_CPU1_SA_CS_N<0>'
 '@S9S_MB_2U_LIB.S9S_MB_2U(SCH_1):M_E_CPU1_SA_CS_N'<0>:
 C_SIGNAL='@s9s_mb_2u_lib.s9s_mb_2u(sch_1):m_e_cpu1_sa_cs_n(0)';
NODE_NAME     U1 EP51
 '@S9S_MB_2U_LIB.S9S_MB_2U(SCH_1):PAGE55_I7@PURE_QUANTA.SOCKET4677_AZIF0045P001C01CS(CHIPS)':
 'DDR4_SA_CS_N0': CDS_PINID='DDR4_SA_CS_N0';
NODE_NAME     J25 64
 '@S9S_MB_2U_LIB.S9S_MB_2U(SCH_1):PAGE106_I180@PURE_QUANTA.SCONN288_ADR50017P130CC(CHIPS)':
 'CS0_A_N': CDS_PINID='CS0_A_N';
NET_NAME
'M_E_CPU1_SA_CS_N<1>'
 '@S9S_MB_2U_LIB.S9S_MB_2U(SCH_1):M_E_CPU1_SA_CS_N'<1>:
 C_SIGNAL='@s9s_mb_2u_lib.s9s_mb_2u(sch_1):m_e_cpu1_sa_cs_n(1)';
NODE_NAME     U1 ET51
 '@S9S_MB_2U_LIB.S9S_MB_2U(SCH_1):PAGE55_I7@PURE_QUANTA.SOCKET4677_AZIF0045P001C01CS(CHIPS)':
 'DDR4_SA_CS_N1': CDS_PINID='DDR4_SA_CS_N1';
NODE_NAME     J25 209
 '@S9S_MB_2U_LIB.S9S_MB_2U(SCH_1):PAGE106_I180@PURE_QUANTA.SCONN288_ADR50017P130CC(CHIPS)':
 'CS1_A_N': CDS_PINID='CS1_A_N';
NET_NAME
'M_E_CPU1_SA_CS_N<2>'
 '@S9S_MB_2U_LIB.S9S_MB_2U(SCH_1):M_E_CPU1_SA_CS_N'<2>:
 C_SIGNAL='@s9s_mb_2u_lib.s9s_mb_2u(sch_1):m_e_cpu1_sa_cs_n(2)';
NODE_NAME     U1 EM51
 '@S9S_MB_2U_LIB.S9S_MB_2U(SCH_1):PAGE55_I7@PURE_QUANTA.SOCKET4677_AZIF0045P001C01CS(CHIPS)':
 'DDR4_SA_CS_N2': CDS_PINID='DDR4_SA_CS_N2';
NODE_NAME     J26 64
 '@S9S_MB_2U_LIB.S9S_MB_2U(SCH_1):PAGE107_I180@PURE_QUANTA.SCONN288_ADR50017P087CC(CHIPS)':
 'CS0_A_N': CDS_PINID='CS0_A_N';
NET_NAME
'M_E_CPU1_SA_CS_N<3>'
 '@S9S_MB_2U_LIB.S9S_MB_2U(SCH_1):M_E_CPU1_SA_CS_N'<3>:
 C_SIGNAL='@s9s_mb_2u_lib.s9s_mb_2u(sch_1):m_e_cpu1_sa_cs_n(3)';
NODE_NAME     U1 EL50
 '@S9S_MB_2U_LIB.S9S_MB_2U(SCH_1):PAGE55_I7@PURE_QUANTA.SOCKET4677_AZIF0045P001C01CS(CHIPS)':
 'DDR4_SA_CS_N3': CDS_PINID='DDR4_SA_CS_N3';
NODE_NAME     J26 209
 '@S9S_MB_2U_LIB.S9S_MB_2U(SCH_1):PAGE107_I180@PURE_QUANTA.SCONN288_ADR50017P087CC(CHIPS)':
 'CS1_A_N': CDS_PINID='CS1_A_N';
NET_NAME
'M_E_CPU1_SA_DQ<0>'
 '@S9S_MB_2U_LIB.S9S_MB_2U(SCH_1):M_E_CPU1_SA_DQ'<0>:
 C_SIGNAL='@s9s_mb_2u_lib.s9s_mb_2u(sch_1):m_e_cpu1_sa_dq(0)';
NODE_NAME     U1 EL78
 '@S9S_MB_2U_LIB.S9S_MB_2U(SCH_1):PAGE55_I7@PURE_QUANTA.SOCKET4677_AZIF0045P001C01CS(CHIPS)':
 'DDR4_SA_DQ0': CDS_PINID='DDR4_SA_DQ0';
NODE_NAME     J25 7
 '@S9S_MB_2U_LIB.S9S_MB_2U(SCH_1):PAGE106_I180@PURE_QUANTA.SCONN288_ADR50017P130CC(CHIPS)':
 'DQ0_A': CDS_PINID='DQ0_A';
NODE_NAME     J26 7
 '@S9S_MB_2U_LIB.S9S_MB_2U(SCH_1):PAGE107_I180@PURE_QUANTA.SCONN288_ADR50017P087CC(CHIPS)':
 'DQ0_A': CDS_PINID='DQ0_A';
NET_NAME
'M_E_CPU1_SA_DQ<10>'
 '@S9S_MB_2U_LIB.S9S_MB_2U(SCH_1):M_E_CPU1_SA_DQ'<10>:
 C_SIGNAL='@s9s_mb_2u_lib.s9s_mb_2u(sch_1):m_e_cpu1_sa_dq(10)';
NODE_NAME     U1 EG72
 '@S9S_MB_2U_LIB.S9S_MB_2U(SCH_1):PAGE55_I7@PURE_QUANTA.SOCKET4677_AZIF0045P001C01CS(CHIPS)':
 'DDR4_SA_DQ10': CDS_PINID='DDR4_SA_DQ10';
NODE_NAME     J25 163
 '@S9S_MB_2U_LIB.S9S_MB_2U(SCH_1):PAGE106_I180@PURE_QUANTA.SCONN288_ADR50017P130CC(CHIPS)':
 'DQ10_A': CDS_PINID='DQ10_A';
NODE_NAME     J26 163
 '@S9S_MB_2U_LIB.S9S_MB_2U(SCH_1):PAGE107_I180@PURE_QUANTA.SCONN288_ADR50017P087CC(CHIPS)':
 'DQ10_A': CDS_PINID='DQ10_A';
NET_NAME
'M_E_CPU1_SA_DQ<11>'
 '@S9S_MB_2U_LIB.S9S_MB_2U(SCH_1):M_E_CPU1_SA_DQ'<11>:
 C_SIGNAL='@s9s_mb_2u_lib.s9s_mb_2u(sch_1):m_e_cpu1_sa_dq(11)';
NODE_NAME     U1 EH71
 '@S9S_MB_2U_LIB.S9S_MB_2U(SCH_1):PAGE55_I7@PURE_QUANTA.SOCKET4677_AZIF0045P001C01CS(CHIPS)':
 'DDR4_SA_DQ11': CDS_PINID='DDR4_SA_DQ11';
NODE_NAME     J25 165
 '@S9S_MB_2U_LIB.S9S_MB_2U(SCH_1):PAGE106_I180@PURE_QUANTA.SCONN288_ADR50017P130CC(CHIPS)':
 'DQ11_A': CDS_PINID='DQ11_A';
NODE_NAME     J26 165
 '@S9S_MB_2U_LIB.S9S_MB_2U(SCH_1):PAGE107_I180@PURE_QUANTA.SCONN288_ADR50017P087CC(CHIPS)':
 'DQ11_A': CDS_PINID='DQ11_A';
NET_NAME
'M_E_CPU1_SA_DQ<12>'
 '@S9S_MB_2U_LIB.S9S_MB_2U(SCH_1):M_E_CPU1_SA_DQ'<12>:
 C_SIGNAL='@s9s_mb_2u_lib.s9s_mb_2u(sch_1):m_e_cpu1_sa_dq(12)';
NODE_NAME     U1 ED69
 '@S9S_MB_2U_LIB.S9S_MB_2U(SCH_1):PAGE55_I7@PURE_QUANTA.SOCKET4677_AZIF0045P001C01CS(CHIPS)':
 'DDR4_SA_DQ12': CDS_PINID='DDR4_SA_DQ12';
NODE_NAME     J25 25
 '@S9S_MB_2U_LIB.S9S_MB_2U(SCH_1):PAGE106_I180@PURE_QUANTA.SCONN288_ADR50017P130CC(CHIPS)':
 'DQ12_A': CDS_PINID='DQ12_A';
NODE_NAME     J26 25
 '@S9S_MB_2U_LIB.S9S_MB_2U(SCH_1):PAGE107_I180@PURE_QUANTA.SCONN288_ADR50017P087CC(CHIPS)':
 'DQ12_A': CDS_PINID='DQ12_A';
NET_NAME
'M_E_CPU1_SA_DQ<13>'
 '@S9S_MB_2U_LIB.S9S_MB_2U(SCH_1):M_E_CPU1_SA_DQ'<13>:
 C_SIGNAL='@s9s_mb_2u_lib.s9s_mb_2u(sch_1):m_e_cpu1_sa_dq(13)';
NODE_NAME     U1 EE68
 '@S9S_MB_2U_LIB.S9S_MB_2U(SCH_1):PAGE55_I7@PURE_QUANTA.SOCKET4677_AZIF0045P001C01CS(CHIPS)':
 'DDR4_SA_DQ13': CDS_PINID='DDR4_SA_DQ13';
NODE_NAME     J25 27
 '@S9S_MB_2U_LIB.S9S_MB_2U(SCH_1):PAGE106_I180@PURE_QUANTA.SCONN288_ADR50017P130CC(CHIPS)':
 'DQ13_A': CDS_PINID='DQ13_A';
NODE_NAME     J26 27
 '@S9S_MB_2U_LIB.S9S_MB_2U(SCH_1):PAGE107_I180@PURE_QUANTA.SCONN288_ADR50017P087CC(CHIPS)':
 'DQ13_A': CDS_PINID='DQ13_A';
NET_NAME
'M_E_CPU1_SA_DQ<14>'
 '@S9S_MB_2U_LIB.S9S_MB_2U(SCH_1):M_E_CPU1_SA_DQ'<14>:
 C_SIGNAL='@s9s_mb_2u_lib.s9s_mb_2u(sch_1):m_e_cpu1_sa_dq(14)';
NODE_NAME     U1 EH69
 '@S9S_MB_2U_LIB.S9S_MB_2U(SCH_1):PAGE55_I7@PURE_QUANTA.SOCKET4677_AZIF0045P001C01CS(CHIPS)':
 'DDR4_SA_DQ14': CDS_PINID='DDR4_SA_DQ14';
NODE_NAME     J25 170
 '@S9S_MB_2U_LIB.S9S_MB_2U(SCH_1):PAGE106_I180@PURE_QUANTA.SCONN288_ADR50017P130CC(CHIPS)':
 'DQ14_A': CDS_PINID='DQ14_A';
NODE_NAME     J26 170
 '@S9S_MB_2U_LIB.S9S_MB_2U(SCH_1):PAGE107_I180@PURE_QUANTA.SCONN288_ADR50017P087CC(CHIPS)':
 'DQ14_A': CDS_PINID='DQ14_A';
NET_NAME
'M_E_CPU1_SA_DQ<15>'
 '@S9S_MB_2U_LIB.S9S_MB_2U(SCH_1):M_E_CPU1_SA_DQ'<15>:
 C_SIGNAL='@s9s_mb_2u_lib.s9s_mb_2u(sch_1):m_e_cpu1_sa_dq(15)';
NODE_NAME     U1 EG68
 '@S9S_MB_2U_LIB.S9S_MB_2U(SCH_1):PAGE55_I7@PURE_QUANTA.SOCKET4677_AZIF0045P001C01CS(CHIPS)':
 'DDR4_SA_DQ15': CDS_PINID='DDR4_SA_DQ15';
NODE_NAME     J25 172
 '@S9S_MB_2U_LIB.S9S_MB_2U(SCH_1):PAGE106_I180@PURE_QUANTA.SCONN288_ADR50017P130CC(CHIPS)':
 'DQ15_A': CDS_PINID='DQ15_A';
NODE_NAME     J26 172
 '@S9S_MB_2U_LIB.S9S_MB_2U(SCH_1):PAGE107_I180@PURE_QUANTA.SCONN288_ADR50017P087CC(CHIPS)':
 'DQ15_A': CDS_PINID='DQ15_A';
NET_NAME
'M_E_CPU1_SA_DQ<16>'
 '@S9S_MB_2U_LIB.S9S_MB_2U(SCH_1):M_E_CPU1_SA_DQ'<16>:
 C_SIGNAL='@s9s_mb_2u_lib.s9s_mb_2u(sch_1):m_e_cpu1_sa_dq(16)';
NODE_NAME     U1 EM71
 '@S9S_MB_2U_LIB.S9S_MB_2U(SCH_1):PAGE55_I7@PURE_QUANTA.SOCKET4677_AZIF0045P001C01CS(CHIPS)':
 'DDR4_SA_DQ16': CDS_PINID='DDR4_SA_DQ16';
NODE_NAME     J25 29
 '@S9S_MB_2U_LIB.S9S_MB_2U(SCH_1):PAGE106_I180@PURE_QUANTA.SCONN288_ADR50017P130CC(CHIPS)':
 'DQ16_A': CDS_PINID='DQ16_A';
NODE_NAME     J26 29
 '@S9S_MB_2U_LIB.S9S_MB_2U(SCH_1):PAGE107_I180@PURE_QUANTA.SCONN288_ADR50017P087CC(CHIPS)':
 'DQ16_A': CDS_PINID='DQ16_A';
NET_NAME
'M_E_CPU1_SA_DQ<17>'
 '@S9S_MB_2U_LIB.S9S_MB_2U(SCH_1):M_E_CPU1_SA_DQ'<17>:
 C_SIGNAL='@s9s_mb_2u_lib.s9s_mb_2u(sch_1):m_e_cpu1_sa_dq(17)';
NODE_NAME     U1 EM69
 '@S9S_MB_2U_LIB.S9S_MB_2U(SCH_1):PAGE55_I7@PURE_QUANTA.SOCKET4677_AZIF0045P001C01CS(CHIPS)':
 'DDR4_SA_DQ17': CDS_PINID='DDR4_SA_DQ17';
NODE_NAME     J25 31
 '@S9S_MB_2U_LIB.S9S_MB_2U(SCH_1):PAGE106_I180@PURE_QUANTA.SCONN288_ADR50017P130CC(CHIPS)':
 'DQ17_A': CDS_PINID='DQ17_A';
NODE_NAME     J26 31
 '@S9S_MB_2U_LIB.S9S_MB_2U(SCH_1):PAGE107_I180@PURE_QUANTA.SCONN288_ADR50017P087CC(CHIPS)':
 'DQ17_A': CDS_PINID='DQ17_A';
NET_NAME
'M_E_CPU1_SA_DQ<18>'
 '@S9S_MB_2U_LIB.S9S_MB_2U(SCH_1):M_E_CPU1_SA_DQ'<18>:
 C_SIGNAL='@s9s_mb_2u_lib.s9s_mb_2u(sch_1):m_e_cpu1_sa_dq(18)';
NODE_NAME     U1 EN70
 '@S9S_MB_2U_LIB.S9S_MB_2U(SCH_1):PAGE55_I7@PURE_QUANTA.SOCKET4677_AZIF0045P001C01CS(CHIPS)':
 'DDR4_SA_DQ18': CDS_PINID='DDR4_SA_DQ18';
NODE_NAME     J25 174
 '@S9S_MB_2U_LIB.S9S_MB_2U(SCH_1):PAGE106_I180@PURE_QUANTA.SCONN288_ADR50017P130CC(CHIPS)':
 'DQ18_A': CDS_PINID='DQ18_A';
NODE_NAME     J26 174
 '@S9S_MB_2U_LIB.S9S_MB_2U(SCH_1):PAGE107_I180@PURE_QUANTA.SCONN288_ADR50017P087CC(CHIPS)':
 'DQ18_A': CDS_PINID='DQ18_A';
NET_NAME
'M_E_CPU1_SA_DQ<19>'
 '@S9S_MB_2U_LIB.S9S_MB_2U(SCH_1):M_E_CPU1_SA_DQ'<19>:
 C_SIGNAL='@s9s_mb_2u_lib.s9s_mb_2u(sch_1):m_e_cpu1_sa_dq(19)';
NODE_NAME     U1 ER68
 '@S9S_MB_2U_LIB.S9S_MB_2U(SCH_1):PAGE55_I7@PURE_QUANTA.SOCKET4677_AZIF0045P001C01CS(CHIPS)':
 'DDR4_SA_DQ19': CDS_PINID='DDR4_SA_DQ19';
NODE_NAME     J25 176
 '@S9S_MB_2U_LIB.S9S_MB_2U(SCH_1):PAGE106_I180@PURE_QUANTA.SCONN288_ADR50017P130CC(CHIPS)':
 'DQ19_A': CDS_PINID='DQ19_A';
NODE_NAME     J26 176
 '@S9S_MB_2U_LIB.S9S_MB_2U(SCH_1):PAGE107_I180@PURE_QUANTA.SCONN288_ADR50017P087CC(CHIPS)':
 'DQ19_A': CDS_PINID='DQ19_A';
NET_NAME
'M_E_CPU1_SA_DQ<1>'
 '@S9S_MB_2U_LIB.S9S_MB_2U(SCH_1):M_E_CPU1_SA_DQ'<1>:
 C_SIGNAL='@s9s_mb_2u_lib.s9s_mb_2u(sch_1):m_e_cpu1_sa_dq(1)';
NODE_NAME     U1 EM77
 '@S9S_MB_2U_LIB.S9S_MB_2U(SCH_1):PAGE55_I7@PURE_QUANTA.SOCKET4677_AZIF0045P001C01CS(CHIPS)':
 'DDR4_SA_DQ1': CDS_PINID='DDR4_SA_DQ1';
NODE_NAME     J25 9
 '@S9S_MB_2U_LIB.S9S_MB_2U(SCH_1):PAGE106_I180@PURE_QUANTA.SCONN288_ADR50017P130CC(CHIPS)':
 'DQ1_A': CDS_PINID='DQ1_A';
NODE_NAME     J26 9
 '@S9S_MB_2U_LIB.S9S_MB_2U(SCH_1):PAGE107_I180@PURE_QUANTA.SCONN288_ADR50017P087CC(CHIPS)':
 'DQ1_A': CDS_PINID='DQ1_A';
NET_NAME
'M_E_CPU1_SA_DQ<20>'
 '@S9S_MB_2U_LIB.S9S_MB_2U(SCH_1):M_E_CPU1_SA_DQ'<20>:
 C_SIGNAL='@s9s_mb_2u_lib.s9s_mb_2u(sch_1):m_e_cpu1_sa_dq(20)';
NODE_NAME     U1 ER66
 '@S9S_MB_2U_LIB.S9S_MB_2U(SCH_1):PAGE55_I7@PURE_QUANTA.SOCKET4677_AZIF0045P001C01CS(CHIPS)':
 'DDR4_SA_DQ20': CDS_PINID='DDR4_SA_DQ20';
NODE_NAME     J25 36
 '@S9S_MB_2U_LIB.S9S_MB_2U(SCH_1):PAGE106_I180@PURE_QUANTA.SCONN288_ADR50017P130CC(CHIPS)':
 'DQ20_A': CDS_PINID='DQ20_A';
NODE_NAME     J26 36
 '@S9S_MB_2U_LIB.S9S_MB_2U(SCH_1):PAGE107_I180@PURE_QUANTA.SCONN288_ADR50017P087CC(CHIPS)':
 'DQ20_A': CDS_PINID='DQ20_A';
NET_NAME
'M_E_CPU1_SA_DQ<21>'
 '@S9S_MB_2U_LIB.S9S_MB_2U(SCH_1):M_E_CPU1_SA_DQ'<21>:
 C_SIGNAL='@s9s_mb_2u_lib.s9s_mb_2u(sch_1):m_e_cpu1_sa_dq(21)';
NODE_NAME     U1 EM65
 '@S9S_MB_2U_LIB.S9S_MB_2U(SCH_1):PAGE55_I7@PURE_QUANTA.SOCKET4677_AZIF0045P001C01CS(CHIPS)':
 'DDR4_SA_DQ21': CDS_PINID='DDR4_SA_DQ21';
NODE_NAME     J25 38
 '@S9S_MB_2U_LIB.S9S_MB_2U(SCH_1):PAGE106_I180@PURE_QUANTA.SCONN288_ADR50017P130CC(CHIPS)':
 'DQ21_A': CDS_PINID='DQ21_A';
NODE_NAME     J26 38
 '@S9S_MB_2U_LIB.S9S_MB_2U(SCH_1):PAGE107_I180@PURE_QUANTA.SCONN288_ADR50017P087CC(CHIPS)':
 'DQ21_A': CDS_PINID='DQ21_A';
NET_NAME
'M_E_CPU1_SA_DQ<22>'
 '@S9S_MB_2U_LIB.S9S_MB_2U(SCH_1):M_E_CPU1_SA_DQ'<22>:
 C_SIGNAL='@s9s_mb_2u_lib.s9s_mb_2u(sch_1):m_e_cpu1_sa_dq(22)';
NODE_NAME     U1 EL66
 '@S9S_MB_2U_LIB.S9S_MB_2U(SCH_1):PAGE55_I7@PURE_QUANTA.SOCKET4677_AZIF0045P001C01CS(CHIPS)':
 'DDR4_SA_DQ22': CDS_PINID='DDR4_SA_DQ22';
NODE_NAME     J25 181
 '@S9S_MB_2U_LIB.S9S_MB_2U(SCH_1):PAGE106_I180@PURE_QUANTA.SCONN288_ADR50017P130CC(CHIPS)':
 'DQ22_A': CDS_PINID='DQ22_A';
NODE_NAME     J26 181
 '@S9S_MB_2U_LIB.S9S_MB_2U(SCH_1):PAGE107_I180@PURE_QUANTA.SCONN288_ADR50017P087CC(CHIPS)':
 'DQ22_A': CDS_PINID='DQ22_A';
NET_NAME
'M_E_CPU1_SA_DQ<23>'
 '@S9S_MB_2U_LIB.S9S_MB_2U(SCH_1):M_E_CPU1_SA_DQ'<23>:
 C_SIGNAL='@s9s_mb_2u_lib.s9s_mb_2u(sch_1):m_e_cpu1_sa_dq(23)';
NODE_NAME     U1 EP65
 '@S9S_MB_2U_LIB.S9S_MB_2U(SCH_1):PAGE55_I7@PURE_QUANTA.SOCKET4677_AZIF0045P001C01CS(CHIPS)':
 'DDR4_SA_DQ23': CDS_PINID='DDR4_SA_DQ23';
NODE_NAME     J25 183
 '@S9S_MB_2U_LIB.S9S_MB_2U(SCH_1):PAGE106_I180@PURE_QUANTA.SCONN288_ADR50017P130CC(CHIPS)':
 'DQ23_A': CDS_PINID='DQ23_A';
NODE_NAME     J26 183
 '@S9S_MB_2U_LIB.S9S_MB_2U(SCH_1):PAGE107_I180@PURE_QUANTA.SCONN288_ADR50017P087CC(CHIPS)':
 'DQ23_A': CDS_PINID='DQ23_A';
NET_NAME
'M_E_CPU1_SA_DQ<24>'
 '@S9S_MB_2U_LIB.S9S_MB_2U(SCH_1):M_E_CPU1_SA_DQ'<24>:
 C_SIGNAL='@s9s_mb_2u_lib.s9s_mb_2u(sch_1):m_e_cpu1_sa_dq(24)';
NODE_NAME     U1 EM63
 '@S9S_MB_2U_LIB.S9S_MB_2U(SCH_1):PAGE55_I7@PURE_QUANTA.SOCKET4677_AZIF0045P001C01CS(CHIPS)':
 'DDR4_SA_DQ24': CDS_PINID='DDR4_SA_DQ24';
NODE_NAME     J25 40
 '@S9S_MB_2U_LIB.S9S_MB_2U(SCH_1):PAGE106_I180@PURE_QUANTA.SCONN288_ADR50017P130CC(CHIPS)':
 'DQ24_A': CDS_PINID='DQ24_A';
NODE_NAME     J26 40
 '@S9S_MB_2U_LIB.S9S_MB_2U(SCH_1):PAGE107_I180@PURE_QUANTA.SCONN288_ADR50017P087CC(CHIPS)':
 'DQ24_A': CDS_PINID='DQ24_A';
NET_NAME
'M_E_CPU1_SA_DQ<25>'
 '@S9S_MB_2U_LIB.S9S_MB_2U(SCH_1):M_E_CPU1_SA_DQ'<25>:
 C_SIGNAL='@s9s_mb_2u_lib.s9s_mb_2u(sch_1):m_e_cpu1_sa_dq(25)';
NODE_NAME     U1 EL62
 '@S9S_MB_2U_LIB.S9S_MB_2U(SCH_1):PAGE55_I7@PURE_QUANTA.SOCKET4677_AZIF0045P001C01CS(CHIPS)':
 'DDR4_SA_DQ25': CDS_PINID='DDR4_SA_DQ25';
NODE_NAME     J25 42
 '@S9S_MB_2U_LIB.S9S_MB_2U(SCH_1):PAGE106_I180@PURE_QUANTA.SCONN288_ADR50017P130CC(CHIPS)':
 'DQ25_A': CDS_PINID='DQ25_A';
NODE_NAME     J26 42
 '@S9S_MB_2U_LIB.S9S_MB_2U(SCH_1):PAGE107_I180@PURE_QUANTA.SCONN288_ADR50017P087CC(CHIPS)':
 'DQ25_A': CDS_PINID='DQ25_A';
NET_NAME
'M_E_CPU1_SA_DQ<26>'
 '@S9S_MB_2U_LIB.S9S_MB_2U(SCH_1):M_E_CPU1_SA_DQ'<26>:
 C_SIGNAL='@s9s_mb_2u_lib.s9s_mb_2u(sch_1):m_e_cpu1_sa_dq(26)';
NODE_NAME     U1 EP63
 '@S9S_MB_2U_LIB.S9S_MB_2U(SCH_1):PAGE55_I7@PURE_QUANTA.SOCKET4677_AZIF0045P001C01CS(CHIPS)':
 'DDR4_SA_DQ26': CDS_PINID='DDR4_SA_DQ26';
NODE_NAME     J25 185
 '@S9S_MB_2U_LIB.S9S_MB_2U(SCH_1):PAGE106_I180@PURE_QUANTA.SCONN288_ADR50017P130CC(CHIPS)':
 'DQ26_A': CDS_PINID='DQ26_A';
NODE_NAME     J26 185
 '@S9S_MB_2U_LIB.S9S_MB_2U(SCH_1):PAGE107_I180@PURE_QUANTA.SCONN288_ADR50017P087CC(CHIPS)':
 'DQ26_A': CDS_PINID='DQ26_A';
NET_NAME
'M_E_CPU1_SA_DQ<27>'
 '@S9S_MB_2U_LIB.S9S_MB_2U(SCH_1):M_E_CPU1_SA_DQ'<27>:
 C_SIGNAL='@s9s_mb_2u_lib.s9s_mb_2u(sch_1):m_e_cpu1_sa_dq(27)';
NODE_NAME     U1 ER62
 '@S9S_MB_2U_LIB.S9S_MB_2U(SCH_1):PAGE55_I7@PURE_QUANTA.SOCKET4677_AZIF0045P001C01CS(CHIPS)':
 'DDR4_SA_DQ27': CDS_PINID='DDR4_SA_DQ27';
NODE_NAME     J25 187
 '@S9S_MB_2U_LIB.S9S_MB_2U(SCH_1):PAGE106_I180@PURE_QUANTA.SCONN288_ADR50017P130CC(CHIPS)':
 'DQ27_A': CDS_PINID='DQ27_A';
NODE_NAME     J26 187
 '@S9S_MB_2U_LIB.S9S_MB_2U(SCH_1):PAGE107_I180@PURE_QUANTA.SCONN288_ADR50017P087CC(CHIPS)':
 'DQ27_A': CDS_PINID='DQ27_A';
NET_NAME
'M_E_CPU1_SA_DQ<28>'
 '@S9S_MB_2U_LIB.S9S_MB_2U(SCH_1):M_E_CPU1_SA_DQ'<28>:
 C_SIGNAL='@s9s_mb_2u_lib.s9s_mb_2u(sch_1):m_e_cpu1_sa_dq(28)';
NODE_NAME     U1 EL60
 '@S9S_MB_2U_LIB.S9S_MB_2U(SCH_1):PAGE55_I7@PURE_QUANTA.SOCKET4677_AZIF0045P001C01CS(CHIPS)':
 'DDR4_SA_DQ28': CDS_PINID='DDR4_SA_DQ28';
NODE_NAME     J25 47
 '@S9S_MB_2U_LIB.S9S_MB_2U(SCH_1):PAGE106_I180@PURE_QUANTA.SCONN288_ADR50017P130CC(CHIPS)':
 'DQ28_A': CDS_PINID='DQ28_A';
NODE_NAME     J26 47
 '@S9S_MB_2U_LIB.S9S_MB_2U(SCH_1):PAGE107_I180@PURE_QUANTA.SCONN288_ADR50017P087CC(CHIPS)':
 'DQ28_A': CDS_PINID='DQ28_A';
NET_NAME
'M_E_CPU1_SA_DQ<29>'
 '@S9S_MB_2U_LIB.S9S_MB_2U(SCH_1):M_E_CPU1_SA_DQ'<29>:
 C_SIGNAL='@s9s_mb_2u_lib.s9s_mb_2u(sch_1):m_e_cpu1_sa_dq(29)';
NODE_NAME     U1 EM59
 '@S9S_MB_2U_LIB.S9S_MB_2U(SCH_1):PAGE55_I7@PURE_QUANTA.SOCKET4677_AZIF0045P001C01CS(CHIPS)':
 'DDR4_SA_DQ29': CDS_PINID='DDR4_SA_DQ29';
NODE_NAME     J25 49
 '@S9S_MB_2U_LIB.S9S_MB_2U(SCH_1):PAGE106_I180@PURE_QUANTA.SCONN288_ADR50017P130CC(CHIPS)':
 'DQ29_A': CDS_PINID='DQ29_A';
NODE_NAME     J26 49
 '@S9S_MB_2U_LIB.S9S_MB_2U(SCH_1):PAGE107_I180@PURE_QUANTA.SCONN288_ADR50017P087CC(CHIPS)':
 'DQ29_A': CDS_PINID='DQ29_A';
NET_NAME
'M_E_CPU1_SA_DQ<2>'
 '@S9S_MB_2U_LIB.S9S_MB_2U(SCH_1):M_E_CPU1_SA_DQ'<2>:
 C_SIGNAL='@s9s_mb_2u_lib.s9s_mb_2u(sch_1):m_e_cpu1_sa_dq(2)';
NODE_NAME     U1 EP79
 '@S9S_MB_2U_LIB.S9S_MB_2U(SCH_1):PAGE55_I7@PURE_QUANTA.SOCKET4677_AZIF0045P001C01CS(CHIPS)':
 'DDR4_SA_DQ2': CDS_PINID='DDR4_SA_DQ2';
NODE_NAME     J25 152
 '@S9S_MB_2U_LIB.S9S_MB_2U(SCH_1):PAGE106_I180@PURE_QUANTA.SCONN288_ADR50017P130CC(CHIPS)':
 'DQ2_A': CDS_PINID='DQ2_A';
NODE_NAME     J26 152
 '@S9S_MB_2U_LIB.S9S_MB_2U(SCH_1):PAGE107_I180@PURE_QUANTA.SCONN288_ADR50017P087CC(CHIPS)':
 'DQ2_A': CDS_PINID='DQ2_A';
NET_NAME
'M_E_CPU1_SA_DQ<30>'
 '@S9S_MB_2U_LIB.S9S_MB_2U(SCH_1):M_E_CPU1_SA_DQ'<30>:
 C_SIGNAL='@s9s_mb_2u_lib.s9s_mb_2u(sch_1):m_e_cpu1_sa_dq(30)';
NODE_NAME     U1 ER60
 '@S9S_MB_2U_LIB.S9S_MB_2U(SCH_1):PAGE55_I7@PURE_QUANTA.SOCKET4677_AZIF0045P001C01CS(CHIPS)':
 'DDR4_SA_DQ30': CDS_PINID='DDR4_SA_DQ30';
NODE_NAME     J25 192
 '@S9S_MB_2U_LIB.S9S_MB_2U(SCH_1):PAGE106_I180@PURE_QUANTA.SCONN288_ADR50017P130CC(CHIPS)':
 'DQ30_A': CDS_PINID='DQ30_A';
NODE_NAME     J26 192
 '@S9S_MB_2U_LIB.S9S_MB_2U(SCH_1):PAGE107_I180@PURE_QUANTA.SCONN288_ADR50017P087CC(CHIPS)':
 'DQ30_A': CDS_PINID='DQ30_A';
NET_NAME
'M_E_CPU1_SA_DQ<31>'
 '@S9S_MB_2U_LIB.S9S_MB_2U(SCH_1):M_E_CPU1_SA_DQ'<31>:
 C_SIGNAL='@s9s_mb_2u_lib.s9s_mb_2u(sch_1):m_e_cpu1_sa_dq(31)';
NODE_NAME     U1 EP59
 '@S9S_MB_2U_LIB.S9S_MB_2U(SCH_1):PAGE55_I7@PURE_QUANTA.SOCKET4677_AZIF0045P001C01CS(CHIPS)':
 'DDR4_SA_DQ31': CDS_PINID='DDR4_SA_DQ31';
NODE_NAME     J25 194
 '@S9S_MB_2U_LIB.S9S_MB_2U(SCH_1):PAGE106_I180@PURE_QUANTA.SCONN288_ADR50017P130CC(CHIPS)':
 'DQ31_A': CDS_PINID='DQ31_A';
NODE_NAME     J26 194
 '@S9S_MB_2U_LIB.S9S_MB_2U(SCH_1):PAGE107_I180@PURE_QUANTA.SCONN288_ADR50017P087CC(CHIPS)':
 'DQ31_A': CDS_PINID='DQ31_A';
NET_NAME
'M_E_CPU1_SA_DQ<3>'
 '@S9S_MB_2U_LIB.S9S_MB_2U(SCH_1):M_E_CPU1_SA_DQ'<3>:
 C_SIGNAL='@s9s_mb_2u_lib.s9s_mb_2u(sch_1):m_e_cpu1_sa_dq(3)';
NODE_NAME     U1 ER76
 '@S9S_MB_2U_LIB.S9S_MB_2U(SCH_1):PAGE55_I7@PURE_QUANTA.SOCKET4677_AZIF0045P001C01CS(CHIPS)':
 'DDR4_SA_DQ3': CDS_PINID='DDR4_SA_DQ3';
NODE_NAME     J25 154
 '@S9S_MB_2U_LIB.S9S_MB_2U(SCH_1):PAGE106_I180@PURE_QUANTA.SCONN288_ADR50017P130CC(CHIPS)':
 'DQ3_A': CDS_PINID='DQ3_A';
NODE_NAME     J26 154
 '@S9S_MB_2U_LIB.S9S_MB_2U(SCH_1):PAGE107_I180@PURE_QUANTA.SCONN288_ADR50017P087CC(CHIPS)':
 'DQ3_A': CDS_PINID='DQ3_A';
NET_NAME
'M_E_CPU1_SA_DQ<4>'
 '@S9S_MB_2U_LIB.S9S_MB_2U(SCH_1):M_E_CPU1_SA_DQ'<4>:
 C_SIGNAL='@s9s_mb_2u_lib.s9s_mb_2u(sch_1):m_e_cpu1_sa_dq(4)';
NODE_NAME     U1 EL74
 '@S9S_MB_2U_LIB.S9S_MB_2U(SCH_1):PAGE55_I7@PURE_QUANTA.SOCKET4677_AZIF0045P001C01CS(CHIPS)':
 'DDR4_SA_DQ4': CDS_PINID='DDR4_SA_DQ4';
NODE_NAME     J25 14
 '@S9S_MB_2U_LIB.S9S_MB_2U(SCH_1):PAGE106_I180@PURE_QUANTA.SCONN288_ADR50017P130CC(CHIPS)':
 'DQ4_A': CDS_PINID='DQ4_A';
NODE_NAME     J26 14
 '@S9S_MB_2U_LIB.S9S_MB_2U(SCH_1):PAGE107_I180@PURE_QUANTA.SCONN288_ADR50017P087CC(CHIPS)':
 'DQ4_A': CDS_PINID='DQ4_A';
NET_NAME
'M_E_CPU1_SA_DQ<5>'
 '@S9S_MB_2U_LIB.S9S_MB_2U(SCH_1):M_E_CPU1_SA_DQ'<5>:
 C_SIGNAL='@s9s_mb_2u_lib.s9s_mb_2u(sch_1):m_e_cpu1_sa_dq(5)';
NODE_NAME     U1 EK73
 '@S9S_MB_2U_LIB.S9S_MB_2U(SCH_1):PAGE55_I7@PURE_QUANTA.SOCKET4677_AZIF0045P001C01CS(CHIPS)':
 'DDR4_SA_DQ5': CDS_PINID='DDR4_SA_DQ5';
NODE_NAME     J25 16
 '@S9S_MB_2U_LIB.S9S_MB_2U(SCH_1):PAGE106_I180@PURE_QUANTA.SCONN288_ADR50017P130CC(CHIPS)':
 'DQ5_A': CDS_PINID='DQ5_A';
NODE_NAME     J26 16
 '@S9S_MB_2U_LIB.S9S_MB_2U(SCH_1):PAGE107_I180@PURE_QUANTA.SCONN288_ADR50017P087CC(CHIPS)':
 'DQ5_A': CDS_PINID='DQ5_A';
NET_NAME
'M_E_CPU1_SA_DQ<6>'
 '@S9S_MB_2U_LIB.S9S_MB_2U(SCH_1):M_E_CPU1_SA_DQ'<6>:
 C_SIGNAL='@s9s_mb_2u_lib.s9s_mb_2u(sch_1):m_e_cpu1_sa_dq(6)';
NODE_NAME     U1 EP73
 '@S9S_MB_2U_LIB.S9S_MB_2U(SCH_1):PAGE55_I7@PURE_QUANTA.SOCKET4677_AZIF0045P001C01CS(CHIPS)':
 'DDR4_SA_DQ6': CDS_PINID='DDR4_SA_DQ6';
NODE_NAME     J25 159
 '@S9S_MB_2U_LIB.S9S_MB_2U(SCH_1):PAGE106_I180@PURE_QUANTA.SCONN288_ADR50017P130CC(CHIPS)':
 'DQ6_A': CDS_PINID='DQ6_A';
NODE_NAME     J26 159
 '@S9S_MB_2U_LIB.S9S_MB_2U(SCH_1):PAGE107_I180@PURE_QUANTA.SCONN288_ADR50017P087CC(CHIPS)':
 'DQ6_A': CDS_PINID='DQ6_A';
NET_NAME
'M_E_CPU1_SA_DQ<7>'
 '@S9S_MB_2U_LIB.S9S_MB_2U(SCH_1):M_E_CPU1_SA_DQ'<7>:
 C_SIGNAL='@s9s_mb_2u_lib.s9s_mb_2u(sch_1):m_e_cpu1_sa_dq(7)';
NODE_NAME     U1 ER72
 '@S9S_MB_2U_LIB.S9S_MB_2U(SCH_1):PAGE55_I7@PURE_QUANTA.SOCKET4677_AZIF0045P001C01CS(CHIPS)':
 'DDR4_SA_DQ7': CDS_PINID='DDR4_SA_DQ7';
NODE_NAME     J25 161
 '@S9S_MB_2U_LIB.S9S_MB_2U(SCH_1):PAGE106_I180@PURE_QUANTA.SCONN288_ADR50017P130CC(CHIPS)':
 'DQ7_A': CDS_PINID='DQ7_A';
NODE_NAME     J26 161
 '@S9S_MB_2U_LIB.S9S_MB_2U(SCH_1):PAGE107_I180@PURE_QUANTA.SCONN288_ADR50017P087CC(CHIPS)':
 'DQ7_A': CDS_PINID='DQ7_A';
NET_NAME
'M_E_CPU1_SA_DQ<8>'
 '@S9S_MB_2U_LIB.S9S_MB_2U(SCH_1):M_E_CPU1_SA_DQ'<8>:
 C_SIGNAL='@s9s_mb_2u_lib.s9s_mb_2u(sch_1):m_e_cpu1_sa_dq(8)';
NODE_NAME     U1 EE72
 '@S9S_MB_2U_LIB.S9S_MB_2U(SCH_1):PAGE55_I7@PURE_QUANTA.SOCKET4677_AZIF0045P001C01CS(CHIPS)':
 'DDR4_SA_DQ8': CDS_PINID='DDR4_SA_DQ8';
NODE_NAME     J25 18
 '@S9S_MB_2U_LIB.S9S_MB_2U(SCH_1):PAGE106_I180@PURE_QUANTA.SCONN288_ADR50017P130CC(CHIPS)':
 'DQ8_A': CDS_PINID='DQ8_A';
NODE_NAME     J26 18
 '@S9S_MB_2U_LIB.S9S_MB_2U(SCH_1):PAGE107_I180@PURE_QUANTA.SCONN288_ADR50017P087CC(CHIPS)':
 'DQ8_A': CDS_PINID='DQ8_A';
NET_NAME
'M_E_CPU1_SA_DQ<9>'
 '@S9S_MB_2U_LIB.S9S_MB_2U(SCH_1):M_E_CPU1_SA_DQ'<9>:
 C_SIGNAL='@s9s_mb_2u_lib.s9s_mb_2u(sch_1):m_e_cpu1_sa_dq(9)';
NODE_NAME     U1 ED71
 '@S9S_MB_2U_LIB.S9S_MB_2U(SCH_1):PAGE55_I7@PURE_QUANTA.SOCKET4677_AZIF0045P001C01CS(CHIPS)':
 'DDR4_SA_DQ9': CDS_PINID='DDR4_SA_DQ9';
NODE_NAME     J25 20
 '@S9S_MB_2U_LIB.S9S_MB_2U(SCH_1):PAGE106_I180@PURE_QUANTA.SCONN288_ADR50017P130CC(CHIPS)':
 'DQ9_A': CDS_PINID='DQ9_A';
NODE_NAME     J26 20
 '@S9S_MB_2U_LIB.S9S_MB_2U(SCH_1):PAGE107_I180@PURE_QUANTA.SCONN288_ADR50017P087CC(CHIPS)':
 'DQ9_A': CDS_PINID='DQ9_A';
NET_NAME
'M_E_CPU1_SA_DQS_DN<0>'
 '@S9S_MB_2U_LIB.S9S_MB_2U(SCH_1):M_E_CPU1_SA_DQS_DN'<0>:
 C_SIGNAL='@s9s_mb_2u_lib.s9s_mb_2u(sch_1):m_e_cpu1_sa_dqs_dn(0)';
NODE_NAME     U1 EP75
 '@S9S_MB_2U_LIB.S9S_MB_2U(SCH_1):PAGE55_I7@PURE_QUANTA.SOCKET4677_AZIF0045P001C01CS(CHIPS)':
 'DDR4_SA_DQS_DN0': CDS_PINID='DDR4_SA_DQS_DN0';
NODE_NAME     J25 12
 '@S9S_MB_2U_LIB.S9S_MB_2U(SCH_1):PAGE106_I181@PURE_QUANTA.SCONN288_ADR50017P130CC(CHIPS)':
 'DQS0_A_C': CDS_PINID='DQS0_A_C';
NODE_NAME     J26 12
 '@S9S_MB_2U_LIB.S9S_MB_2U(SCH_1):PAGE107_I181@PURE_QUANTA.SCONN288_ADR50017P087CC(CHIPS)':
 'DQS0_A_C': CDS_PINID='DQS0_A_C';
NET_NAME
'M_E_CPU1_SA_DQS_DN<1>'
 '@S9S_MB_2U_LIB.S9S_MB_2U(SCH_1):M_E_CPU1_SA_DQS_DN'<1>:
 C_SIGNAL='@s9s_mb_2u_lib.s9s_mb_2u(sch_1):m_e_cpu1_sa_dqs_dn(1)';
NODE_NAME     U1 EC70
 '@S9S_MB_2U_LIB.S9S_MB_2U(SCH_1):PAGE55_I7@PURE_QUANTA.SOCKET4677_AZIF0045P001C01CS(CHIPS)':
 'DDR4_SA_DQS_DN1': CDS_PINID='DDR4_SA_DQS_DN1';
NODE_NAME     J25 23
 '@S9S_MB_2U_LIB.S9S_MB_2U(SCH_1):PAGE106_I181@PURE_QUANTA.SCONN288_ADR50017P130CC(CHIPS)':
 'DQS1_A_C': CDS_PINID='DQS1_A_C';
NODE_NAME     J26 23
 '@S9S_MB_2U_LIB.S9S_MB_2U(SCH_1):PAGE107_I181@PURE_QUANTA.SCONN288_ADR50017P087CC(CHIPS)':
 'DQS1_A_C': CDS_PINID='DQS1_A_C';
NET_NAME
'M_E_CPU1_SA_DQS_DN<2>'
 '@S9S_MB_2U_LIB.S9S_MB_2U(SCH_1):M_E_CPU1_SA_DQS_DN'<2>:
 C_SIGNAL='@s9s_mb_2u_lib.s9s_mb_2u(sch_1):m_e_cpu1_sa_dqs_dn(2)';
NODE_NAME     U1 EK67
 '@S9S_MB_2U_LIB.S9S_MB_2U(SCH_1):PAGE55_I7@PURE_QUANTA.SOCKET4677_AZIF0045P001C01CS(CHIPS)':
 'DDR4_SA_DQS_DN2': CDS_PINID='DDR4_SA_DQS_DN2';
NODE_NAME     J25 34
 '@S9S_MB_2U_LIB.S9S_MB_2U(SCH_1):PAGE106_I181@PURE_QUANTA.SCONN288_ADR50017P130CC(CHIPS)':
 'DQS2_A_C': CDS_PINID='DQS2_A_C';
NODE_NAME     J26 34
 '@S9S_MB_2U_LIB.S9S_MB_2U(SCH_1):PAGE107_I181@PURE_QUANTA.SCONN288_ADR50017P087CC(CHIPS)':
 'DQS2_A_C': CDS_PINID='DQS2_A_C';
NET_NAME
'M_E_CPU1_SA_DQS_DN<3>'
 '@S9S_MB_2U_LIB.S9S_MB_2U(SCH_1):M_E_CPU1_SA_DQS_DN'<3>:
 C_SIGNAL='@s9s_mb_2u_lib.s9s_mb_2u(sch_1):m_e_cpu1_sa_dqs_dn(3)';
NODE_NAME     U1 EK61
 '@S9S_MB_2U_LIB.S9S_MB_2U(SCH_1):PAGE55_I7@PURE_QUANTA.SOCKET4677_AZIF0045P001C01CS(CHIPS)':
 'DDR4_SA_DQS_DN3': CDS_PINID='DDR4_SA_DQS_DN3';
NODE_NAME     J25 45
 '@S9S_MB_2U_LIB.S9S_MB_2U(SCH_1):PAGE106_I181@PURE_QUANTA.SCONN288_ADR50017P130CC(CHIPS)':
 'DQS3_A_C': CDS_PINID='DQS3_A_C';
NODE_NAME     J26 45
 '@S9S_MB_2U_LIB.S9S_MB_2U(SCH_1):PAGE107_I181@PURE_QUANTA.SCONN288_ADR50017P087CC(CHIPS)':
 'DQS3_A_C': CDS_PINID='DQS3_A_C';
NET_NAME
'M_E_CPU1_SA_DQS_DN<4>'
 '@S9S_MB_2U_LIB.S9S_MB_2U(SCH_1):M_E_CPU1_SA_DQS_DN'<4>:
 C_SIGNAL='@s9s_mb_2u_lib.s9s_mb_2u(sch_1):m_e_cpu1_sa_dqs_dn(4)';
NODE_NAME     U1 EM55
 '@S9S_MB_2U_LIB.S9S_MB_2U(SCH_1):PAGE55_I7@PURE_QUANTA.SOCKET4677_AZIF0045P001C01CS(CHIPS)':
 'DDR4_SA_DQS_DN4': CDS_PINID='DDR4_SA_DQS_DN4';
NODE_NAME     J25 56
 '@S9S_MB_2U_LIB.S9S_MB_2U(SCH_1):PAGE106_I181@PURE_QUANTA.SCONN288_ADR50017P130CC(CHIPS)':
 'DQS4_A_C': CDS_PINID='DQS4_A_C';
NODE_NAME     J26 56
 '@S9S_MB_2U_LIB.S9S_MB_2U(SCH_1):PAGE107_I181@PURE_QUANTA.SCONN288_ADR50017P087CC(CHIPS)':
 'DQS4_A_C': CDS_PINID='DQS4_A_C';
NET_NAME
'M_E_CPU1_SA_DQS_DN<5>'
 '@S9S_MB_2U_LIB.S9S_MB_2U(SCH_1):M_E_CPU1_SA_DQS_DN'<5>:
 C_SIGNAL='@s9s_mb_2u_lib.s9s_mb_2u(sch_1):m_e_cpu1_sa_dqs_dn(5)';
NODE_NAME     U1 EM75
 '@S9S_MB_2U_LIB.S9S_MB_2U(SCH_1):PAGE55_I7@PURE_QUANTA.SOCKET4677_AZIF0045P001C01CS(CHIPS)':
 'DDR4_SA_DQS_DN5': CDS_PINID='DDR4_SA_DQS_DN5';
NODE_NAME     J25 156
 '@S9S_MB_2U_LIB.S9S_MB_2U(SCH_1):PAGE106_I181@PURE_QUANTA.SCONN288_ADR50017P130CC(CHIPS)':
 'DQS5_A_C||TDQS5_A_C||DQS5_A_T||TDQS5_A_T': CDS_PINID='\dqs5_a_c||tdqs5_a_c||dqs5_a_t||tdqs5_a_t\';
NODE_NAME     J26 156
 '@S9S_MB_2U_LIB.S9S_MB_2U(SCH_1):PAGE107_I181@PURE_QUANTA.SCONN288_ADR50017P087CC(CHIPS)':
 'DQS5_A_C||TDQS5_A_C||DQS5_A_T||TDQS5_A_T': CDS_PINID='\dqs5_a_c||tdqs5_a_c||dqs5_a_t||tdqs5_a_t\';
NET_NAME
'M_E_CPU1_SA_DQS_DN<6>'
 '@S9S_MB_2U_LIB.S9S_MB_2U(SCH_1):M_E_CPU1_SA_DQS_DN'<6>:
 C_SIGNAL='@s9s_mb_2u_lib.s9s_mb_2u(sch_1):m_e_cpu1_sa_dqs_dn(6)';
NODE_NAME     U1 EJ70
 '@S9S_MB_2U_LIB.S9S_MB_2U(SCH_1):PAGE55_I7@PURE_QUANTA.SOCKET4677_AZIF0045P001C01CS(CHIPS)':
 'DDR4_SA_DQS_DN6': CDS_PINID='DDR4_SA_DQS_DN6';
NODE_NAME     J25 167
 '@S9S_MB_2U_LIB.S9S_MB_2U(SCH_1):PAGE106_I181@PURE_QUANTA.SCONN288_ADR50017P130CC(CHIPS)':
 'DQS6_A_C||TDQS6_A_C||DQS6_A_T||TDQS6_A_T': CDS_PINID='\dqs6_a_c||tdqs6_a_c||dqs6_a_t||tdqs6_a_t\';
NODE_NAME     J26 167
 '@S9S_MB_2U_LIB.S9S_MB_2U(SCH_1):PAGE107_I181@PURE_QUANTA.SCONN288_ADR50017P087CC(CHIPS)':
 'DQS6_A_C||TDQS6_A_C||DQS6_A_T||TDQS6_A_T': CDS_PINID='\dqs6_a_c||tdqs6_a_c||dqs6_a_t||tdqs6_a_t\';
NET_NAME
'M_E_CPU1_SA_DQS_DN<7>'
 '@S9S_MB_2U_LIB.S9S_MB_2U(SCH_1):M_E_CPU1_SA_DQS_DN'<7>:
 C_SIGNAL='@s9s_mb_2u_lib.s9s_mb_2u(sch_1):m_e_cpu1_sa_dqs_dn(7)';
NODE_NAME     U1 EN68
 '@S9S_MB_2U_LIB.S9S_MB_2U(SCH_1):PAGE55_I7@PURE_QUANTA.SOCKET4677_AZIF0045P001C01CS(CHIPS)':
 'DDR4_SA_DQS_DN7': CDS_PINID='DDR4_SA_DQS_DN7';
NODE_NAME     J25 178
 '@S9S_MB_2U_LIB.S9S_MB_2U(SCH_1):PAGE106_I181@PURE_QUANTA.SCONN288_ADR50017P130CC(CHIPS)':
 'DQS7_A_C||TDQS7_A_C': CDS_PINID='\dqs7_a_c||tdqs7_a_c\';
NODE_NAME     J26 178
 '@S9S_MB_2U_LIB.S9S_MB_2U(SCH_1):PAGE107_I181@PURE_QUANTA.SCONN288_ADR50017P087CC(CHIPS)':
 'DQS7_A_C||TDQS7_A_C': CDS_PINID='\dqs7_a_c||tdqs7_a_c\';
NET_NAME
'M_E_CPU1_SA_DQS_DN<8>'
 '@S9S_MB_2U_LIB.S9S_MB_2U(SCH_1):M_E_CPU1_SA_DQS_DN'<8>:
 C_SIGNAL='@s9s_mb_2u_lib.s9s_mb_2u(sch_1):m_e_cpu1_sa_dqs_dn(8)';
NODE_NAME     U1 ET61
 '@S9S_MB_2U_LIB.S9S_MB_2U(SCH_1):PAGE55_I7@PURE_QUANTA.SOCKET4677_AZIF0045P001C01CS(CHIPS)':
 'DDR4_SA_DQS_DN8': CDS_PINID='DDR4_SA_DQS_DN8';
NODE_NAME     J25 189
 '@S9S_MB_2U_LIB.S9S_MB_2U(SCH_1):PAGE106_I181@PURE_QUANTA.SCONN288_ADR50017P130CC(CHIPS)':
 'DQS8_A_C||TDQS8_A_C': CDS_PINID='\dqs8_a_c||tdqs8_a_c\';
NODE_NAME     J26 189
 '@S9S_MB_2U_LIB.S9S_MB_2U(SCH_1):PAGE107_I181@PURE_QUANTA.SCONN288_ADR50017P087CC(CHIPS)':
 'DQS8_A_C||TDQS8_A_C': CDS_PINID='\dqs8_a_c||tdqs8_a_c\';
NET_NAME
'M_E_CPU1_SA_DQS_DN<9>'
 '@S9S_MB_2U_LIB.S9S_MB_2U(SCH_1):M_E_CPU1_SA_DQS_DN'<9>:
 C_SIGNAL='@s9s_mb_2u_lib.s9s_mb_2u(sch_1):m_e_cpu1_sa_dqs_dn(9)';
NODE_NAME     U1 ET55
 '@S9S_MB_2U_LIB.S9S_MB_2U(SCH_1):PAGE55_I7@PURE_QUANTA.SOCKET4677_AZIF0045P001C01CS(CHIPS)':
 'DDR4_SA_DQS_DN9': CDS_PINID='DDR4_SA_DQS_DN9';
NODE_NAME     J25 200
 '@S9S_MB_2U_LIB.S9S_MB_2U(SCH_1):PAGE106_I181@PURE_QUANTA.SCONN288_ADR50017P130CC(CHIPS)':
 'DQS9_A_C||TDQS9_A_C': CDS_PINID='\dqs9_a_c||tdqs9_a_c\';
NODE_NAME     J26 200
 '@S9S_MB_2U_LIB.S9S_MB_2U(SCH_1):PAGE107_I181@PURE_QUANTA.SCONN288_ADR50017P087CC(CHIPS)':
 'DQS9_A_C||TDQS9_A_C': CDS_PINID='\dqs9_a_c||tdqs9_a_c\';
NET_NAME
'M_E_CPU1_SA_DQS_DP<0>'
 '@S9S_MB_2U_LIB.S9S_MB_2U(SCH_1):M_E_CPU1_SA_DQS_DP'<0>:
 C_SIGNAL='@s9s_mb_2u_lib.s9s_mb_2u(sch_1):m_e_cpu1_sa_dqs_dp(0)';
NODE_NAME     U1 EN76
 '@S9S_MB_2U_LIB.S9S_MB_2U(SCH_1):PAGE55_I7@PURE_QUANTA.SOCKET4677_AZIF0045P001C01CS(CHIPS)':
 'DDR4_SA_DQS_DP0': CDS_PINID='DDR4_SA_DQS_DP0';
NODE_NAME     J25 11
 '@S9S_MB_2U_LIB.S9S_MB_2U(SCH_1):PAGE106_I181@PURE_QUANTA.SCONN288_ADR50017P130CC(CHIPS)':
 'DQS0_A_T': CDS_PINID='DQS0_A_T';
NODE_NAME     J26 11
 '@S9S_MB_2U_LIB.S9S_MB_2U(SCH_1):PAGE107_I181@PURE_QUANTA.SCONN288_ADR50017P087CC(CHIPS)':
 'DQS0_A_T': CDS_PINID='DQS0_A_T';
NET_NAME
'M_E_CPU1_SA_DQS_DP<1>'
 '@S9S_MB_2U_LIB.S9S_MB_2U(SCH_1):M_E_CPU1_SA_DQS_DP'<1>:
 C_SIGNAL='@s9s_mb_2u_lib.s9s_mb_2u(sch_1):m_e_cpu1_sa_dqs_dp(1)';
NODE_NAME     U1 EE70
 '@S9S_MB_2U_LIB.S9S_MB_2U(SCH_1):PAGE55_I7@PURE_QUANTA.SOCKET4677_AZIF0045P001C01CS(CHIPS)':
 'DDR4_SA_DQS_DP1': CDS_PINID='DDR4_SA_DQS_DP1';
NODE_NAME     J25 22
 '@S9S_MB_2U_LIB.S9S_MB_2U(SCH_1):PAGE106_I181@PURE_QUANTA.SCONN288_ADR50017P130CC(CHIPS)':
 'DQS1_A_T': CDS_PINID='DQS1_A_T';
NODE_NAME     J26 22
 '@S9S_MB_2U_LIB.S9S_MB_2U(SCH_1):PAGE107_I181@PURE_QUANTA.SCONN288_ADR50017P087CC(CHIPS)':
 'DQS1_A_T': CDS_PINID='DQS1_A_T';
NET_NAME
'M_E_CPU1_SA_DQS_DP<2>'
 '@S9S_MB_2U_LIB.S9S_MB_2U(SCH_1):M_E_CPU1_SA_DQS_DP'<2>:
 C_SIGNAL='@s9s_mb_2u_lib.s9s_mb_2u(sch_1):m_e_cpu1_sa_dqs_dp(2)';
NODE_NAME     U1 EL68
 '@S9S_MB_2U_LIB.S9S_MB_2U(SCH_1):PAGE55_I7@PURE_QUANTA.SOCKET4677_AZIF0045P001C01CS(CHIPS)':
 'DDR4_SA_DQS_DP2': CDS_PINID='DDR4_SA_DQS_DP2';
NODE_NAME     J25 33
 '@S9S_MB_2U_LIB.S9S_MB_2U(SCH_1):PAGE106_I181@PURE_QUANTA.SCONN288_ADR50017P130CC(CHIPS)':
 'DQS2_A_T': CDS_PINID='DQS2_A_T';
NODE_NAME     J26 33
 '@S9S_MB_2U_LIB.S9S_MB_2U(SCH_1):PAGE107_I181@PURE_QUANTA.SCONN288_ADR50017P087CC(CHIPS)':
 'DQS2_A_T': CDS_PINID='DQS2_A_T';
NET_NAME
'M_E_CPU1_SA_DQS_DP<3>'
 '@S9S_MB_2U_LIB.S9S_MB_2U(SCH_1):M_E_CPU1_SA_DQS_DP'<3>:
 C_SIGNAL='@s9s_mb_2u_lib.s9s_mb_2u(sch_1):m_e_cpu1_sa_dqs_dp(3)';
NODE_NAME     U1 EM61
 '@S9S_MB_2U_LIB.S9S_MB_2U(SCH_1):PAGE55_I7@PURE_QUANTA.SOCKET4677_AZIF0045P001C01CS(CHIPS)':
 'DDR4_SA_DQS_DP3': CDS_PINID='DDR4_SA_DQS_DP3';
NODE_NAME     J25 44
 '@S9S_MB_2U_LIB.S9S_MB_2U(SCH_1):PAGE106_I181@PURE_QUANTA.SCONN288_ADR50017P130CC(CHIPS)':
 'DQS3_A_T': CDS_PINID='DQS3_A_T';
NODE_NAME     J26 44
 '@S9S_MB_2U_LIB.S9S_MB_2U(SCH_1):PAGE107_I181@PURE_QUANTA.SCONN288_ADR50017P087CC(CHIPS)':
 'DQS3_A_T': CDS_PINID='DQS3_A_T';
NET_NAME
'M_E_CPU1_SA_DQS_DP<4>'
 '@S9S_MB_2U_LIB.S9S_MB_2U(SCH_1):M_E_CPU1_SA_DQS_DP'<4>:
 C_SIGNAL='@s9s_mb_2u_lib.s9s_mb_2u(sch_1):m_e_cpu1_sa_dqs_dp(4)';
NODE_NAME     U1 EK55
 '@S9S_MB_2U_LIB.S9S_MB_2U(SCH_1):PAGE55_I7@PURE_QUANTA.SOCKET4677_AZIF0045P001C01CS(CHIPS)':
 'DDR4_SA_DQS_DP4': CDS_PINID='DDR4_SA_DQS_DP4';
NODE_NAME     J25 55
 '@S9S_MB_2U_LIB.S9S_MB_2U(SCH_1):PAGE106_I181@PURE_QUANTA.SCONN288_ADR50017P130CC(CHIPS)':
 'DQS4_A_T': CDS_PINID='DQS4_A_T';
NODE_NAME     J26 55
 '@S9S_MB_2U_LIB.S9S_MB_2U(SCH_1):PAGE107_I181@PURE_QUANTA.SCONN288_ADR50017P087CC(CHIPS)':
 'DQS4_A_T': CDS_PINID='DQS4_A_T';
NET_NAME
'M_E_CPU1_SA_DQS_DP<5>'
 '@S9S_MB_2U_LIB.S9S_MB_2U(SCH_1):M_E_CPU1_SA_DQS_DP'<5>:
 C_SIGNAL='@s9s_mb_2u_lib.s9s_mb_2u(sch_1):m_e_cpu1_sa_dqs_dp(5)';
NODE_NAME     U1 EN74
 '@S9S_MB_2U_LIB.S9S_MB_2U(SCH_1):PAGE55_I7@PURE_QUANTA.SOCKET4677_AZIF0045P001C01CS(CHIPS)':
 'DDR4_SA_DQS_DP5': CDS_PINID='DDR4_SA_DQS_DP5';
NODE_NAME     J25 157
 '@S9S_MB_2U_LIB.S9S_MB_2U(SCH_1):PAGE106_I181@PURE_QUANTA.SCONN288_ADR50017P130CC(CHIPS)':
 'DQS5_A_T||TDQS5_A_T': CDS_PINID='\dqs5_a_t||tdqs5_a_t\';
NODE_NAME     J26 157
 '@S9S_MB_2U_LIB.S9S_MB_2U(SCH_1):PAGE107_I181@PURE_QUANTA.SCONN288_ADR50017P087CC(CHIPS)':
 'DQS5_A_T||TDQS5_A_T': CDS_PINID='\dqs5_a_t||tdqs5_a_t\';
NET_NAME
'M_E_CPU1_SA_DQS_DP<6>'
 '@S9S_MB_2U_LIB.S9S_MB_2U(SCH_1):M_E_CPU1_SA_DQS_DP'<6>:
 C_SIGNAL='@s9s_mb_2u_lib.s9s_mb_2u(sch_1):m_e_cpu1_sa_dqs_dp(6)';
NODE_NAME     U1 EG70
 '@S9S_MB_2U_LIB.S9S_MB_2U(SCH_1):PAGE55_I7@PURE_QUANTA.SOCKET4677_AZIF0045P001C01CS(CHIPS)':
 'DDR4_SA_DQS_DP6': CDS_PINID='DDR4_SA_DQS_DP6';
NODE_NAME     J25 168
 '@S9S_MB_2U_LIB.S9S_MB_2U(SCH_1):PAGE106_I181@PURE_QUANTA.SCONN288_ADR50017P130CC(CHIPS)':
 'DQS6_A_T||TDQS6_A_T': CDS_PINID='\dqs6_a_t||tdqs6_a_t\';
NODE_NAME     J26 168
 '@S9S_MB_2U_LIB.S9S_MB_2U(SCH_1):PAGE107_I181@PURE_QUANTA.SCONN288_ADR50017P087CC(CHIPS)':
 'DQS6_A_T||TDQS6_A_T': CDS_PINID='\dqs6_a_t||tdqs6_a_t\';
NET_NAME
'M_E_CPU1_SA_DQS_DP<7>'
 '@S9S_MB_2U_LIB.S9S_MB_2U(SCH_1):M_E_CPU1_SA_DQS_DP'<7>:
 C_SIGNAL='@s9s_mb_2u_lib.s9s_mb_2u(sch_1):m_e_cpu1_sa_dqs_dp(7)';
NODE_NAME     U1 EM67
 '@S9S_MB_2U_LIB.S9S_MB_2U(SCH_1):PAGE55_I7@PURE_QUANTA.SOCKET4677_AZIF0045P001C01CS(CHIPS)':
 'DDR4_SA_DQS_DP7': CDS_PINID='DDR4_SA_DQS_DP7';
NODE_NAME     J25 179
 '@S9S_MB_2U_LIB.S9S_MB_2U(SCH_1):PAGE106_I181@PURE_QUANTA.SCONN288_ADR50017P130CC(CHIPS)':
 'DQS7_A_T||TDQS7_A_T': CDS_PINID='\dqs7_a_t||tdqs7_a_t\';
NODE_NAME     J26 179
 '@S9S_MB_2U_LIB.S9S_MB_2U(SCH_1):PAGE107_I181@PURE_QUANTA.SCONN288_ADR50017P087CC(CHIPS)':
 'DQS7_A_T||TDQS7_A_T': CDS_PINID='\dqs7_a_t||tdqs7_a_t\';
NET_NAME
'M_E_CPU1_SA_DQS_DP<8>'
 '@S9S_MB_2U_LIB.S9S_MB_2U(SCH_1):M_E_CPU1_SA_DQS_DP'<8>:
 C_SIGNAL='@s9s_mb_2u_lib.s9s_mb_2u(sch_1):m_e_cpu1_sa_dqs_dp(8)';
NODE_NAME     U1 EP61
 '@S9S_MB_2U_LIB.S9S_MB_2U(SCH_1):PAGE55_I7@PURE_QUANTA.SOCKET4677_AZIF0045P001C01CS(CHIPS)':
 'DDR4_SA_DQS_DP8': CDS_PINID='DDR4_SA_DQS_DP8';
NODE_NAME     J25 190
 '@S9S_MB_2U_LIB.S9S_MB_2U(SCH_1):PAGE106_I181@PURE_QUANTA.SCONN288_ADR50017P130CC(CHIPS)':
 'DQS8_A_T||TDQS8_A_T': CDS_PINID='\dqs8_a_t||tdqs8_a_t\';
NODE_NAME     J26 190
 '@S9S_MB_2U_LIB.S9S_MB_2U(SCH_1):PAGE107_I181@PURE_QUANTA.SCONN288_ADR50017P087CC(CHIPS)':
 'DQS8_A_T||TDQS8_A_T': CDS_PINID='\dqs8_a_t||tdqs8_a_t\';
NET_NAME
'M_E_CPU1_SA_DQS_DP<9>'
 '@S9S_MB_2U_LIB.S9S_MB_2U(SCH_1):M_E_CPU1_SA_DQS_DP'<9>:
 C_SIGNAL='@s9s_mb_2u_lib.s9s_mb_2u(sch_1):m_e_cpu1_sa_dqs_dp(9)';
NODE_NAME     U1 EP55
 '@S9S_MB_2U_LIB.S9S_MB_2U(SCH_1):PAGE55_I7@PURE_QUANTA.SOCKET4677_AZIF0045P001C01CS(CHIPS)':
 'DDR4_SA_DQS_DP9': CDS_PINID='DDR4_SA_DQS_DP9';
NODE_NAME     J25 201
 '@S9S_MB_2U_LIB.S9S_MB_2U(SCH_1):PAGE106_I181@PURE_QUANTA.SCONN288_ADR50017P130CC(CHIPS)':
 'DQS9_A_T||TDQS9_A_T': CDS_PINID='\dqs9_a_t||tdqs9_a_t\';
NODE_NAME     J26 201
 '@S9S_MB_2U_LIB.S9S_MB_2U(SCH_1):PAGE107_I181@PURE_QUANTA.SCONN288_ADR50017P087CC(CHIPS)':
 'DQS9_A_T||TDQS9_A_T': CDS_PINID='\dqs9_a_t||tdqs9_a_t\';
NET_NAME
'M_E_CPU1_SA_PAR'
 '@S9S_MB_2U_LIB.S9S_MB_2U(SCH_1):M_E_CPU1_SA_PAR':
 C_SIGNAL='@s9s_mb_2u_lib.s9s_mb_2u(sch_1):m_e_cpu1_sa_par';
NODE_NAME     U1 EE43
 '@S9S_MB_2U_LIB.S9S_MB_2U(SCH_1):PAGE55_I7@PURE_QUANTA.SOCKET4677_AZIF0045P001C01CS(CHIPS)':
 'DDR4_SA_PAR': CDS_PINID='DDR4_SA_PAR';
NODE_NAME     J25 74
 '@S9S_MB_2U_LIB.S9S_MB_2U(SCH_1):PAGE106_I180@PURE_QUANTA.SCONN288_ADR50017P130CC(CHIPS)':
 'PAR_A': CDS_PINID='PAR_A';
NODE_NAME     J26 74
 '@S9S_MB_2U_LIB.S9S_MB_2U(SCH_1):PAGE107_I180@PURE_QUANTA.SCONN288_ADR50017P087CC(CHIPS)':
 'PAR_A': CDS_PINID='PAR_A';
NET_NAME
'M_E_CPU1_SA_RSP<0>'
 '@S9S_MB_2U_LIB.S9S_MB_2U(SCH_1):M_E_CPU1_SA_RSP'<0>:
 C_SIGNAL='@s9s_mb_2u_lib.s9s_mb_2u(sch_1):m_e_cpu1_sa_rsp(0)';
NODE_NAME     U1 DD44
 '@S9S_MB_2U_LIB.S9S_MB_2U(SCH_1):PAGE55_I7@PURE_QUANTA.SOCKET4677_AZIF0045P001C01CS(CHIPS)':
 'DDR4_A_RSP0': CDS_PINID='DDR4_A_RSP0';
NODE_NAME     J25 86
 '@S9S_MB_2U_LIB.S9S_MB_2U(SCH_1):PAGE106_I180@PURE_QUANTA.SCONN288_ADR50017P130CC(CHIPS)':
 'LBD||RSP_A_N': CDS_PINID='\lbd||rsp_a_n\';
NET_NAME
'M_E_CPU1_SA_RSP<1>'
 '@S9S_MB_2U_LIB.S9S_MB_2U(SCH_1):M_E_CPU1_SA_RSP'<1>:
 C_SIGNAL='@s9s_mb_2u_lib.s9s_mb_2u(sch_1):m_e_cpu1_sa_rsp(1)';
NODE_NAME     U1 DC43
 '@S9S_MB_2U_LIB.S9S_MB_2U(SCH_1):PAGE55_I7@PURE_QUANTA.SOCKET4677_AZIF0045P001C01CS(CHIPS)':
 'DDR4_A_RSP1': CDS_PINID='DDR4_A_RSP1';
NODE_NAME     J26 86
 '@S9S_MB_2U_LIB.S9S_MB_2U(SCH_1):PAGE107_I180@PURE_QUANTA.SCONN288_ADR50017P087CC(CHIPS)':
 'LBD||RSP_A_N': CDS_PINID='\lbd||rsp_a_n\';
NET_NAME
'M_E_CPU1_SB_CA<0>'
 '@S9S_MB_2U_LIB.S9S_MB_2U(SCH_1):M_E_CPU1_SB_CA'<0>:
 C_SIGNAL='@s9s_mb_2u_lib.s9s_mb_2u(sch_1):m_e_cpu1_sb_ca(0)';
NODE_NAME     U1 EG43
 '@S9S_MB_2U_LIB.S9S_MB_2U(SCH_1):PAGE55_I7@PURE_QUANTA.SOCKET4677_AZIF0045P001C01CS(CHIPS)':
 'DDR4_SB_CA0': CDS_PINID='DDR4_SB_CA0';
NODE_NAME     J25 76
 '@S9S_MB_2U_LIB.S9S_MB_2U(SCH_1):PAGE106_I180@PURE_QUANTA.SCONN288_ADR50017P130CC(CHIPS)':
 'CA0_B': CDS_PINID='CA0_B';
NODE_NAME     J26 76
 '@S9S_MB_2U_LIB.S9S_MB_2U(SCH_1):PAGE107_I180@PURE_QUANTA.SCONN288_ADR50017P087CC(CHIPS)':
 'CA0_B': CDS_PINID='CA0_B';
NET_NAME
'M_E_CPU1_SB_CA<1>'
 '@S9S_MB_2U_LIB.S9S_MB_2U(SCH_1):M_E_CPU1_SB_CA'<1>:
 C_SIGNAL='@s9s_mb_2u_lib.s9s_mb_2u(sch_1):m_e_cpu1_sb_ca(1)';
NODE_NAME     U1 EH44
 '@S9S_MB_2U_LIB.S9S_MB_2U(SCH_1):PAGE55_I7@PURE_QUANTA.SOCKET4677_AZIF0045P001C01CS(CHIPS)':
 'DDR4_SB_CA1': CDS_PINID='DDR4_SB_CA1';
NODE_NAME     J25 221
 '@S9S_MB_2U_LIB.S9S_MB_2U(SCH_1):PAGE106_I180@PURE_QUANTA.SCONN288_ADR50017P130CC(CHIPS)':
 'CA1_B': CDS_PINID='CA1_B';
NODE_NAME     J26 221
 '@S9S_MB_2U_LIB.S9S_MB_2U(SCH_1):PAGE107_I180@PURE_QUANTA.SCONN288_ADR50017P087CC(CHIPS)':
 'CA1_B': CDS_PINID='CA1_B';
NET_NAME
'M_E_CPU1_SB_CA<2>'
 '@S9S_MB_2U_LIB.S9S_MB_2U(SCH_1):M_E_CPU1_SB_CA'<2>:
 C_SIGNAL='@s9s_mb_2u_lib.s9s_mb_2u(sch_1):m_e_cpu1_sb_ca(2)';
NODE_NAME     U1 EM44
 '@S9S_MB_2U_LIB.S9S_MB_2U(SCH_1):PAGE55_I7@PURE_QUANTA.SOCKET4677_AZIF0045P001C01CS(CHIPS)':
 'DDR4_SB_CA2': CDS_PINID='DDR4_SB_CA2';
NODE_NAME     J25 78
 '@S9S_MB_2U_LIB.S9S_MB_2U(SCH_1):PAGE106_I180@PURE_QUANTA.SCONN288_ADR50017P130CC(CHIPS)':
 'CA2_B': CDS_PINID='CA2_B';
NODE_NAME     J26 78
 '@S9S_MB_2U_LIB.S9S_MB_2U(SCH_1):PAGE107_I180@PURE_QUANTA.SCONN288_ADR50017P087CC(CHIPS)':
 'CA2_B': CDS_PINID='CA2_B';
NET_NAME
'M_E_CPU1_SB_CA<3>'
 '@S9S_MB_2U_LIB.S9S_MB_2U(SCH_1):M_E_CPU1_SB_CA'<3>:
 C_SIGNAL='@s9s_mb_2u_lib.s9s_mb_2u(sch_1):m_e_cpu1_sb_ca(3)';
NODE_NAME     U1 EP44
 '@S9S_MB_2U_LIB.S9S_MB_2U(SCH_1):PAGE55_I7@PURE_QUANTA.SOCKET4677_AZIF0045P001C01CS(CHIPS)':
 'DDR4_SB_CA3': CDS_PINID='DDR4_SB_CA3';
NODE_NAME     J25 223
 '@S9S_MB_2U_LIB.S9S_MB_2U(SCH_1):PAGE106_I180@PURE_QUANTA.SCONN288_ADR50017P130CC(CHIPS)':
 'CA3_B': CDS_PINID='CA3_B';
NODE_NAME     J26 223
 '@S9S_MB_2U_LIB.S9S_MB_2U(SCH_1):PAGE107_I180@PURE_QUANTA.SCONN288_ADR50017P087CC(CHIPS)':
 'CA3_B': CDS_PINID='CA3_B';
NET_NAME
'M_E_CPU1_SB_CA<4>'
 '@S9S_MB_2U_LIB.S9S_MB_2U(SCH_1):M_E_CPU1_SB_CA'<4>:
 C_SIGNAL='@s9s_mb_2u_lib.s9s_mb_2u(sch_1):m_e_cpu1_sb_ca(4)';
NODE_NAME     U1 EL43
 '@S9S_MB_2U_LIB.S9S_MB_2U(SCH_1):PAGE55_I7@PURE_QUANTA.SOCKET4677_AZIF0045P001C01CS(CHIPS)':
 'DDR4_SB_CA4': CDS_PINID='DDR4_SB_CA4';
NODE_NAME     J25 80
 '@S9S_MB_2U_LIB.S9S_MB_2U(SCH_1):PAGE106_I180@PURE_QUANTA.SCONN288_ADR50017P130CC(CHIPS)':
 'CA4_B': CDS_PINID='CA4_B';
NODE_NAME     J26 80
 '@S9S_MB_2U_LIB.S9S_MB_2U(SCH_1):PAGE107_I180@PURE_QUANTA.SCONN288_ADR50017P087CC(CHIPS)':
 'CA4_B': CDS_PINID='CA4_B';
NET_NAME
'M_E_CPU1_SB_CA<5>'
 '@S9S_MB_2U_LIB.S9S_MB_2U(SCH_1):M_E_CPU1_SB_CA'<5>:
 C_SIGNAL='@s9s_mb_2u_lib.s9s_mb_2u(sch_1):m_e_cpu1_sb_ca(5)';
NODE_NAME     U1 ET42
 '@S9S_MB_2U_LIB.S9S_MB_2U(SCH_1):PAGE55_I7@PURE_QUANTA.SOCKET4677_AZIF0045P001C01CS(CHIPS)':
 'DDR4_SB_CA5': CDS_PINID='DDR4_SB_CA5';
NODE_NAME     J25 225
 '@S9S_MB_2U_LIB.S9S_MB_2U(SCH_1):PAGE106_I180@PURE_QUANTA.SCONN288_ADR50017P130CC(CHIPS)':
 'CA5_B': CDS_PINID='CA5_B';
NODE_NAME     J26 225
 '@S9S_MB_2U_LIB.S9S_MB_2U(SCH_1):PAGE107_I180@PURE_QUANTA.SCONN288_ADR50017P087CC(CHIPS)':
 'CA5_B': CDS_PINID='CA5_B';
NET_NAME
'M_E_CPU1_SB_CA<6>'
 '@S9S_MB_2U_LIB.S9S_MB_2U(SCH_1):M_E_CPU1_SB_CA'<6>:
 C_SIGNAL='@s9s_mb_2u_lib.s9s_mb_2u(sch_1):m_e_cpu1_sb_ca(6)';
NODE_NAME     U1 EK42
 '@S9S_MB_2U_LIB.S9S_MB_2U(SCH_1):PAGE55_I7@PURE_QUANTA.SOCKET4677_AZIF0045P001C01CS(CHIPS)':
 'DDR4_SB_CA6': CDS_PINID='DDR4_SB_CA6';
NODE_NAME     J25 82
 '@S9S_MB_2U_LIB.S9S_MB_2U(SCH_1):PAGE106_I180@PURE_QUANTA.SCONN288_ADR50017P130CC(CHIPS)':
 'CA6_B': CDS_PINID='CA6_B';
NODE_NAME     J26 82
 '@S9S_MB_2U_LIB.S9S_MB_2U(SCH_1):PAGE107_I180@PURE_QUANTA.SCONN288_ADR50017P087CC(CHIPS)':
 'CA6_B': CDS_PINID='CA6_B';
NET_NAME
'M_E_CPU1_SB_CB<0>'
 '@S9S_MB_2U_LIB.S9S_MB_2U(SCH_1):M_E_CPU1_SB_CB'<0>:
 C_SIGNAL='@s9s_mb_2u_lib.s9s_mb_2u(sch_1):m_e_cpu1_sb_cb(0)';
NODE_NAME     U1 EL35
 '@S9S_MB_2U_LIB.S9S_MB_2U(SCH_1):PAGE55_I7@PURE_QUANTA.SOCKET4677_AZIF0045P001C01CS(CHIPS)':
 'DDR4_SB_ECC0': CDS_PINID='DDR4_SB_ECC0';
NODE_NAME     J25 96
 '@S9S_MB_2U_LIB.S9S_MB_2U(SCH_1):PAGE106_I180@PURE_QUANTA.SCONN288_ADR50017P130CC(CHIPS)':
 'CB0_B': CDS_PINID='CB0_B';
NODE_NAME     J26 96
 '@S9S_MB_2U_LIB.S9S_MB_2U(SCH_1):PAGE107_I180@PURE_QUANTA.SCONN288_ADR50017P087CC(CHIPS)':
 'CB0_B': CDS_PINID='CB0_B';
NET_NAME
'M_E_CPU1_SB_CB<1>'
 '@S9S_MB_2U_LIB.S9S_MB_2U(SCH_1):M_E_CPU1_SB_CB'<1>:
 C_SIGNAL='@s9s_mb_2u_lib.s9s_mb_2u(sch_1):m_e_cpu1_sb_cb(1)';
NODE_NAME     U1 EM34
 '@S9S_MB_2U_LIB.S9S_MB_2U(SCH_1):PAGE55_I7@PURE_QUANTA.SOCKET4677_AZIF0045P001C01CS(CHIPS)':
 'DDR4_SB_ECC1': CDS_PINID='DDR4_SB_ECC1';
NODE_NAME     J25 98
 '@S9S_MB_2U_LIB.S9S_MB_2U(SCH_1):PAGE106_I180@PURE_QUANTA.SCONN288_ADR50017P130CC(CHIPS)':
 'CB1_B': CDS_PINID='CB1_B';
NODE_NAME     J26 98
 '@S9S_MB_2U_LIB.S9S_MB_2U(SCH_1):PAGE107_I180@PURE_QUANTA.SCONN288_ADR50017P087CC(CHIPS)':
 'CB1_B': CDS_PINID='CB1_B';
NET_NAME
'M_E_CPU1_SB_CB<2>'
 '@S9S_MB_2U_LIB.S9S_MB_2U(SCH_1):M_E_CPU1_SB_CB'<2>:
 C_SIGNAL='@s9s_mb_2u_lib.s9s_mb_2u(sch_1):m_e_cpu1_sb_cb(2)';
NODE_NAME     U1 ER35
 '@S9S_MB_2U_LIB.S9S_MB_2U(SCH_1):PAGE55_I7@PURE_QUANTA.SOCKET4677_AZIF0045P001C01CS(CHIPS)':
 'DDR4_SB_ECC2': CDS_PINID='DDR4_SB_ECC2';
NODE_NAME     J25 241
 '@S9S_MB_2U_LIB.S9S_MB_2U(SCH_1):PAGE106_I180@PURE_QUANTA.SCONN288_ADR50017P130CC(CHIPS)':
 'CB2_B': CDS_PINID='CB2_B';
NODE_NAME     J26 241
 '@S9S_MB_2U_LIB.S9S_MB_2U(SCH_1):PAGE107_I180@PURE_QUANTA.SCONN288_ADR50017P087CC(CHIPS)':
 'CB2_B': CDS_PINID='CB2_B';
NET_NAME
'M_E_CPU1_SB_CB<3>'
 '@S9S_MB_2U_LIB.S9S_MB_2U(SCH_1):M_E_CPU1_SB_CB'<3>:
 C_SIGNAL='@s9s_mb_2u_lib.s9s_mb_2u(sch_1):m_e_cpu1_sb_cb(3)';
NODE_NAME     U1 EP34
 '@S9S_MB_2U_LIB.S9S_MB_2U(SCH_1):PAGE55_I7@PURE_QUANTA.SOCKET4677_AZIF0045P001C01CS(CHIPS)':
 'DDR4_SB_ECC3': CDS_PINID='DDR4_SB_ECC3';
NODE_NAME     J25 243
 '@S9S_MB_2U_LIB.S9S_MB_2U(SCH_1):PAGE106_I180@PURE_QUANTA.SCONN288_ADR50017P130CC(CHIPS)':
 'CB3_B': CDS_PINID='CB3_B';
NODE_NAME     J26 243
 '@S9S_MB_2U_LIB.S9S_MB_2U(SCH_1):PAGE107_I180@PURE_QUANTA.SCONN288_ADR50017P087CC(CHIPS)':
 'CB3_B': CDS_PINID='CB3_B';
NET_NAME
'M_E_CPU1_SB_CB<4>'
 '@S9S_MB_2U_LIB.S9S_MB_2U(SCH_1):M_E_CPU1_SB_CB'<4>:
 C_SIGNAL='@s9s_mb_2u_lib.s9s_mb_2u(sch_1):m_e_cpu1_sb_cb(4)';
NODE_NAME     U1 EM38
 '@S9S_MB_2U_LIB.S9S_MB_2U(SCH_1):PAGE55_I7@PURE_QUANTA.SOCKET4677_AZIF0045P001C01CS(CHIPS)':
 'DDR4_SB_ECC4': CDS_PINID='DDR4_SB_ECC4';
NODE_NAME     J25 89
 '@S9S_MB_2U_LIB.S9S_MB_2U(SCH_1):PAGE106_I180@PURE_QUANTA.SCONN288_ADR50017P130CC(CHIPS)':
 'CB4_B': CDS_PINID='CB4_B';
NODE_NAME     J26 89
 '@S9S_MB_2U_LIB.S9S_MB_2U(SCH_1):PAGE107_I180@PURE_QUANTA.SCONN288_ADR50017P087CC(CHIPS)':
 'CB4_B': CDS_PINID='CB4_B';
NET_NAME
'M_E_CPU1_SB_CB<5>'
 '@S9S_MB_2U_LIB.S9S_MB_2U(SCH_1):M_E_CPU1_SB_CB'<5>:
 C_SIGNAL='@s9s_mb_2u_lib.s9s_mb_2u(sch_1):m_e_cpu1_sb_cb(5)';
NODE_NAME     U1 EL37
 '@S9S_MB_2U_LIB.S9S_MB_2U(SCH_1):PAGE55_I7@PURE_QUANTA.SOCKET4677_AZIF0045P001C01CS(CHIPS)':
 'DDR4_SB_ECC5': CDS_PINID='DDR4_SB_ECC5';
NODE_NAME     J25 91
 '@S9S_MB_2U_LIB.S9S_MB_2U(SCH_1):PAGE106_I180@PURE_QUANTA.SCONN288_ADR50017P130CC(CHIPS)':
 'CB5_B': CDS_PINID='CB5_B';
NODE_NAME     J26 91
 '@S9S_MB_2U_LIB.S9S_MB_2U(SCH_1):PAGE107_I180@PURE_QUANTA.SCONN288_ADR50017P087CC(CHIPS)':
 'CB5_B': CDS_PINID='CB5_B';
NET_NAME
'M_E_CPU1_SB_CB<6>'
 '@S9S_MB_2U_LIB.S9S_MB_2U(SCH_1):M_E_CPU1_SB_CB'<6>:
 C_SIGNAL='@s9s_mb_2u_lib.s9s_mb_2u(sch_1):m_e_cpu1_sb_cb(6)';
NODE_NAME     U1 EP38
 '@S9S_MB_2U_LIB.S9S_MB_2U(SCH_1):PAGE55_I7@PURE_QUANTA.SOCKET4677_AZIF0045P001C01CS(CHIPS)':
 'DDR4_SB_ECC6': CDS_PINID='DDR4_SB_ECC6';
NODE_NAME     J25 234
 '@S9S_MB_2U_LIB.S9S_MB_2U(SCH_1):PAGE106_I180@PURE_QUANTA.SCONN288_ADR50017P130CC(CHIPS)':
 'CB6_B': CDS_PINID='CB6_B';
NODE_NAME     J26 234
 '@S9S_MB_2U_LIB.S9S_MB_2U(SCH_1):PAGE107_I180@PURE_QUANTA.SCONN288_ADR50017P087CC(CHIPS)':
 'CB6_B': CDS_PINID='CB6_B';
NET_NAME
'M_E_CPU1_SB_CB<7>'
 '@S9S_MB_2U_LIB.S9S_MB_2U(SCH_1):M_E_CPU1_SB_CB'<7>:
 C_SIGNAL='@s9s_mb_2u_lib.s9s_mb_2u(sch_1):m_e_cpu1_sb_cb(7)';
NODE_NAME     U1 ER37
 '@S9S_MB_2U_LIB.S9S_MB_2U(SCH_1):PAGE55_I7@PURE_QUANTA.SOCKET4677_AZIF0045P001C01CS(CHIPS)':
 'DDR4_SB_ECC7': CDS_PINID='DDR4_SB_ECC7';
NODE_NAME     J25 236
 '@S9S_MB_2U_LIB.S9S_MB_2U(SCH_1):PAGE106_I180@PURE_QUANTA.SCONN288_ADR50017P130CC(CHIPS)':
 'CB7_B': CDS_PINID='CB7_B';
NODE_NAME     J26 236
 '@S9S_MB_2U_LIB.S9S_MB_2U(SCH_1):PAGE107_I180@PURE_QUANTA.SCONN288_ADR50017P087CC(CHIPS)':
 'CB7_B': CDS_PINID='CB7_B';
NET_NAME
'M_E_CPU1_SB_CS_N<0>'
 '@S9S_MB_2U_LIB.S9S_MB_2U(SCH_1):M_E_CPU1_SB_CS_N'<0>:
 C_SIGNAL='@s9s_mb_2u_lib.s9s_mb_2u(sch_1):m_e_cpu1_sb_cs_n(0)';
NODE_NAME     U1 EP40
 '@S9S_MB_2U_LIB.S9S_MB_2U(SCH_1):PAGE55_I7@PURE_QUANTA.SOCKET4677_AZIF0045P001C01CS(CHIPS)':
 'DDR4_SB_CS_N0': CDS_PINID='DDR4_SB_CS_N0';
NODE_NAME     J25 84
 '@S9S_MB_2U_LIB.S9S_MB_2U(SCH_1):PAGE106_I180@PURE_QUANTA.SCONN288_ADR50017P130CC(CHIPS)':
 'CS0_B_N': CDS_PINID='CS0_B_N';
NET_NAME
'M_E_CPU1_SB_CS_N<1>'
 '@S9S_MB_2U_LIB.S9S_MB_2U(SCH_1):M_E_CPU1_SB_CS_N'<1>:
 C_SIGNAL='@s9s_mb_2u_lib.s9s_mb_2u(sch_1):m_e_cpu1_sb_cs_n(1)';
NODE_NAME     U1 ET40
 '@S9S_MB_2U_LIB.S9S_MB_2U(SCH_1):PAGE55_I7@PURE_QUANTA.SOCKET4677_AZIF0045P001C01CS(CHIPS)':
 'DDR4_SB_CS_N1': CDS_PINID='DDR4_SB_CS_N1';
NODE_NAME     J25 229
 '@S9S_MB_2U_LIB.S9S_MB_2U(SCH_1):PAGE106_I180@PURE_QUANTA.SCONN288_ADR50017P130CC(CHIPS)':
 'CS1_B_N': CDS_PINID='CS1_B_N';
NET_NAME
'M_E_CPU1_SB_CS_N<2>'
 '@S9S_MB_2U_LIB.S9S_MB_2U(SCH_1):M_E_CPU1_SB_CS_N'<2>:
 C_SIGNAL='@s9s_mb_2u_lib.s9s_mb_2u(sch_1):m_e_cpu1_sb_cs_n(2)';
NODE_NAME     U1 EM40
 '@S9S_MB_2U_LIB.S9S_MB_2U(SCH_1):PAGE55_I7@PURE_QUANTA.SOCKET4677_AZIF0045P001C01CS(CHIPS)':
 'DDR4_SB_CS_N2': CDS_PINID='DDR4_SB_CS_N2';
NODE_NAME     J26 84
 '@S9S_MB_2U_LIB.S9S_MB_2U(SCH_1):PAGE107_I180@PURE_QUANTA.SCONN288_ADR50017P087CC(CHIPS)':
 'CS0_B_N': CDS_PINID='CS0_B_N';
NET_NAME
'M_E_CPU1_SB_CS_N<3>'
 '@S9S_MB_2U_LIB.S9S_MB_2U(SCH_1):M_E_CPU1_SB_CS_N'<3>:
 C_SIGNAL='@s9s_mb_2u_lib.s9s_mb_2u(sch_1):m_e_cpu1_sb_cs_n(3)';
NODE_NAME     U1 EL41
 '@S9S_MB_2U_LIB.S9S_MB_2U(SCH_1):PAGE55_I7@PURE_QUANTA.SOCKET4677_AZIF0045P001C01CS(CHIPS)':
 'DDR4_SB_CS_N3': CDS_PINID='DDR4_SB_CS_N3';
NODE_NAME     J26 229
 '@S9S_MB_2U_LIB.S9S_MB_2U(SCH_1):PAGE107_I180@PURE_QUANTA.SCONN288_ADR50017P087CC(CHIPS)':
 'CS1_B_N': CDS_PINID='CS1_B_N';
NET_NAME
'M_E_CPU1_SB_DQ<0>'
 '@S9S_MB_2U_LIB.S9S_MB_2U(SCH_1):M_E_CPU1_SB_DQ'<0>:
 C_SIGNAL='@s9s_mb_2u_lib.s9s_mb_2u(sch_1):m_e_cpu1_sb_dq(0)';
NODE_NAME     U1 EE29
 '@S9S_MB_2U_LIB.S9S_MB_2U(SCH_1):PAGE55_I7@PURE_QUANTA.SOCKET4677_AZIF0045P001C01CS(CHIPS)':
 'DDR4_SB_DQ0': CDS_PINID='DDR4_SB_DQ0';
NODE_NAME     J25 100
 '@S9S_MB_2U_LIB.S9S_MB_2U(SCH_1):PAGE106_I180@PURE_QUANTA.SCONN288_ADR50017P130CC(CHIPS)':
 'DQ0_B': CDS_PINID='DQ0_B';
NODE_NAME     J26 100
 '@S9S_MB_2U_LIB.S9S_MB_2U(SCH_1):PAGE107_I180@PURE_QUANTA.SCONN288_ADR50017P087CC(CHIPS)':
 'DQ0_B': CDS_PINID='DQ0_B';
NET_NAME
'M_E_CPU1_SB_DQ<10>'
 '@S9S_MB_2U_LIB.S9S_MB_2U(SCH_1):M_E_CPU1_SB_DQ'<10>:
 C_SIGNAL='@s9s_mb_2u_lib.s9s_mb_2u(sch_1):m_e_cpu1_sb_dq(10)';
NODE_NAME     U1 EP32
 '@S9S_MB_2U_LIB.S9S_MB_2U(SCH_1):PAGE55_I7@PURE_QUANTA.SOCKET4677_AZIF0045P001C01CS(CHIPS)':
 'DDR4_SB_DQ10': CDS_PINID='DDR4_SB_DQ10';
NODE_NAME     J25 256
 '@S9S_MB_2U_LIB.S9S_MB_2U(SCH_1):PAGE106_I180@PURE_QUANTA.SCONN288_ADR50017P130CC(CHIPS)':
 'DQ10_B': CDS_PINID='DQ10_B';
NODE_NAME     J26 256
 '@S9S_MB_2U_LIB.S9S_MB_2U(SCH_1):PAGE107_I180@PURE_QUANTA.SCONN288_ADR50017P087CC(CHIPS)':
 'DQ10_B': CDS_PINID='DQ10_B';
NET_NAME
'M_E_CPU1_SB_DQ<11>'
 '@S9S_MB_2U_LIB.S9S_MB_2U(SCH_1):M_E_CPU1_SB_DQ'<11>:
 C_SIGNAL='@s9s_mb_2u_lib.s9s_mb_2u(sch_1):m_e_cpu1_sb_dq(11)';
NODE_NAME     U1 ER31
 '@S9S_MB_2U_LIB.S9S_MB_2U(SCH_1):PAGE55_I7@PURE_QUANTA.SOCKET4677_AZIF0045P001C01CS(CHIPS)':
 'DDR4_SB_DQ11': CDS_PINID='DDR4_SB_DQ11';
NODE_NAME     J25 258
 '@S9S_MB_2U_LIB.S9S_MB_2U(SCH_1):PAGE106_I180@PURE_QUANTA.SCONN288_ADR50017P130CC(CHIPS)':
 'DQ11_B': CDS_PINID='DQ11_B';
NODE_NAME     J26 258
 '@S9S_MB_2U_LIB.S9S_MB_2U(SCH_1):PAGE107_I180@PURE_QUANTA.SCONN288_ADR50017P087CC(CHIPS)':
 'DQ11_B': CDS_PINID='DQ11_B';
NET_NAME
'M_E_CPU1_SB_DQ<12>'
 '@S9S_MB_2U_LIB.S9S_MB_2U(SCH_1):M_E_CPU1_SB_DQ'<12>:
 C_SIGNAL='@s9s_mb_2u_lib.s9s_mb_2u(sch_1):m_e_cpu1_sb_dq(12)';
NODE_NAME     U1 EL29
 '@S9S_MB_2U_LIB.S9S_MB_2U(SCH_1):PAGE55_I7@PURE_QUANTA.SOCKET4677_AZIF0045P001C01CS(CHIPS)':
 'DDR4_SB_DQ12': CDS_PINID='DDR4_SB_DQ12';
NODE_NAME     J25 118
 '@S9S_MB_2U_LIB.S9S_MB_2U(SCH_1):PAGE106_I180@PURE_QUANTA.SCONN288_ADR50017P130CC(CHIPS)':
 'DQ12_B': CDS_PINID='DQ12_B';
NODE_NAME     J26 118
 '@S9S_MB_2U_LIB.S9S_MB_2U(SCH_1):PAGE107_I180@PURE_QUANTA.SCONN288_ADR50017P087CC(CHIPS)':
 'DQ12_B': CDS_PINID='DQ12_B';
NET_NAME
'M_E_CPU1_SB_DQ<13>'
 '@S9S_MB_2U_LIB.S9S_MB_2U(SCH_1):M_E_CPU1_SB_DQ'<13>:
 C_SIGNAL='@s9s_mb_2u_lib.s9s_mb_2u(sch_1):m_e_cpu1_sb_dq(13)';
NODE_NAME     U1 EM28
 '@S9S_MB_2U_LIB.S9S_MB_2U(SCH_1):PAGE55_I7@PURE_QUANTA.SOCKET4677_AZIF0045P001C01CS(CHIPS)':
 'DDR4_SB_DQ13': CDS_PINID='DDR4_SB_DQ13';
NODE_NAME     J25 120
 '@S9S_MB_2U_LIB.S9S_MB_2U(SCH_1):PAGE106_I180@PURE_QUANTA.SCONN288_ADR50017P130CC(CHIPS)':
 'DQ13_B': CDS_PINID='DQ13_B';
NODE_NAME     J26 120
 '@S9S_MB_2U_LIB.S9S_MB_2U(SCH_1):PAGE107_I180@PURE_QUANTA.SCONN288_ADR50017P087CC(CHIPS)':
 'DQ13_B': CDS_PINID='DQ13_B';
NET_NAME
'M_E_CPU1_SB_DQ<14>'
 '@S9S_MB_2U_LIB.S9S_MB_2U(SCH_1):M_E_CPU1_SB_DQ'<14>:
 C_SIGNAL='@s9s_mb_2u_lib.s9s_mb_2u(sch_1):m_e_cpu1_sb_dq(14)';
NODE_NAME     U1 ER29
 '@S9S_MB_2U_LIB.S9S_MB_2U(SCH_1):PAGE55_I7@PURE_QUANTA.SOCKET4677_AZIF0045P001C01CS(CHIPS)':
 'DDR4_SB_DQ14': CDS_PINID='DDR4_SB_DQ14';
NODE_NAME     J25 263
 '@S9S_MB_2U_LIB.S9S_MB_2U(SCH_1):PAGE106_I180@PURE_QUANTA.SCONN288_ADR50017P130CC(CHIPS)':
 'DQ14_B': CDS_PINID='DQ14_B';
NODE_NAME     J26 263
 '@S9S_MB_2U_LIB.S9S_MB_2U(SCH_1):PAGE107_I180@PURE_QUANTA.SCONN288_ADR50017P087CC(CHIPS)':
 'DQ14_B': CDS_PINID='DQ14_B';
NET_NAME
'M_E_CPU1_SB_DQ<15>'
 '@S9S_MB_2U_LIB.S9S_MB_2U(SCH_1):M_E_CPU1_SB_DQ'<15>:
 C_SIGNAL='@s9s_mb_2u_lib.s9s_mb_2u(sch_1):m_e_cpu1_sb_dq(15)';
NODE_NAME     U1 EP28
 '@S9S_MB_2U_LIB.S9S_MB_2U(SCH_1):PAGE55_I7@PURE_QUANTA.SOCKET4677_AZIF0045P001C01CS(CHIPS)':
 'DDR4_SB_DQ15': CDS_PINID='DDR4_SB_DQ15';
NODE_NAME     J25 265
 '@S9S_MB_2U_LIB.S9S_MB_2U(SCH_1):PAGE106_I180@PURE_QUANTA.SCONN288_ADR50017P130CC(CHIPS)':
 'DQ15_B': CDS_PINID='DQ15_B';
NODE_NAME     J26 265
 '@S9S_MB_2U_LIB.S9S_MB_2U(SCH_1):PAGE107_I180@PURE_QUANTA.SCONN288_ADR50017P087CC(CHIPS)':
 'DQ15_B': CDS_PINID='DQ15_B';
NET_NAME
'M_E_CPU1_SB_DQ<16>'
 '@S9S_MB_2U_LIB.S9S_MB_2U(SCH_1):M_E_CPU1_SB_DQ'<16>:
 C_SIGNAL='@s9s_mb_2u_lib.s9s_mb_2u(sch_1):m_e_cpu1_sb_dq(16)';
NODE_NAME     U1 EM26
 '@S9S_MB_2U_LIB.S9S_MB_2U(SCH_1):PAGE55_I7@PURE_QUANTA.SOCKET4677_AZIF0045P001C01CS(CHIPS)':
 'DDR4_SB_DQ16': CDS_PINID='DDR4_SB_DQ16';
NODE_NAME     J25 122
 '@S9S_MB_2U_LIB.S9S_MB_2U(SCH_1):PAGE106_I180@PURE_QUANTA.SCONN288_ADR50017P130CC(CHIPS)':
 'DQ16_B': CDS_PINID='DQ16_B';
NODE_NAME     J26 122
 '@S9S_MB_2U_LIB.S9S_MB_2U(SCH_1):PAGE107_I180@PURE_QUANTA.SCONN288_ADR50017P087CC(CHIPS)':
 'DQ16_B': CDS_PINID='DQ16_B';
NET_NAME
'M_E_CPU1_SB_DQ<17>'
 '@S9S_MB_2U_LIB.S9S_MB_2U(SCH_1):M_E_CPU1_SB_DQ'<17>:
 C_SIGNAL='@s9s_mb_2u_lib.s9s_mb_2u(sch_1):m_e_cpu1_sb_dq(17)';
NODE_NAME     U1 EL25
 '@S9S_MB_2U_LIB.S9S_MB_2U(SCH_1):PAGE55_I7@PURE_QUANTA.SOCKET4677_AZIF0045P001C01CS(CHIPS)':
 'DDR4_SB_DQ17': CDS_PINID='DDR4_SB_DQ17';
NODE_NAME     J25 124
 '@S9S_MB_2U_LIB.S9S_MB_2U(SCH_1):PAGE106_I180@PURE_QUANTA.SCONN288_ADR50017P130CC(CHIPS)':
 'DQ17_B': CDS_PINID='DQ17_B';
NODE_NAME     J26 124
 '@S9S_MB_2U_LIB.S9S_MB_2U(SCH_1):PAGE107_I180@PURE_QUANTA.SCONN288_ADR50017P087CC(CHIPS)':
 'DQ17_B': CDS_PINID='DQ17_B';
NET_NAME
'M_E_CPU1_SB_DQ<18>'
 '@S9S_MB_2U_LIB.S9S_MB_2U(SCH_1):M_E_CPU1_SB_DQ'<18>:
 C_SIGNAL='@s9s_mb_2u_lib.s9s_mb_2u(sch_1):m_e_cpu1_sb_dq(18)';
NODE_NAME     U1 EP26
 '@S9S_MB_2U_LIB.S9S_MB_2U(SCH_1):PAGE55_I7@PURE_QUANTA.SOCKET4677_AZIF0045P001C01CS(CHIPS)':
 'DDR4_SB_DQ18': CDS_PINID='DDR4_SB_DQ18';
NODE_NAME     J25 267
 '@S9S_MB_2U_LIB.S9S_MB_2U(SCH_1):PAGE106_I180@PURE_QUANTA.SCONN288_ADR50017P130CC(CHIPS)':
 'DQ18_B': CDS_PINID='DQ18_B';
NODE_NAME     J26 267
 '@S9S_MB_2U_LIB.S9S_MB_2U(SCH_1):PAGE107_I180@PURE_QUANTA.SCONN288_ADR50017P087CC(CHIPS)':
 'DQ18_B': CDS_PINID='DQ18_B';
NET_NAME
'M_E_CPU1_SB_DQ<19>'
 '@S9S_MB_2U_LIB.S9S_MB_2U(SCH_1):M_E_CPU1_SB_DQ'<19>:
 C_SIGNAL='@s9s_mb_2u_lib.s9s_mb_2u(sch_1):m_e_cpu1_sb_dq(19)';
NODE_NAME     U1 ER25
 '@S9S_MB_2U_LIB.S9S_MB_2U(SCH_1):PAGE55_I7@PURE_QUANTA.SOCKET4677_AZIF0045P001C01CS(CHIPS)':
 'DDR4_SB_DQ19': CDS_PINID='DDR4_SB_DQ19';
NODE_NAME     J25 269
 '@S9S_MB_2U_LIB.S9S_MB_2U(SCH_1):PAGE106_I180@PURE_QUANTA.SCONN288_ADR50017P130CC(CHIPS)':
 'DQ19_B': CDS_PINID='DQ19_B';
NODE_NAME     J26 269
 '@S9S_MB_2U_LIB.S9S_MB_2U(SCH_1):PAGE107_I180@PURE_QUANTA.SCONN288_ADR50017P087CC(CHIPS)':
 'DQ19_B': CDS_PINID='DQ19_B';
NET_NAME
'M_E_CPU1_SB_DQ<1>'
 '@S9S_MB_2U_LIB.S9S_MB_2U(SCH_1):M_E_CPU1_SB_DQ'<1>:
 C_SIGNAL='@s9s_mb_2u_lib.s9s_mb_2u(sch_1):m_e_cpu1_sb_dq(1)';
NODE_NAME     U1 ED28
 '@S9S_MB_2U_LIB.S9S_MB_2U(SCH_1):PAGE55_I7@PURE_QUANTA.SOCKET4677_AZIF0045P001C01CS(CHIPS)':
 'DDR4_SB_DQ1': CDS_PINID='DDR4_SB_DQ1';
NODE_NAME     J25 102
 '@S9S_MB_2U_LIB.S9S_MB_2U(SCH_1):PAGE106_I180@PURE_QUANTA.SCONN288_ADR50017P130CC(CHIPS)':
 'DQ1_B': CDS_PINID='DQ1_B';
NODE_NAME     J26 102
 '@S9S_MB_2U_LIB.S9S_MB_2U(SCH_1):PAGE107_I180@PURE_QUANTA.SCONN288_ADR50017P087CC(CHIPS)':
 'DQ1_B': CDS_PINID='DQ1_B';
NET_NAME
'M_E_CPU1_SB_DQ<20>'
 '@S9S_MB_2U_LIB.S9S_MB_2U(SCH_1):M_E_CPU1_SB_DQ'<20>:
 C_SIGNAL='@s9s_mb_2u_lib.s9s_mb_2u(sch_1):m_e_cpu1_sb_dq(20)';
NODE_NAME     U1 EL23
 '@S9S_MB_2U_LIB.S9S_MB_2U(SCH_1):PAGE55_I7@PURE_QUANTA.SOCKET4677_AZIF0045P001C01CS(CHIPS)':
 'DDR4_SB_DQ20': CDS_PINID='DDR4_SB_DQ20';
NODE_NAME     J25 129
 '@S9S_MB_2U_LIB.S9S_MB_2U(SCH_1):PAGE106_I180@PURE_QUANTA.SCONN288_ADR50017P130CC(CHIPS)':
 'DQ20_B': CDS_PINID='DQ20_B';
NODE_NAME     J26 129
 '@S9S_MB_2U_LIB.S9S_MB_2U(SCH_1):PAGE107_I180@PURE_QUANTA.SCONN288_ADR50017P087CC(CHIPS)':
 'DQ20_B': CDS_PINID='DQ20_B';
NET_NAME
'M_E_CPU1_SB_DQ<21>'
 '@S9S_MB_2U_LIB.S9S_MB_2U(SCH_1):M_E_CPU1_SB_DQ'<21>:
 C_SIGNAL='@s9s_mb_2u_lib.s9s_mb_2u(sch_1):m_e_cpu1_sb_dq(21)';
NODE_NAME     U1 EM22
 '@S9S_MB_2U_LIB.S9S_MB_2U(SCH_1):PAGE55_I7@PURE_QUANTA.SOCKET4677_AZIF0045P001C01CS(CHIPS)':
 'DDR4_SB_DQ21': CDS_PINID='DDR4_SB_DQ21';
NODE_NAME     J25 131
 '@S9S_MB_2U_LIB.S9S_MB_2U(SCH_1):PAGE106_I180@PURE_QUANTA.SCONN288_ADR50017P130CC(CHIPS)':
 'DQ21_B': CDS_PINID='DQ21_B';
NODE_NAME     J26 131
 '@S9S_MB_2U_LIB.S9S_MB_2U(SCH_1):PAGE107_I180@PURE_QUANTA.SCONN288_ADR50017P087CC(CHIPS)':
 'DQ21_B': CDS_PINID='DQ21_B';
NET_NAME
'M_E_CPU1_SB_DQ<22>'
 '@S9S_MB_2U_LIB.S9S_MB_2U(SCH_1):M_E_CPU1_SB_DQ'<22>:
 C_SIGNAL='@s9s_mb_2u_lib.s9s_mb_2u(sch_1):m_e_cpu1_sb_dq(22)';
NODE_NAME     U1 ER23
 '@S9S_MB_2U_LIB.S9S_MB_2U(SCH_1):PAGE55_I7@PURE_QUANTA.SOCKET4677_AZIF0045P001C01CS(CHIPS)':
 'DDR4_SB_DQ22': CDS_PINID='DDR4_SB_DQ22';
NODE_NAME     J25 274
 '@S9S_MB_2U_LIB.S9S_MB_2U(SCH_1):PAGE106_I180@PURE_QUANTA.SCONN288_ADR50017P130CC(CHIPS)':
 'DQ22_B': CDS_PINID='DQ22_B';
NODE_NAME     J26 274
 '@S9S_MB_2U_LIB.S9S_MB_2U(SCH_1):PAGE107_I180@PURE_QUANTA.SCONN288_ADR50017P087CC(CHIPS)':
 'DQ22_B': CDS_PINID='DQ22_B';
NET_NAME
'M_E_CPU1_SB_DQ<23>'
 '@S9S_MB_2U_LIB.S9S_MB_2U(SCH_1):M_E_CPU1_SB_DQ'<23>:
 C_SIGNAL='@s9s_mb_2u_lib.s9s_mb_2u(sch_1):m_e_cpu1_sb_dq(23)';
NODE_NAME     U1 EP22
 '@S9S_MB_2U_LIB.S9S_MB_2U(SCH_1):PAGE55_I7@PURE_QUANTA.SOCKET4677_AZIF0045P001C01CS(CHIPS)':
 'DDR4_SB_DQ23': CDS_PINID='DDR4_SB_DQ23';
NODE_NAME     J25 276
 '@S9S_MB_2U_LIB.S9S_MB_2U(SCH_1):PAGE106_I180@PURE_QUANTA.SCONN288_ADR50017P130CC(CHIPS)':
 'DQ23_B': CDS_PINID='DQ23_B';
NODE_NAME     J26 276
 '@S9S_MB_2U_LIB.S9S_MB_2U(SCH_1):PAGE107_I180@PURE_QUANTA.SCONN288_ADR50017P087CC(CHIPS)':
 'DQ23_B': CDS_PINID='DQ23_B';
NET_NAME
'M_E_CPU1_SB_DQ<24>'
 '@S9S_MB_2U_LIB.S9S_MB_2U(SCH_1):M_E_CPU1_SB_DQ'<24>:
 C_SIGNAL='@s9s_mb_2u_lib.s9s_mb_2u(sch_1):m_e_cpu1_sb_dq(24)';
NODE_NAME     U1 EM20
 '@S9S_MB_2U_LIB.S9S_MB_2U(SCH_1):PAGE55_I7@PURE_QUANTA.SOCKET4677_AZIF0045P001C01CS(CHIPS)':
 'DDR4_SB_DQ24': CDS_PINID='DDR4_SB_DQ24';
NODE_NAME     J25 133
 '@S9S_MB_2U_LIB.S9S_MB_2U(SCH_1):PAGE106_I180@PURE_QUANTA.SCONN288_ADR50017P130CC(CHIPS)':
 'DQ24_B': CDS_PINID='DQ24_B';
NODE_NAME     J26 133
 '@S9S_MB_2U_LIB.S9S_MB_2U(SCH_1):PAGE107_I180@PURE_QUANTA.SCONN288_ADR50017P087CC(CHIPS)':
 'DQ24_B': CDS_PINID='DQ24_B';
NET_NAME
'M_E_CPU1_SB_DQ<25>'
 '@S9S_MB_2U_LIB.S9S_MB_2U(SCH_1):M_E_CPU1_SB_DQ'<25>:
 C_SIGNAL='@s9s_mb_2u_lib.s9s_mb_2u(sch_1):m_e_cpu1_sb_dq(25)';
NODE_NAME     U1 EL19
 '@S9S_MB_2U_LIB.S9S_MB_2U(SCH_1):PAGE55_I7@PURE_QUANTA.SOCKET4677_AZIF0045P001C01CS(CHIPS)':
 'DDR4_SB_DQ25': CDS_PINID='DDR4_SB_DQ25';
NODE_NAME     J25 135
 '@S9S_MB_2U_LIB.S9S_MB_2U(SCH_1):PAGE106_I180@PURE_QUANTA.SCONN288_ADR50017P130CC(CHIPS)':
 'DQ25_B': CDS_PINID='DQ25_B';
NODE_NAME     J26 135
 '@S9S_MB_2U_LIB.S9S_MB_2U(SCH_1):PAGE107_I180@PURE_QUANTA.SCONN288_ADR50017P087CC(CHIPS)':
 'DQ25_B': CDS_PINID='DQ25_B';
NET_NAME
'M_E_CPU1_SB_DQ<26>'
 '@S9S_MB_2U_LIB.S9S_MB_2U(SCH_1):M_E_CPU1_SB_DQ'<26>:
 C_SIGNAL='@s9s_mb_2u_lib.s9s_mb_2u(sch_1):m_e_cpu1_sb_dq(26)';
NODE_NAME     U1 EP20
 '@S9S_MB_2U_LIB.S9S_MB_2U(SCH_1):PAGE55_I7@PURE_QUANTA.SOCKET4677_AZIF0045P001C01CS(CHIPS)':
 'DDR4_SB_DQ26': CDS_PINID='DDR4_SB_DQ26';
NODE_NAME     J25 278
 '@S9S_MB_2U_LIB.S9S_MB_2U(SCH_1):PAGE106_I180@PURE_QUANTA.SCONN288_ADR50017P130CC(CHIPS)':
 'DQ26_B': CDS_PINID='DQ26_B';
NODE_NAME     J26 278
 '@S9S_MB_2U_LIB.S9S_MB_2U(SCH_1):PAGE107_I180@PURE_QUANTA.SCONN288_ADR50017P087CC(CHIPS)':
 'DQ26_B': CDS_PINID='DQ26_B';
NET_NAME
'M_E_CPU1_SB_DQ<27>'
 '@S9S_MB_2U_LIB.S9S_MB_2U(SCH_1):M_E_CPU1_SB_DQ'<27>:
 C_SIGNAL='@s9s_mb_2u_lib.s9s_mb_2u(sch_1):m_e_cpu1_sb_dq(27)';
NODE_NAME     U1 ER19
 '@S9S_MB_2U_LIB.S9S_MB_2U(SCH_1):PAGE55_I7@PURE_QUANTA.SOCKET4677_AZIF0045P001C01CS(CHIPS)':
 'DDR4_SB_DQ27': CDS_PINID='DDR4_SB_DQ27';
NODE_NAME     J25 280
 '@S9S_MB_2U_LIB.S9S_MB_2U(SCH_1):PAGE106_I180@PURE_QUANTA.SCONN288_ADR50017P130CC(CHIPS)':
 'DQ27_B': CDS_PINID='DQ27_B';
NODE_NAME     J26 280
 '@S9S_MB_2U_LIB.S9S_MB_2U(SCH_1):PAGE107_I180@PURE_QUANTA.SCONN288_ADR50017P087CC(CHIPS)':
 'DQ27_B': CDS_PINID='DQ27_B';
NET_NAME
'M_E_CPU1_SB_DQ<28>'
 '@S9S_MB_2U_LIB.S9S_MB_2U(SCH_1):M_E_CPU1_SB_DQ'<28>:
 C_SIGNAL='@s9s_mb_2u_lib.s9s_mb_2u(sch_1):m_e_cpu1_sb_dq(28)';
NODE_NAME     U1 EL17
 '@S9S_MB_2U_LIB.S9S_MB_2U(SCH_1):PAGE55_I7@PURE_QUANTA.SOCKET4677_AZIF0045P001C01CS(CHIPS)':
 'DDR4_SB_DQ28': CDS_PINID='DDR4_SB_DQ28';
NODE_NAME     J25 140
 '@S9S_MB_2U_LIB.S9S_MB_2U(SCH_1):PAGE106_I180@PURE_QUANTA.SCONN288_ADR50017P130CC(CHIPS)':
 'DQ28_B': CDS_PINID='DQ28_B';
NODE_NAME     J26 140
 '@S9S_MB_2U_LIB.S9S_MB_2U(SCH_1):PAGE107_I180@PURE_QUANTA.SCONN288_ADR50017P087CC(CHIPS)':
 'DQ28_B': CDS_PINID='DQ28_B';
NET_NAME
'M_E_CPU1_SB_DQ<29>'
 '@S9S_MB_2U_LIB.S9S_MB_2U(SCH_1):M_E_CPU1_SB_DQ'<29>:
 C_SIGNAL='@s9s_mb_2u_lib.s9s_mb_2u(sch_1):m_e_cpu1_sb_dq(29)';
NODE_NAME     U1 EM16
 '@S9S_MB_2U_LIB.S9S_MB_2U(SCH_1):PAGE55_I7@PURE_QUANTA.SOCKET4677_AZIF0045P001C01CS(CHIPS)':
 'DDR4_SB_DQ29': CDS_PINID='DDR4_SB_DQ29';
NODE_NAME     J25 142
 '@S9S_MB_2U_LIB.S9S_MB_2U(SCH_1):PAGE106_I180@PURE_QUANTA.SCONN288_ADR50017P130CC(CHIPS)':
 'DQ29_B': CDS_PINID='DQ29_B';
NODE_NAME     J26 142
 '@S9S_MB_2U_LIB.S9S_MB_2U(SCH_1):PAGE107_I180@PURE_QUANTA.SCONN288_ADR50017P087CC(CHIPS)':
 'DQ29_B': CDS_PINID='DQ29_B';
NET_NAME
'M_E_CPU1_SB_DQ<2>'
 '@S9S_MB_2U_LIB.S9S_MB_2U(SCH_1):M_E_CPU1_SB_DQ'<2>:
 C_SIGNAL='@s9s_mb_2u_lib.s9s_mb_2u(sch_1):m_e_cpu1_sb_dq(2)';
NODE_NAME     U1 EG29
 '@S9S_MB_2U_LIB.S9S_MB_2U(SCH_1):PAGE55_I7@PURE_QUANTA.SOCKET4677_AZIF0045P001C01CS(CHIPS)':
 'DDR4_SB_DQ2': CDS_PINID='DDR4_SB_DQ2';
NODE_NAME     J25 245
 '@S9S_MB_2U_LIB.S9S_MB_2U(SCH_1):PAGE106_I180@PURE_QUANTA.SCONN288_ADR50017P130CC(CHIPS)':
 'DQ2_B': CDS_PINID='DQ2_B';
NODE_NAME     J26 245
 '@S9S_MB_2U_LIB.S9S_MB_2U(SCH_1):PAGE107_I180@PURE_QUANTA.SCONN288_ADR50017P087CC(CHIPS)':
 'DQ2_B': CDS_PINID='DQ2_B';
NET_NAME
'M_E_CPU1_SB_DQ<30>'
 '@S9S_MB_2U_LIB.S9S_MB_2U(SCH_1):M_E_CPU1_SB_DQ'<30>:
 C_SIGNAL='@s9s_mb_2u_lib.s9s_mb_2u(sch_1):m_e_cpu1_sb_dq(30)';
NODE_NAME     U1 ER17
 '@S9S_MB_2U_LIB.S9S_MB_2U(SCH_1):PAGE55_I7@PURE_QUANTA.SOCKET4677_AZIF0045P001C01CS(CHIPS)':
 'DDR4_SB_DQ30': CDS_PINID='DDR4_SB_DQ30';
NODE_NAME     J25 285
 '@S9S_MB_2U_LIB.S9S_MB_2U(SCH_1):PAGE106_I180@PURE_QUANTA.SCONN288_ADR50017P130CC(CHIPS)':
 'DQ30_B': CDS_PINID='DQ30_B';
NODE_NAME     J26 285
 '@S9S_MB_2U_LIB.S9S_MB_2U(SCH_1):PAGE107_I180@PURE_QUANTA.SCONN288_ADR50017P087CC(CHIPS)':
 'DQ30_B': CDS_PINID='DQ30_B';
NET_NAME
'M_E_CPU1_SB_DQ<31>'
 '@S9S_MB_2U_LIB.S9S_MB_2U(SCH_1):M_E_CPU1_SB_DQ'<31>:
 C_SIGNAL='@s9s_mb_2u_lib.s9s_mb_2u(sch_1):m_e_cpu1_sb_dq(31)';
NODE_NAME     U1 EP16
 '@S9S_MB_2U_LIB.S9S_MB_2U(SCH_1):PAGE55_I7@PURE_QUANTA.SOCKET4677_AZIF0045P001C01CS(CHIPS)':
 'DDR4_SB_DQ31': CDS_PINID='DDR4_SB_DQ31';
NODE_NAME     J25 287
 '@S9S_MB_2U_LIB.S9S_MB_2U(SCH_1):PAGE106_I180@PURE_QUANTA.SCONN288_ADR50017P130CC(CHIPS)':
 'DQ31_B': CDS_PINID='DQ31_B';
NODE_NAME     J26 287
 '@S9S_MB_2U_LIB.S9S_MB_2U(SCH_1):PAGE107_I180@PURE_QUANTA.SCONN288_ADR50017P087CC(CHIPS)':
 'DQ31_B': CDS_PINID='DQ31_B';
NET_NAME
'M_E_CPU1_SB_DQ<3>'
 '@S9S_MB_2U_LIB.S9S_MB_2U(SCH_1):M_E_CPU1_SB_DQ'<3>:
 C_SIGNAL='@s9s_mb_2u_lib.s9s_mb_2u(sch_1):m_e_cpu1_sb_dq(3)';
NODE_NAME     U1 EH28
 '@S9S_MB_2U_LIB.S9S_MB_2U(SCH_1):PAGE55_I7@PURE_QUANTA.SOCKET4677_AZIF0045P001C01CS(CHIPS)':
 'DDR4_SB_DQ3': CDS_PINID='DDR4_SB_DQ3';
NODE_NAME     J25 247
 '@S9S_MB_2U_LIB.S9S_MB_2U(SCH_1):PAGE106_I180@PURE_QUANTA.SCONN288_ADR50017P130CC(CHIPS)':
 'DQ3_B': CDS_PINID='DQ3_B';
NODE_NAME     J26 247
 '@S9S_MB_2U_LIB.S9S_MB_2U(SCH_1):PAGE107_I180@PURE_QUANTA.SCONN288_ADR50017P087CC(CHIPS)':
 'DQ3_B': CDS_PINID='DQ3_B';
NET_NAME
'M_E_CPU1_SB_DQ<4>'
 '@S9S_MB_2U_LIB.S9S_MB_2U(SCH_1):M_E_CPU1_SB_DQ'<4>:
 C_SIGNAL='@s9s_mb_2u_lib.s9s_mb_2u(sch_1):m_e_cpu1_sb_dq(4)';
NODE_NAME     U1 ED26
 '@S9S_MB_2U_LIB.S9S_MB_2U(SCH_1):PAGE55_I7@PURE_QUANTA.SOCKET4677_AZIF0045P001C01CS(CHIPS)':
 'DDR4_SB_DQ4': CDS_PINID='DDR4_SB_DQ4';
NODE_NAME     J25 107
 '@S9S_MB_2U_LIB.S9S_MB_2U(SCH_1):PAGE106_I180@PURE_QUANTA.SCONN288_ADR50017P130CC(CHIPS)':
 'DQ4_B': CDS_PINID='DQ4_B';
NODE_NAME     J26 107
 '@S9S_MB_2U_LIB.S9S_MB_2U(SCH_1):PAGE107_I180@PURE_QUANTA.SCONN288_ADR50017P087CC(CHIPS)':
 'DQ4_B': CDS_PINID='DQ4_B';
NET_NAME
'M_E_CPU1_SB_DQ<5>'
 '@S9S_MB_2U_LIB.S9S_MB_2U(SCH_1):M_E_CPU1_SB_DQ'<5>:
 C_SIGNAL='@s9s_mb_2u_lib.s9s_mb_2u(sch_1):m_e_cpu1_sb_dq(5)';
NODE_NAME     U1 EE25
 '@S9S_MB_2U_LIB.S9S_MB_2U(SCH_1):PAGE55_I7@PURE_QUANTA.SOCKET4677_AZIF0045P001C01CS(CHIPS)':
 'DDR4_SB_DQ5': CDS_PINID='DDR4_SB_DQ5';
NODE_NAME     J25 109
 '@S9S_MB_2U_LIB.S9S_MB_2U(SCH_1):PAGE106_I180@PURE_QUANTA.SCONN288_ADR50017P130CC(CHIPS)':
 'DQ5_B': CDS_PINID='DQ5_B';
NODE_NAME     J26 109
 '@S9S_MB_2U_LIB.S9S_MB_2U(SCH_1):PAGE107_I180@PURE_QUANTA.SCONN288_ADR50017P087CC(CHIPS)':
 'DQ5_B': CDS_PINID='DQ5_B';
NET_NAME
'M_E_CPU1_SB_DQ<6>'
 '@S9S_MB_2U_LIB.S9S_MB_2U(SCH_1):M_E_CPU1_SB_DQ'<6>:
 C_SIGNAL='@s9s_mb_2u_lib.s9s_mb_2u(sch_1):m_e_cpu1_sb_dq(6)';
NODE_NAME     U1 EH26
 '@S9S_MB_2U_LIB.S9S_MB_2U(SCH_1):PAGE55_I7@PURE_QUANTA.SOCKET4677_AZIF0045P001C01CS(CHIPS)':
 'DDR4_SB_DQ6': CDS_PINID='DDR4_SB_DQ6';
NODE_NAME     J25 252
 '@S9S_MB_2U_LIB.S9S_MB_2U(SCH_1):PAGE106_I180@PURE_QUANTA.SCONN288_ADR50017P130CC(CHIPS)':
 'DQ6_B': CDS_PINID='DQ6_B';
NODE_NAME     J26 252
 '@S9S_MB_2U_LIB.S9S_MB_2U(SCH_1):PAGE107_I180@PURE_QUANTA.SCONN288_ADR50017P087CC(CHIPS)':
 'DQ6_B': CDS_PINID='DQ6_B';
NET_NAME
'M_E_CPU1_SB_DQ<7>'
 '@S9S_MB_2U_LIB.S9S_MB_2U(SCH_1):M_E_CPU1_SB_DQ'<7>:
 C_SIGNAL='@s9s_mb_2u_lib.s9s_mb_2u(sch_1):m_e_cpu1_sb_dq(7)';
NODE_NAME     U1 EG25
 '@S9S_MB_2U_LIB.S9S_MB_2U(SCH_1):PAGE55_I7@PURE_QUANTA.SOCKET4677_AZIF0045P001C01CS(CHIPS)':
 'DDR4_SB_DQ7': CDS_PINID='DDR4_SB_DQ7';
NODE_NAME     J25 254
 '@S9S_MB_2U_LIB.S9S_MB_2U(SCH_1):PAGE106_I180@PURE_QUANTA.SCONN288_ADR50017P130CC(CHIPS)':
 'DQ7_B': CDS_PINID='DQ7_B';
NODE_NAME     J26 254
 '@S9S_MB_2U_LIB.S9S_MB_2U(SCH_1):PAGE107_I180@PURE_QUANTA.SCONN288_ADR50017P087CC(CHIPS)':
 'DQ7_B': CDS_PINID='DQ7_B';
NET_NAME
'M_E_CPU1_SB_DQ<8>'
 '@S9S_MB_2U_LIB.S9S_MB_2U(SCH_1):M_E_CPU1_SB_DQ'<8>:
 C_SIGNAL='@s9s_mb_2u_lib.s9s_mb_2u(sch_1):m_e_cpu1_sb_dq(8)';
NODE_NAME     U1 EM32
 '@S9S_MB_2U_LIB.S9S_MB_2U(SCH_1):PAGE55_I7@PURE_QUANTA.SOCKET4677_AZIF0045P001C01CS(CHIPS)':
 'DDR4_SB_DQ8': CDS_PINID='DDR4_SB_DQ8';
NODE_NAME     J25 111
 '@S9S_MB_2U_LIB.S9S_MB_2U(SCH_1):PAGE106_I180@PURE_QUANTA.SCONN288_ADR50017P130CC(CHIPS)':
 'DQ8_B': CDS_PINID='DQ8_B';
NODE_NAME     J26 111
 '@S9S_MB_2U_LIB.S9S_MB_2U(SCH_1):PAGE107_I180@PURE_QUANTA.SCONN288_ADR50017P087CC(CHIPS)':
 'DQ8_B': CDS_PINID='DQ8_B';
NET_NAME
'M_E_CPU1_SB_DQ<9>'
 '@S9S_MB_2U_LIB.S9S_MB_2U(SCH_1):M_E_CPU1_SB_DQ'<9>:
 C_SIGNAL='@s9s_mb_2u_lib.s9s_mb_2u(sch_1):m_e_cpu1_sb_dq(9)';
NODE_NAME     U1 EL31
 '@S9S_MB_2U_LIB.S9S_MB_2U(SCH_1):PAGE55_I7@PURE_QUANTA.SOCKET4677_AZIF0045P001C01CS(CHIPS)':
 'DDR4_SB_DQ9': CDS_PINID='DDR4_SB_DQ9';
NODE_NAME     J25 113
 '@S9S_MB_2U_LIB.S9S_MB_2U(SCH_1):PAGE106_I180@PURE_QUANTA.SCONN288_ADR50017P130CC(CHIPS)':
 'DQ9_B': CDS_PINID='DQ9_B';
NODE_NAME     J26 113
 '@S9S_MB_2U_LIB.S9S_MB_2U(SCH_1):PAGE107_I180@PURE_QUANTA.SCONN288_ADR50017P087CC(CHIPS)':
 'DQ9_B': CDS_PINID='DQ9_B';
NET_NAME
'M_E_CPU1_SB_DQS_DN<0>'
 '@S9S_MB_2U_LIB.S9S_MB_2U(SCH_1):M_E_CPU1_SB_DQS_DN'<0>:
 C_SIGNAL='@s9s_mb_2u_lib.s9s_mb_2u(sch_1):m_e_cpu1_sb_dqs_dn(0)';
NODE_NAME     U1 EE27
 '@S9S_MB_2U_LIB.S9S_MB_2U(SCH_1):PAGE55_I7@PURE_QUANTA.SOCKET4677_AZIF0045P001C01CS(CHIPS)':
 'DDR4_SB_DQS_DN0': CDS_PINID='DDR4_SB_DQS_DN0';
NODE_NAME     J25 105
 '@S9S_MB_2U_LIB.S9S_MB_2U(SCH_1):PAGE106_I181@PURE_QUANTA.SCONN288_ADR50017P130CC(CHIPS)':
 'DQS0_B_C': CDS_PINID='DQS0_B_C';
NODE_NAME     J26 105
 '@S9S_MB_2U_LIB.S9S_MB_2U(SCH_1):PAGE107_I181@PURE_QUANTA.SCONN288_ADR50017P087CC(CHIPS)':
 'DQS0_B_C': CDS_PINID='DQS0_B_C';
NET_NAME
'M_E_CPU1_SB_DQS_DN<1>'
 '@S9S_MB_2U_LIB.S9S_MB_2U(SCH_1):M_E_CPU1_SB_DQS_DN'<1>:
 C_SIGNAL='@s9s_mb_2u_lib.s9s_mb_2u(sch_1):m_e_cpu1_sb_dqs_dn(1)';
NODE_NAME     U1 EK30
 '@S9S_MB_2U_LIB.S9S_MB_2U(SCH_1):PAGE55_I7@PURE_QUANTA.SOCKET4677_AZIF0045P001C01CS(CHIPS)':
 'DDR4_SB_DQS_DN1': CDS_PINID='DDR4_SB_DQS_DN1';
NODE_NAME     J25 116
 '@S9S_MB_2U_LIB.S9S_MB_2U(SCH_1):PAGE106_I181@PURE_QUANTA.SCONN288_ADR50017P130CC(CHIPS)':
 'DQS1_B_C': CDS_PINID='DQS1_B_C';
NODE_NAME     J26 116
 '@S9S_MB_2U_LIB.S9S_MB_2U(SCH_1):PAGE107_I181@PURE_QUANTA.SCONN288_ADR50017P087CC(CHIPS)':
 'DQS1_B_C': CDS_PINID='DQS1_B_C';
NET_NAME
'M_E_CPU1_SB_DQS_DN<2>'
 '@S9S_MB_2U_LIB.S9S_MB_2U(SCH_1):M_E_CPU1_SB_DQS_DN'<2>:
 C_SIGNAL='@s9s_mb_2u_lib.s9s_mb_2u(sch_1):m_e_cpu1_sb_dqs_dn(2)';
NODE_NAME     U1 EK24
 '@S9S_MB_2U_LIB.S9S_MB_2U(SCH_1):PAGE55_I7@PURE_QUANTA.SOCKET4677_AZIF0045P001C01CS(CHIPS)':
 'DDR4_SB_DQS_DN2': CDS_PINID='DDR4_SB_DQS_DN2';
NODE_NAME     J25 127
 '@S9S_MB_2U_LIB.S9S_MB_2U(SCH_1):PAGE106_I181@PURE_QUANTA.SCONN288_ADR50017P130CC(CHIPS)':
 'DQS2_B_C': CDS_PINID='DQS2_B_C';
NODE_NAME     J26 127
 '@S9S_MB_2U_LIB.S9S_MB_2U(SCH_1):PAGE107_I181@PURE_QUANTA.SCONN288_ADR50017P087CC(CHIPS)':
 'DQS2_B_C': CDS_PINID='DQS2_B_C';
NET_NAME
'M_E_CPU1_SB_DQS_DN<3>'
 '@S9S_MB_2U_LIB.S9S_MB_2U(SCH_1):M_E_CPU1_SB_DQS_DN'<3>:
 C_SIGNAL='@s9s_mb_2u_lib.s9s_mb_2u(sch_1):m_e_cpu1_sb_dqs_dn(3)';
NODE_NAME     U1 EK18
 '@S9S_MB_2U_LIB.S9S_MB_2U(SCH_1):PAGE55_I7@PURE_QUANTA.SOCKET4677_AZIF0045P001C01CS(CHIPS)':
 'DDR4_SB_DQS_DN3': CDS_PINID='DDR4_SB_DQS_DN3';
NODE_NAME     J25 138
 '@S9S_MB_2U_LIB.S9S_MB_2U(SCH_1):PAGE106_I181@PURE_QUANTA.SCONN288_ADR50017P130CC(CHIPS)':
 'DQS3_B_C': CDS_PINID='DQS3_B_C';
NODE_NAME     J26 138
 '@S9S_MB_2U_LIB.S9S_MB_2U(SCH_1):PAGE107_I181@PURE_QUANTA.SCONN288_ADR50017P087CC(CHIPS)':
 'DQS3_B_C': CDS_PINID='DQS3_B_C';
NET_NAME
'M_E_CPU1_SB_DQS_DN<4>'
 '@S9S_MB_2U_LIB.S9S_MB_2U(SCH_1):M_E_CPU1_SB_DQS_DN'<4>:
 C_SIGNAL='@s9s_mb_2u_lib.s9s_mb_2u(sch_1):m_e_cpu1_sb_dqs_dn(4)';
NODE_NAME     U1 ET36
 '@S9S_MB_2U_LIB.S9S_MB_2U(SCH_1):PAGE55_I7@PURE_QUANTA.SOCKET4677_AZIF0045P001C01CS(CHIPS)':
 'DDR4_SB_DQS_DN4': CDS_PINID='DDR4_SB_DQS_DN4';
NODE_NAME     J25 238
 '@S9S_MB_2U_LIB.S9S_MB_2U(SCH_1):PAGE106_I181@PURE_QUANTA.SCONN288_ADR50017P130CC(CHIPS)':
 'DQS4_B_C': CDS_PINID='DQS4_B_C';
NODE_NAME     J26 238
 '@S9S_MB_2U_LIB.S9S_MB_2U(SCH_1):PAGE107_I181@PURE_QUANTA.SCONN288_ADR50017P087CC(CHIPS)':
 'DQS4_B_C': CDS_PINID='DQS4_B_C';
NET_NAME
'M_E_CPU1_SB_DQS_DN<5>'
 '@S9S_MB_2U_LIB.S9S_MB_2U(SCH_1):M_E_CPU1_SB_DQS_DN'<5>:
 C_SIGNAL='@s9s_mb_2u_lib.s9s_mb_2u(sch_1):m_e_cpu1_sb_dqs_dn(5)';
NODE_NAME     U1 EJ27
 '@S9S_MB_2U_LIB.S9S_MB_2U(SCH_1):PAGE55_I7@PURE_QUANTA.SOCKET4677_AZIF0045P001C01CS(CHIPS)':
 'DDR4_SB_DQS_DN5': CDS_PINID='DDR4_SB_DQS_DN5';
NODE_NAME     J25 249
 '@S9S_MB_2U_LIB.S9S_MB_2U(SCH_1):PAGE106_I181@PURE_QUANTA.SCONN288_ADR50017P130CC(CHIPS)':
 'DQS5_B_C||TDQS5_B_C': CDS_PINID='\dqs5_b_c||tdqs5_b_c\';
NODE_NAME     J26 249
 '@S9S_MB_2U_LIB.S9S_MB_2U(SCH_1):PAGE107_I181@PURE_QUANTA.SCONN288_ADR50017P087CC(CHIPS)':
 'DQS5_B_C||TDQS5_B_C': CDS_PINID='\dqs5_b_c||tdqs5_b_c\';
NET_NAME
'M_E_CPU1_SB_DQS_DN<6>'
 '@S9S_MB_2U_LIB.S9S_MB_2U(SCH_1):M_E_CPU1_SB_DQS_DN'<6>:
 C_SIGNAL='@s9s_mb_2u_lib.s9s_mb_2u(sch_1):m_e_cpu1_sb_dqs_dn(6)';
NODE_NAME     U1 ET30
 '@S9S_MB_2U_LIB.S9S_MB_2U(SCH_1):PAGE55_I7@PURE_QUANTA.SOCKET4677_AZIF0045P001C01CS(CHIPS)':
 'DDR4_SB_DQS_DN6': CDS_PINID='DDR4_SB_DQS_DN6';
NODE_NAME     J25 260
 '@S9S_MB_2U_LIB.S9S_MB_2U(SCH_1):PAGE106_I181@PURE_QUANTA.SCONN288_ADR50017P130CC(CHIPS)':
 'DQS6_B_C||TDQS6_B_C': CDS_PINID='\dqs6_b_c||tdqs6_b_c\';
NODE_NAME     J26 260
 '@S9S_MB_2U_LIB.S9S_MB_2U(SCH_1):PAGE107_I181@PURE_QUANTA.SCONN288_ADR50017P087CC(CHIPS)':
 'DQS6_B_C||TDQS6_B_C': CDS_PINID='\dqs6_b_c||tdqs6_b_c\';
NET_NAME
'M_E_CPU1_SB_DQS_DN<7>'
 '@S9S_MB_2U_LIB.S9S_MB_2U(SCH_1):M_E_CPU1_SB_DQS_DN'<7>:
 C_SIGNAL='@s9s_mb_2u_lib.s9s_mb_2u(sch_1):m_e_cpu1_sb_dqs_dn(7)';
NODE_NAME     U1 ET24
 '@S9S_MB_2U_LIB.S9S_MB_2U(SCH_1):PAGE55_I7@PURE_QUANTA.SOCKET4677_AZIF0045P001C01CS(CHIPS)':
 'DDR4_SB_DQS_DN7': CDS_PINID='DDR4_SB_DQS_DN7';
NODE_NAME     J25 271
 '@S9S_MB_2U_LIB.S9S_MB_2U(SCH_1):PAGE106_I181@PURE_QUANTA.SCONN288_ADR50017P130CC(CHIPS)':
 'DQS7_B_C||TDQS7_B_C': CDS_PINID='\dqs7_b_c||tdqs7_b_c\';
NODE_NAME     J26 271
 '@S9S_MB_2U_LIB.S9S_MB_2U(SCH_1):PAGE107_I181@PURE_QUANTA.SCONN288_ADR50017P087CC(CHIPS)':
 'DQS7_B_C||TDQS7_B_C': CDS_PINID='\dqs7_b_c||tdqs7_b_c\';
NET_NAME
'M_E_CPU1_SB_DQS_DN<8>'
 '@S9S_MB_2U_LIB.S9S_MB_2U(SCH_1):M_E_CPU1_SB_DQS_DN'<8>:
 C_SIGNAL='@s9s_mb_2u_lib.s9s_mb_2u(sch_1):m_e_cpu1_sb_dqs_dn(8)';
NODE_NAME     U1 ET18
 '@S9S_MB_2U_LIB.S9S_MB_2U(SCH_1):PAGE55_I7@PURE_QUANTA.SOCKET4677_AZIF0045P001C01CS(CHIPS)':
 'DDR4_SB_DQS_DN8': CDS_PINID='DDR4_SB_DQS_DN8';
NODE_NAME     J25 282
 '@S9S_MB_2U_LIB.S9S_MB_2U(SCH_1):PAGE106_I181@PURE_QUANTA.SCONN288_ADR50017P130CC(CHIPS)':
 'DQS8_B_C||TDQS8_B_C': CDS_PINID='\dqs8_b_c||tdqs8_b_c\';
NODE_NAME     J26 282
 '@S9S_MB_2U_LIB.S9S_MB_2U(SCH_1):PAGE107_I181@PURE_QUANTA.SCONN288_ADR50017P087CC(CHIPS)':
 'DQS8_B_C||TDQS8_B_C': CDS_PINID='\dqs8_b_c||tdqs8_b_c\';
NET_NAME
'M_E_CPU1_SB_DQS_DN<9>'
 '@S9S_MB_2U_LIB.S9S_MB_2U(SCH_1):M_E_CPU1_SB_DQS_DN'<9>:
 C_SIGNAL='@s9s_mb_2u_lib.s9s_mb_2u(sch_1):m_e_cpu1_sb_dqs_dn(9)';
NODE_NAME     U1 EK36
 '@S9S_MB_2U_LIB.S9S_MB_2U(SCH_1):PAGE55_I7@PURE_QUANTA.SOCKET4677_AZIF0045P001C01CS(CHIPS)':
 'DDR4_SB_DQS_DN9': CDS_PINID='DDR4_SB_DQS_DN9';
NODE_NAME     J25 94
 '@S9S_MB_2U_LIB.S9S_MB_2U(SCH_1):PAGE106_I181@PURE_QUANTA.SCONN288_ADR50017P130CC(CHIPS)':
 'DQS9_B_C||TDQS9_B_C': CDS_PINID='\dqs9_b_c||tdqs9_b_c\';
NODE_NAME     J26 94
 '@S9S_MB_2U_LIB.S9S_MB_2U(SCH_1):PAGE107_I181@PURE_QUANTA.SCONN288_ADR50017P087CC(CHIPS)':
 'DQS9_B_C||TDQS9_B_C': CDS_PINID='\dqs9_b_c||tdqs9_b_c\';
NET_NAME
'M_E_CPU1_SB_DQS_DP<0>'
 '@S9S_MB_2U_LIB.S9S_MB_2U(SCH_1):M_E_CPU1_SB_DQS_DP'<0>:
 C_SIGNAL='@s9s_mb_2u_lib.s9s_mb_2u(sch_1):m_e_cpu1_sb_dqs_dp(0)';
NODE_NAME     U1 EC27
 '@S9S_MB_2U_LIB.S9S_MB_2U(SCH_1):PAGE55_I7@PURE_QUANTA.SOCKET4677_AZIF0045P001C01CS(CHIPS)':
 'DDR4_SB_DQS_DP0': CDS_PINID='DDR4_SB_DQS_DP0';
NODE_NAME     J25 104
 '@S9S_MB_2U_LIB.S9S_MB_2U(SCH_1):PAGE106_I181@PURE_QUANTA.SCONN288_ADR50017P130CC(CHIPS)':
 'DQS0_B_T': CDS_PINID='DQS0_B_T';
NODE_NAME     J26 104
 '@S9S_MB_2U_LIB.S9S_MB_2U(SCH_1):PAGE107_I181@PURE_QUANTA.SCONN288_ADR50017P087CC(CHIPS)':
 'DQS0_B_T': CDS_PINID='DQS0_B_T';
NET_NAME
'M_E_CPU1_SB_DQS_DP<1>'
 '@S9S_MB_2U_LIB.S9S_MB_2U(SCH_1):M_E_CPU1_SB_DQS_DP'<1>:
 C_SIGNAL='@s9s_mb_2u_lib.s9s_mb_2u(sch_1):m_e_cpu1_sb_dqs_dp(1)';
NODE_NAME     U1 EM30
 '@S9S_MB_2U_LIB.S9S_MB_2U(SCH_1):PAGE55_I7@PURE_QUANTA.SOCKET4677_AZIF0045P001C01CS(CHIPS)':
 'DDR4_SB_DQS_DP1': CDS_PINID='DDR4_SB_DQS_DP1';
NODE_NAME     J25 115
 '@S9S_MB_2U_LIB.S9S_MB_2U(SCH_1):PAGE106_I181@PURE_QUANTA.SCONN288_ADR50017P130CC(CHIPS)':
 'DQS1_B_T': CDS_PINID='DQS1_B_T';
NODE_NAME     J26 115
 '@S9S_MB_2U_LIB.S9S_MB_2U(SCH_1):PAGE107_I181@PURE_QUANTA.SCONN288_ADR50017P087CC(CHIPS)':
 'DQS1_B_T': CDS_PINID='DQS1_B_T';
NET_NAME
'M_E_CPU1_SB_DQS_DP<2>'
 '@S9S_MB_2U_LIB.S9S_MB_2U(SCH_1):M_E_CPU1_SB_DQS_DP'<2>:
 C_SIGNAL='@s9s_mb_2u_lib.s9s_mb_2u(sch_1):m_e_cpu1_sb_dqs_dp(2)';
NODE_NAME     U1 EM24
 '@S9S_MB_2U_LIB.S9S_MB_2U(SCH_1):PAGE55_I7@PURE_QUANTA.SOCKET4677_AZIF0045P001C01CS(CHIPS)':
 'DDR4_SB_DQS_DP2': CDS_PINID='DDR4_SB_DQS_DP2';
NODE_NAME     J25 126
 '@S9S_MB_2U_LIB.S9S_MB_2U(SCH_1):PAGE106_I181@PURE_QUANTA.SCONN288_ADR50017P130CC(CHIPS)':
 'DQS2_B_T': CDS_PINID='DQS2_B_T';
NODE_NAME     J26 126
 '@S9S_MB_2U_LIB.S9S_MB_2U(SCH_1):PAGE107_I181@PURE_QUANTA.SCONN288_ADR50017P087CC(CHIPS)':
 'DQS2_B_T': CDS_PINID='DQS2_B_T';
NET_NAME
'M_E_CPU1_SB_DQS_DP<3>'
 '@S9S_MB_2U_LIB.S9S_MB_2U(SCH_1):M_E_CPU1_SB_DQS_DP'<3>:
 C_SIGNAL='@s9s_mb_2u_lib.s9s_mb_2u(sch_1):m_e_cpu1_sb_dqs_dp(3)';
NODE_NAME     U1 EM18
 '@S9S_MB_2U_LIB.S9S_MB_2U(SCH_1):PAGE55_I7@PURE_QUANTA.SOCKET4677_AZIF0045P001C01CS(CHIPS)':
 'DDR4_SB_DQS_DP3': CDS_PINID='DDR4_SB_DQS_DP3';
NODE_NAME     J25 137
 '@S9S_MB_2U_LIB.S9S_MB_2U(SCH_1):PAGE106_I181@PURE_QUANTA.SCONN288_ADR50017P130CC(CHIPS)':
 'DQS3_B_T': CDS_PINID='DQS3_B_T';
NODE_NAME     J26 137
 '@S9S_MB_2U_LIB.S9S_MB_2U(SCH_1):PAGE107_I181@PURE_QUANTA.SCONN288_ADR50017P087CC(CHIPS)':
 'DQS3_B_T': CDS_PINID='DQS3_B_T';
NET_NAME
'M_E_CPU1_SB_DQS_DP<4>'
 '@S9S_MB_2U_LIB.S9S_MB_2U(SCH_1):M_E_CPU1_SB_DQS_DP'<4>:
 C_SIGNAL='@s9s_mb_2u_lib.s9s_mb_2u(sch_1):m_e_cpu1_sb_dqs_dp(4)';
NODE_NAME     U1 EP36
 '@S9S_MB_2U_LIB.S9S_MB_2U(SCH_1):PAGE55_I7@PURE_QUANTA.SOCKET4677_AZIF0045P001C01CS(CHIPS)':
 'DDR4_SB_DQS_DP4': CDS_PINID='DDR4_SB_DQS_DP4';
NODE_NAME     J25 239
 '@S9S_MB_2U_LIB.S9S_MB_2U(SCH_1):PAGE106_I181@PURE_QUANTA.SCONN288_ADR50017P130CC(CHIPS)':
 'DQS4_B_T': CDS_PINID='DQS4_B_T';
NODE_NAME     J26 239
 '@S9S_MB_2U_LIB.S9S_MB_2U(SCH_1):PAGE107_I181@PURE_QUANTA.SCONN288_ADR50017P087CC(CHIPS)':
 'DQS4_B_T': CDS_PINID='DQS4_B_T';
NET_NAME
'M_E_CPU1_SB_DQS_DP<5>'
 '@S9S_MB_2U_LIB.S9S_MB_2U(SCH_1):M_E_CPU1_SB_DQS_DP'<5>:
 C_SIGNAL='@s9s_mb_2u_lib.s9s_mb_2u(sch_1):m_e_cpu1_sb_dqs_dp(5)';
NODE_NAME     U1 EG27
 '@S9S_MB_2U_LIB.S9S_MB_2U(SCH_1):PAGE55_I7@PURE_QUANTA.SOCKET4677_AZIF0045P001C01CS(CHIPS)':
 'DDR4_SB_DQS_DP5': CDS_PINID='DDR4_SB_DQS_DP5';
NODE_NAME     J25 250
 '@S9S_MB_2U_LIB.S9S_MB_2U(SCH_1):PAGE106_I181@PURE_QUANTA.SCONN288_ADR50017P130CC(CHIPS)':
 'DQS5_B_T||TDQS5_B_T': CDS_PINID='\dqs5_b_t||tdqs5_b_t\';
NODE_NAME     J26 250
 '@S9S_MB_2U_LIB.S9S_MB_2U(SCH_1):PAGE107_I181@PURE_QUANTA.SCONN288_ADR50017P087CC(CHIPS)':
 'DQS5_B_T||TDQS5_B_T': CDS_PINID='\dqs5_b_t||tdqs5_b_t\';
NET_NAME
'M_E_CPU1_SB_DQS_DP<6>'
 '@S9S_MB_2U_LIB.S9S_MB_2U(SCH_1):M_E_CPU1_SB_DQS_DP'<6>:
 C_SIGNAL='@s9s_mb_2u_lib.s9s_mb_2u(sch_1):m_e_cpu1_sb_dqs_dp(6)';
NODE_NAME     U1 EP30
 '@S9S_MB_2U_LIB.S9S_MB_2U(SCH_1):PAGE55_I7@PURE_QUANTA.SOCKET4677_AZIF0045P001C01CS(CHIPS)':
 'DDR4_SB_DQS_DP6': CDS_PINID='DDR4_SB_DQS_DP6';
NODE_NAME     J25 261
 '@S9S_MB_2U_LIB.S9S_MB_2U(SCH_1):PAGE106_I181@PURE_QUANTA.SCONN288_ADR50017P130CC(CHIPS)':
 'DQS6_B_T||TDQS6_B_T': CDS_PINID='\dqs6_b_t||tdqs6_b_t\';
NODE_NAME     J26 261
 '@S9S_MB_2U_LIB.S9S_MB_2U(SCH_1):PAGE107_I181@PURE_QUANTA.SCONN288_ADR50017P087CC(CHIPS)':
 'DQS6_B_T||TDQS6_B_T': CDS_PINID='\dqs6_b_t||tdqs6_b_t\';
NET_NAME
'M_E_CPU1_SB_DQS_DP<7>'
 '@S9S_MB_2U_LIB.S9S_MB_2U(SCH_1):M_E_CPU1_SB_DQS_DP'<7>:
 C_SIGNAL='@s9s_mb_2u_lib.s9s_mb_2u(sch_1):m_e_cpu1_sb_dqs_dp(7)';
NODE_NAME     U1 EP24
 '@S9S_MB_2U_LIB.S9S_MB_2U(SCH_1):PAGE55_I7@PURE_QUANTA.SOCKET4677_AZIF0045P001C01CS(CHIPS)':
 'DDR4_SB_DQS_DP7': CDS_PINID='DDR4_SB_DQS_DP7';
NODE_NAME     J25 272
 '@S9S_MB_2U_LIB.S9S_MB_2U(SCH_1):PAGE106_I181@PURE_QUANTA.SCONN288_ADR50017P130CC(CHIPS)':
 'DQS7_B_T||TDQS7_B_T': CDS_PINID='\dqs7_b_t||tdqs7_b_t\';
NODE_NAME     J26 272
 '@S9S_MB_2U_LIB.S9S_MB_2U(SCH_1):PAGE107_I181@PURE_QUANTA.SCONN288_ADR50017P087CC(CHIPS)':
 'DQS7_B_T||TDQS7_B_T': CDS_PINID='\dqs7_b_t||tdqs7_b_t\';
NET_NAME
'M_E_CPU1_SB_DQS_DP<8>'
 '@S9S_MB_2U_LIB.S9S_MB_2U(SCH_1):M_E_CPU1_SB_DQS_DP'<8>:
 C_SIGNAL='@s9s_mb_2u_lib.s9s_mb_2u(sch_1):m_e_cpu1_sb_dqs_dp(8)';
NODE_NAME     U1 EP18
 '@S9S_MB_2U_LIB.S9S_MB_2U(SCH_1):PAGE55_I7@PURE_QUANTA.SOCKET4677_AZIF0045P001C01CS(CHIPS)':
 'DDR4_SB_DQS_DP8': CDS_PINID='DDR4_SB_DQS_DP8';
NODE_NAME     J25 283
 '@S9S_MB_2U_LIB.S9S_MB_2U(SCH_1):PAGE106_I181@PURE_QUANTA.SCONN288_ADR50017P130CC(CHIPS)':
 'DQS8_B_T||TDQS8_B_T': CDS_PINID='\dqs8_b_t||tdqs8_b_t\';
NODE_NAME     J26 283
 '@S9S_MB_2U_LIB.S9S_MB_2U(SCH_1):PAGE107_I181@PURE_QUANTA.SCONN288_ADR50017P087CC(CHIPS)':
 'DQS8_B_T||TDQS8_B_T': CDS_PINID='\dqs8_b_t||tdqs8_b_t\';
NET_NAME
'M_E_CPU1_SB_DQS_DP<9>'
 '@S9S_MB_2U_LIB.S9S_MB_2U(SCH_1):M_E_CPU1_SB_DQS_DP'<9>:
 C_SIGNAL='@s9s_mb_2u_lib.s9s_mb_2u(sch_1):m_e_cpu1_sb_dqs_dp(9)';
NODE_NAME     U1 EM36
 '@S9S_MB_2U_LIB.S9S_MB_2U(SCH_1):PAGE55_I7@PURE_QUANTA.SOCKET4677_AZIF0045P001C01CS(CHIPS)':
 'DDR4_SB_DQS_DP9': CDS_PINID='DDR4_SB_DQS_DP9';
NODE_NAME     J25 93
 '@S9S_MB_2U_LIB.S9S_MB_2U(SCH_1):PAGE106_I181@PURE_QUANTA.SCONN288_ADR50017P130CC(CHIPS)':
 'DQS9_B_T||TDQS9_B_T||DBI4_B_N': CDS_PINID='\dqs9_b_t||tdqs9_b_t||dbi4_b_n\';
NODE_NAME     J26 93
 '@S9S_MB_2U_LIB.S9S_MB_2U(SCH_1):PAGE107_I181@PURE_QUANTA.SCONN288_ADR50017P087CC(CHIPS)':
 'DQS9_B_T||TDQS9_B_T||DBI4_B_N': CDS_PINID='\dqs9_b_t||tdqs9_b_t||dbi4_b_n\';
NET_NAME
'M_E_CPU1_SB_PAR'
 '@S9S_MB_2U_LIB.S9S_MB_2U(SCH_1):M_E_CPU1_SB_PAR':
 C_SIGNAL='@s9s_mb_2u_lib.s9s_mb_2u(sch_1):m_e_cpu1_sb_par';
NODE_NAME     U1 EP42
 '@S9S_MB_2U_LIB.S9S_MB_2U(SCH_1):PAGE55_I7@PURE_QUANTA.SOCKET4677_AZIF0045P001C01CS(CHIPS)':
 'DDR4_SB_PAR': CDS_PINID='DDR4_SB_PAR';
NODE_NAME     J25 227
 '@S9S_MB_2U_LIB.S9S_MB_2U(SCH_1):PAGE106_I180@PURE_QUANTA.SCONN288_ADR50017P130CC(CHIPS)':
 'PAR_B': CDS_PINID='PAR_B';
NODE_NAME     J26 227
 '@S9S_MB_2U_LIB.S9S_MB_2U(SCH_1):PAGE107_I180@PURE_QUANTA.SCONN288_ADR50017P087CC(CHIPS)':
 'PAR_B': CDS_PINID='PAR_B';
NET_NAME
'M_E_CPU1_SB_RSP<0>'
 '@S9S_MB_2U_LIB.S9S_MB_2U(SCH_1):M_E_CPU1_SB_RSP'<0>:
 C_SIGNAL='@s9s_mb_2u_lib.s9s_mb_2u(sch_1):m_e_cpu1_sb_rsp(0)';
NODE_NAME     U1 DF44
 '@S9S_MB_2U_LIB.S9S_MB_2U(SCH_1):PAGE55_I7@PURE_QUANTA.SOCKET4677_AZIF0045P001C01CS(CHIPS)':
 'DDR4_B_RSP0': CDS_PINID='DDR4_B_RSP0';
NODE_NAME     J25 87
 '@S9S_MB_2U_LIB.S9S_MB_2U(SCH_1):PAGE106_I180@PURE_QUANTA.SCONN288_ADR50017P130CC(CHIPS)':
 'LBS||RSP_B_N': CDS_PINID='\lbs||rsp_b_n\';
NET_NAME
'M_E_CPU1_SB_RSP<1>'
 '@S9S_MB_2U_LIB.S9S_MB_2U(SCH_1):M_E_CPU1_SB_RSP'<1>:
 C_SIGNAL='@s9s_mb_2u_lib.s9s_mb_2u(sch_1):m_e_cpu1_sb_rsp(1)';
NODE_NAME     U1 DG43
 '@S9S_MB_2U_LIB.S9S_MB_2U(SCH_1):PAGE55_I7@PURE_QUANTA.SOCKET4677_AZIF0045P001C01CS(CHIPS)':
 'DDR4_B_RSP1': CDS_PINID='DDR4_B_RSP1';
NODE_NAME     J26 87
 '@S9S_MB_2U_LIB.S9S_MB_2U(SCH_1):PAGE107_I180@PURE_QUANTA.SCONN288_ADR50017P087CC(CHIPS)':
 'LBS||RSP_B_N': CDS_PINID='\lbs||rsp_b_n\';
NET_NAME
'M_F_CPU0_ALERT_N'
 '@S9S_MB_2U_LIB.S9S_MB_2U(SCH_1):M_F_CPU0_ALERT_N':
 C_SIGNAL='@s9s_mb_2u_lib.s9s_mb_2u(sch_1):m_f_cpu0_alert_n';
NODE_NAME     U2 CW48
 '@S9S_MB_2U_LIB.S9S_MB_2U(SCH_1):PAGE25_I169@PURE_QUANTA.SOCKET4677_AZIF0045P001C01CS(CHIPS)':
 'DDR5_ALERT_N': CDS_PINID='DDR5_ALERT_N';
NODE_NAME     J11 62
 '@S9S_MB_2U_LIB.S9S_MB_2U(SCH_1):PAGE92_I25@PURE_QUANTA.SCONN288_ADR50017P130CC(CHIPS)':
 'ALERT_N': CDS_PINID='ALERT_N';
NODE_NAME     J12 62
 '@S9S_MB_2U_LIB.S9S_MB_2U(SCH_1):PAGE93_I24@PURE_QUANTA.SCONN288_ADR50017P087CC(CHIPS)':
 'ALERT_N': CDS_PINID='ALERT_N';
NET_NAME
'M_F_CPU0_CLK_DN<0>'
 '@S9S_MB_2U_LIB.S9S_MB_2U(SCH_1):M_F_CPU0_CLK_DN'<0>:
 C_SIGNAL='@s9s_mb_2u_lib.s9s_mb_2u(sch_1):m_f_cpu0_clk_dn(0)';
NODE_NAME     U2 DY49
 '@S9S_MB_2U_LIB.S9S_MB_2U(SCH_1):PAGE25_I169@PURE_QUANTA.SOCKET4677_AZIF0045P001C01CS(CHIPS)':
 'DDR5_CLK_DN0': CDS_PINID='DDR5_CLK_DN0';
NODE_NAME     J11 218
 '@S9S_MB_2U_LIB.S9S_MB_2U(SCH_1):PAGE92_I25@PURE_QUANTA.SCONN288_ADR50017P130CC(CHIPS)':
 'CK_C': CDS_PINID='CK_C';
NET_NAME
'M_F_CPU0_CLK_DN<1>'
 '@S9S_MB_2U_LIB.S9S_MB_2U(SCH_1):M_F_CPU0_CLK_DN'<1>:
 C_SIGNAL='@s9s_mb_2u_lib.s9s_mb_2u(sch_1):m_f_cpu0_clk_dn(1)';
NODE_NAME     U2 DV49
 '@S9S_MB_2U_LIB.S9S_MB_2U(SCH_1):PAGE25_I169@PURE_QUANTA.SOCKET4677_AZIF0045P001C01CS(CHIPS)':
 'DDR5_CLK_DN1': CDS_PINID='DDR5_CLK_DN1';
NODE_NAME     J12 218
 '@S9S_MB_2U_LIB.S9S_MB_2U(SCH_1):PAGE93_I24@PURE_QUANTA.SCONN288_ADR50017P087CC(CHIPS)':
 'CK_C': CDS_PINID='CK_C';
NET_NAME
'M_F_CPU0_CLK_DP<0>'
 '@S9S_MB_2U_LIB.S9S_MB_2U(SCH_1):M_F_CPU0_CLK_DP'<0>:
 C_SIGNAL='@s9s_mb_2u_lib.s9s_mb_2u(sch_1):m_f_cpu0_clk_dp(0)';
NODE_NAME     U2 EB49
 '@S9S_MB_2U_LIB.S9S_MB_2U(SCH_1):PAGE25_I169@PURE_QUANTA.SOCKET4677_AZIF0045P001C01CS(CHIPS)':
 'DDR5_CLK_DP0': CDS_PINID='DDR5_CLK_DP0';
NODE_NAME     J11 217
 '@S9S_MB_2U_LIB.S9S_MB_2U(SCH_1):PAGE92_I25@PURE_QUANTA.SCONN288_ADR50017P130CC(CHIPS)':
 'CK_T': CDS_PINID='CK_T';
NET_NAME
'M_F_CPU0_CLK_DP<1>'
 '@S9S_MB_2U_LIB.S9S_MB_2U(SCH_1):M_F_CPU0_CLK_DP'<1>:
 C_SIGNAL='@s9s_mb_2u_lib.s9s_mb_2u(sch_1):m_f_cpu0_clk_dp(1)';
NODE_NAME     U2 DT49
 '@S9S_MB_2U_LIB.S9S_MB_2U(SCH_1):PAGE25_I169@PURE_QUANTA.SOCKET4677_AZIF0045P001C01CS(CHIPS)':
 'DDR5_CLK_DP1': CDS_PINID='DDR5_CLK_DP1';
NODE_NAME     J12 217
 '@S9S_MB_2U_LIB.S9S_MB_2U(SCH_1):PAGE93_I24@PURE_QUANTA.SCONN288_ADR50017P087CC(CHIPS)':
 'CK_T': CDS_PINID='CK_T';
NET_NAME
'M_F_CPU0_SA_CA<0>'
 '@S9S_MB_2U_LIB.S9S_MB_2U(SCH_1):M_F_CPU0_SA_CA'<0>:
 C_SIGNAL='@s9s_mb_2u_lib.s9s_mb_2u(sch_1):m_f_cpu0_sa_ca(0)';
NODE_NAME     U2 EC52
 '@S9S_MB_2U_LIB.S9S_MB_2U(SCH_1):PAGE25_I169@PURE_QUANTA.SOCKET4677_AZIF0045P001C01CS(CHIPS)':
 'DDR5_SA_CA0': CDS_PINID='DDR5_SA_CA0';
NODE_NAME     J11 66
 '@S9S_MB_2U_LIB.S9S_MB_2U(SCH_1):PAGE92_I25@PURE_QUANTA.SCONN288_ADR50017P130CC(CHIPS)':
 'CA0_A': CDS_PINID='CA0_A';
NODE_NAME     J12 66
 '@S9S_MB_2U_LIB.S9S_MB_2U(SCH_1):PAGE93_I24@PURE_QUANTA.SCONN288_ADR50017P087CC(CHIPS)':
 'CA0_A': CDS_PINID='CA0_A';
NET_NAME
'M_F_CPU0_SA_CA<1>'
 '@S9S_MB_2U_LIB.S9S_MB_2U(SCH_1):M_F_CPU0_SA_CA'<1>:
 C_SIGNAL='@s9s_mb_2u_lib.s9s_mb_2u(sch_1):m_f_cpu0_sa_ca(1)';
NODE_NAME     U2 EJ52
 '@S9S_MB_2U_LIB.S9S_MB_2U(SCH_1):PAGE25_I169@PURE_QUANTA.SOCKET4677_AZIF0045P001C01CS(CHIPS)':
 'DDR5_SA_CA1': CDS_PINID='DDR5_SA_CA1';
NODE_NAME     J11 211
 '@S9S_MB_2U_LIB.S9S_MB_2U(SCH_1):PAGE92_I25@PURE_QUANTA.SCONN288_ADR50017P130CC(CHIPS)':
 'CA1_A': CDS_PINID='CA1_A';
NODE_NAME     J12 211
 '@S9S_MB_2U_LIB.S9S_MB_2U(SCH_1):PAGE93_I24@PURE_QUANTA.SCONN288_ADR50017P087CC(CHIPS)':
 'CA1_A': CDS_PINID='CA1_A';
NET_NAME
'M_F_CPU0_SA_CA<2>'
 '@S9S_MB_2U_LIB.S9S_MB_2U(SCH_1):M_F_CPU0_SA_CA'<2>:
 C_SIGNAL='@s9s_mb_2u_lib.s9s_mb_2u(sch_1):m_f_cpu0_sa_ca(2)';
NODE_NAME     U2 ED51
 '@S9S_MB_2U_LIB.S9S_MB_2U(SCH_1):PAGE25_I169@PURE_QUANTA.SOCKET4677_AZIF0045P001C01CS(CHIPS)':
 'DDR5_SA_CA2': CDS_PINID='DDR5_SA_CA2';
NODE_NAME     J11 68
 '@S9S_MB_2U_LIB.S9S_MB_2U(SCH_1):PAGE92_I25@PURE_QUANTA.SCONN288_ADR50017P130CC(CHIPS)':
 'CA2_A': CDS_PINID='CA2_A';
NODE_NAME     J12 68
 '@S9S_MB_2U_LIB.S9S_MB_2U(SCH_1):PAGE93_I24@PURE_QUANTA.SCONN288_ADR50017P087CC(CHIPS)':
 'CA2_A': CDS_PINID='CA2_A';
NET_NAME
'M_F_CPU0_SA_CA<3>'
 '@S9S_MB_2U_LIB.S9S_MB_2U(SCH_1):M_F_CPU0_SA_CA'<3>:
 C_SIGNAL='@s9s_mb_2u_lib.s9s_mb_2u(sch_1):m_f_cpu0_sa_ca(3)';
NODE_NAME     U2 EH51
 '@S9S_MB_2U_LIB.S9S_MB_2U(SCH_1):PAGE25_I169@PURE_QUANTA.SOCKET4677_AZIF0045P001C01CS(CHIPS)':
 'DDR5_SA_CA3': CDS_PINID='DDR5_SA_CA3';
NODE_NAME     J11 213
 '@S9S_MB_2U_LIB.S9S_MB_2U(SCH_1):PAGE92_I25@PURE_QUANTA.SCONN288_ADR50017P130CC(CHIPS)':
 'CA3_A': CDS_PINID='CA3_A';
NODE_NAME     J12 213
 '@S9S_MB_2U_LIB.S9S_MB_2U(SCH_1):PAGE93_I24@PURE_QUANTA.SCONN288_ADR50017P087CC(CHIPS)':
 'CA3_A': CDS_PINID='CA3_A';
NET_NAME
'M_F_CPU0_SA_CA<4>'
 '@S9S_MB_2U_LIB.S9S_MB_2U(SCH_1):M_F_CPU0_SA_CA'<4>:
 C_SIGNAL='@s9s_mb_2u_lib.s9s_mb_2u(sch_1):m_f_cpu0_sa_ca(4)';
NODE_NAME     U2 EE50
 '@S9S_MB_2U_LIB.S9S_MB_2U(SCH_1):PAGE25_I169@PURE_QUANTA.SOCKET4677_AZIF0045P001C01CS(CHIPS)':
 'DDR5_SA_CA4': CDS_PINID='DDR5_SA_CA4';
NODE_NAME     J11 70
 '@S9S_MB_2U_LIB.S9S_MB_2U(SCH_1):PAGE92_I25@PURE_QUANTA.SCONN288_ADR50017P130CC(CHIPS)':
 'CA4_A': CDS_PINID='CA4_A';
NODE_NAME     J12 70
 '@S9S_MB_2U_LIB.S9S_MB_2U(SCH_1):PAGE93_I24@PURE_QUANTA.SCONN288_ADR50017P087CC(CHIPS)':
 'CA4_A': CDS_PINID='CA4_A';
NET_NAME
'M_F_CPU0_SA_CA<5>'
 '@S9S_MB_2U_LIB.S9S_MB_2U(SCH_1):M_F_CPU0_SA_CA'<5>:
 C_SIGNAL='@s9s_mb_2u_lib.s9s_mb_2u(sch_1):m_f_cpu0_sa_ca(5)';
NODE_NAME     U2 EG50
 '@S9S_MB_2U_LIB.S9S_MB_2U(SCH_1):PAGE25_I169@PURE_QUANTA.SOCKET4677_AZIF0045P001C01CS(CHIPS)':
 'DDR5_SA_CA5': CDS_PINID='DDR5_SA_CA5';
NODE_NAME     J11 215
 '@S9S_MB_2U_LIB.S9S_MB_2U(SCH_1):PAGE92_I25@PURE_QUANTA.SCONN288_ADR50017P130CC(CHIPS)':
 'CA5_A': CDS_PINID='CA5_A';
NODE_NAME     J12 215
 '@S9S_MB_2U_LIB.S9S_MB_2U(SCH_1):PAGE93_I24@PURE_QUANTA.SCONN288_ADR50017P087CC(CHIPS)':
 'CA5_A': CDS_PINID='CA5_A';
NET_NAME
'M_F_CPU0_SA_CA<6>'
 '@S9S_MB_2U_LIB.S9S_MB_2U(SCH_1):M_F_CPU0_SA_CA'<6>:
 C_SIGNAL='@s9s_mb_2u_lib.s9s_mb_2u(sch_1):m_f_cpu0_sa_ca(6)';
NODE_NAME     U2 DY51
 '@S9S_MB_2U_LIB.S9S_MB_2U(SCH_1):PAGE25_I169@PURE_QUANTA.SOCKET4677_AZIF0045P001C01CS(CHIPS)':
 'DDR5_SA_CA6': CDS_PINID='DDR5_SA_CA6';
NODE_NAME     J11 72
 '@S9S_MB_2U_LIB.S9S_MB_2U(SCH_1):PAGE92_I25@PURE_QUANTA.SCONN288_ADR50017P130CC(CHIPS)':
 'CA6_A': CDS_PINID='CA6_A';
NODE_NAME     J12 72
 '@S9S_MB_2U_LIB.S9S_MB_2U(SCH_1):PAGE93_I24@PURE_QUANTA.SCONN288_ADR50017P087CC(CHIPS)':
 'CA6_A': CDS_PINID='CA6_A';
NET_NAME
'M_F_CPU0_SA_CB<0>'
 '@S9S_MB_2U_LIB.S9S_MB_2U(SCH_1):M_F_CPU0_SA_CB'<0>:
 C_SIGNAL='@s9s_mb_2u_lib.s9s_mb_2u(sch_1):m_f_cpu0_sa_cb(0)';
NODE_NAME     U2 EE60
 '@S9S_MB_2U_LIB.S9S_MB_2U(SCH_1):PAGE25_I169@PURE_QUANTA.SOCKET4677_AZIF0045P001C01CS(CHIPS)':
 'DDR5_SA_ECC0': CDS_PINID='DDR5_SA_ECC0';
NODE_NAME     J11 51
 '@S9S_MB_2U_LIB.S9S_MB_2U(SCH_1):PAGE92_I25@PURE_QUANTA.SCONN288_ADR50017P130CC(CHIPS)':
 'CB0_A': CDS_PINID='CB0_A';
NODE_NAME     J12 51
 '@S9S_MB_2U_LIB.S9S_MB_2U(SCH_1):PAGE93_I24@PURE_QUANTA.SCONN288_ADR50017P087CC(CHIPS)':
 'CB0_A': CDS_PINID='CB0_A';
NET_NAME
'M_F_CPU0_SA_CB<1>'
 '@S9S_MB_2U_LIB.S9S_MB_2U(SCH_1):M_F_CPU0_SA_CB'<1>:
 C_SIGNAL='@s9s_mb_2u_lib.s9s_mb_2u(sch_1):m_f_cpu0_sa_cb(1)';
NODE_NAME     U2 ED59
 '@S9S_MB_2U_LIB.S9S_MB_2U(SCH_1):PAGE25_I169@PURE_QUANTA.SOCKET4677_AZIF0045P001C01CS(CHIPS)':
 'DDR5_SA_ECC1': CDS_PINID='DDR5_SA_ECC1';
NODE_NAME     J11 53
 '@S9S_MB_2U_LIB.S9S_MB_2U(SCH_1):PAGE92_I25@PURE_QUANTA.SCONN288_ADR50017P130CC(CHIPS)':
 'CB1_A': CDS_PINID='CB1_A';
NODE_NAME     J12 53
 '@S9S_MB_2U_LIB.S9S_MB_2U(SCH_1):PAGE93_I24@PURE_QUANTA.SCONN288_ADR50017P087CC(CHIPS)':
 'CB1_A': CDS_PINID='CB1_A';
NET_NAME
'M_F_CPU0_SA_CB<2>'
 '@S9S_MB_2U_LIB.S9S_MB_2U(SCH_1):M_F_CPU0_SA_CB'<2>:
 C_SIGNAL='@s9s_mb_2u_lib.s9s_mb_2u(sch_1):m_f_cpu0_sa_cb(2)';
NODE_NAME     U2 EG60
 '@S9S_MB_2U_LIB.S9S_MB_2U(SCH_1):PAGE25_I169@PURE_QUANTA.SOCKET4677_AZIF0045P001C01CS(CHIPS)':
 'DDR5_SA_ECC2': CDS_PINID='DDR5_SA_ECC2';
NODE_NAME     J11 196
 '@S9S_MB_2U_LIB.S9S_MB_2U(SCH_1):PAGE92_I25@PURE_QUANTA.SCONN288_ADR50017P130CC(CHIPS)':
 'CB2_A': CDS_PINID='CB2_A';
NODE_NAME     J12 196
 '@S9S_MB_2U_LIB.S9S_MB_2U(SCH_1):PAGE93_I24@PURE_QUANTA.SCONN288_ADR50017P087CC(CHIPS)':
 'CB2_A': CDS_PINID='CB2_A';
NET_NAME
'M_F_CPU0_SA_CB<3>'
 '@S9S_MB_2U_LIB.S9S_MB_2U(SCH_1):M_F_CPU0_SA_CB'<3>:
 C_SIGNAL='@s9s_mb_2u_lib.s9s_mb_2u(sch_1):m_f_cpu0_sa_cb(3)';
NODE_NAME     U2 EH59
 '@S9S_MB_2U_LIB.S9S_MB_2U(SCH_1):PAGE25_I169@PURE_QUANTA.SOCKET4677_AZIF0045P001C01CS(CHIPS)':
 'DDR5_SA_ECC3': CDS_PINID='DDR5_SA_ECC3';
NODE_NAME     J11 198
 '@S9S_MB_2U_LIB.S9S_MB_2U(SCH_1):PAGE92_I25@PURE_QUANTA.SCONN288_ADR50017P130CC(CHIPS)':
 'CB3_A': CDS_PINID='CB3_A';
NODE_NAME     J12 198
 '@S9S_MB_2U_LIB.S9S_MB_2U(SCH_1):PAGE93_I24@PURE_QUANTA.SCONN288_ADR50017P087CC(CHIPS)':
 'CB3_A': CDS_PINID='CB3_A';
NET_NAME
'M_F_CPU0_SA_CB<4>'
 '@S9S_MB_2U_LIB.S9S_MB_2U(SCH_1):M_F_CPU0_SA_CB'<4>:
 C_SIGNAL='@s9s_mb_2u_lib.s9s_mb_2u(sch_1):m_f_cpu0_sa_cb(4)';
NODE_NAME     U2 ED57
 '@S9S_MB_2U_LIB.S9S_MB_2U(SCH_1):PAGE25_I169@PURE_QUANTA.SOCKET4677_AZIF0045P001C01CS(CHIPS)':
 'DDR5_SA_ECC4': CDS_PINID='DDR5_SA_ECC4';
NODE_NAME     J11 58
 '@S9S_MB_2U_LIB.S9S_MB_2U(SCH_1):PAGE92_I25@PURE_QUANTA.SCONN288_ADR50017P130CC(CHIPS)':
 'CB4_A': CDS_PINID='CB4_A';
NODE_NAME     J12 58
 '@S9S_MB_2U_LIB.S9S_MB_2U(SCH_1):PAGE93_I24@PURE_QUANTA.SCONN288_ADR50017P087CC(CHIPS)':
 'CB4_A': CDS_PINID='CB4_A';
NET_NAME
'M_F_CPU0_SA_CB<5>'
 '@S9S_MB_2U_LIB.S9S_MB_2U(SCH_1):M_F_CPU0_SA_CB'<5>:
 C_SIGNAL='@s9s_mb_2u_lib.s9s_mb_2u(sch_1):m_f_cpu0_sa_cb(5)';
NODE_NAME     U2 EE56
 '@S9S_MB_2U_LIB.S9S_MB_2U(SCH_1):PAGE25_I169@PURE_QUANTA.SOCKET4677_AZIF0045P001C01CS(CHIPS)':
 'DDR5_SA_ECC5': CDS_PINID='DDR5_SA_ECC5';
NODE_NAME     J11 60
 '@S9S_MB_2U_LIB.S9S_MB_2U(SCH_1):PAGE92_I25@PURE_QUANTA.SCONN288_ADR50017P130CC(CHIPS)':
 'CB5_A': CDS_PINID='CB5_A';
NODE_NAME     J12 60
 '@S9S_MB_2U_LIB.S9S_MB_2U(SCH_1):PAGE93_I24@PURE_QUANTA.SCONN288_ADR50017P087CC(CHIPS)':
 'CB5_A': CDS_PINID='CB5_A';
NET_NAME
'M_F_CPU0_SA_CB<6>'
 '@S9S_MB_2U_LIB.S9S_MB_2U(SCH_1):M_F_CPU0_SA_CB'<6>:
 C_SIGNAL='@s9s_mb_2u_lib.s9s_mb_2u(sch_1):m_f_cpu0_sa_cb(6)';
NODE_NAME     U2 EH57
 '@S9S_MB_2U_LIB.S9S_MB_2U(SCH_1):PAGE25_I169@PURE_QUANTA.SOCKET4677_AZIF0045P001C01CS(CHIPS)':
 'DDR5_SA_ECC6': CDS_PINID='DDR5_SA_ECC6';
NODE_NAME     J11 203
 '@S9S_MB_2U_LIB.S9S_MB_2U(SCH_1):PAGE92_I25@PURE_QUANTA.SCONN288_ADR50017P130CC(CHIPS)':
 'CB6_A': CDS_PINID='CB6_A';
NODE_NAME     J12 203
 '@S9S_MB_2U_LIB.S9S_MB_2U(SCH_1):PAGE93_I24@PURE_QUANTA.SCONN288_ADR50017P087CC(CHIPS)':
 'CB6_A': CDS_PINID='CB6_A';
NET_NAME
'M_F_CPU0_SA_CB<7>'
 '@S9S_MB_2U_LIB.S9S_MB_2U(SCH_1):M_F_CPU0_SA_CB'<7>:
 C_SIGNAL='@s9s_mb_2u_lib.s9s_mb_2u(sch_1):m_f_cpu0_sa_cb(7)';
NODE_NAME     U2 EG56
 '@S9S_MB_2U_LIB.S9S_MB_2U(SCH_1):PAGE25_I169@PURE_QUANTA.SOCKET4677_AZIF0045P001C01CS(CHIPS)':
 'DDR5_SA_ECC7': CDS_PINID='DDR5_SA_ECC7';
NODE_NAME     J11 205
 '@S9S_MB_2U_LIB.S9S_MB_2U(SCH_1):PAGE92_I25@PURE_QUANTA.SCONN288_ADR50017P130CC(CHIPS)':
 'CB7_A': CDS_PINID='CB7_A';
NODE_NAME     J12 205
 '@S9S_MB_2U_LIB.S9S_MB_2U(SCH_1):PAGE93_I24@PURE_QUANTA.SCONN288_ADR50017P087CC(CHIPS)':
 'CB7_A': CDS_PINID='CB7_A';
NET_NAME
'M_F_CPU0_SA_CS_N<0>'
 '@S9S_MB_2U_LIB.S9S_MB_2U(SCH_1):M_F_CPU0_SA_CS_N'<0>:
 C_SIGNAL='@s9s_mb_2u_lib.s9s_mb_2u(sch_1):m_f_cpu0_sa_cs_n(0)';
NODE_NAME     U2 EG54
 '@S9S_MB_2U_LIB.S9S_MB_2U(SCH_1):PAGE25_I169@PURE_QUANTA.SOCKET4677_AZIF0045P001C01CS(CHIPS)':
 'DDR5_SA_CS_N0': CDS_PINID='DDR5_SA_CS_N0';
NODE_NAME     J11 64
 '@S9S_MB_2U_LIB.S9S_MB_2U(SCH_1):PAGE92_I25@PURE_QUANTA.SCONN288_ADR50017P130CC(CHIPS)':
 'CS0_A_N': CDS_PINID='CS0_A_N';
NET_NAME
'M_F_CPU0_SA_CS_N<1>'
 '@S9S_MB_2U_LIB.S9S_MB_2U(SCH_1):M_F_CPU0_SA_CS_N'<1>:
 C_SIGNAL='@s9s_mb_2u_lib.s9s_mb_2u(sch_1):m_f_cpu0_sa_cs_n(1)';
NODE_NAME     U2 EH53
 '@S9S_MB_2U_LIB.S9S_MB_2U(SCH_1):PAGE25_I169@PURE_QUANTA.SOCKET4677_AZIF0045P001C01CS(CHIPS)':
 'DDR5_SA_CS_N1': CDS_PINID='DDR5_SA_CS_N1';
NODE_NAME     J11 209
 '@S9S_MB_2U_LIB.S9S_MB_2U(SCH_1):PAGE92_I25@PURE_QUANTA.SCONN288_ADR50017P130CC(CHIPS)':
 'CS1_A_N': CDS_PINID='CS1_A_N';
NET_NAME
'M_F_CPU0_SA_CS_N<2>'
 '@S9S_MB_2U_LIB.S9S_MB_2U(SCH_1):M_F_CPU0_SA_CS_N'<2>:
 C_SIGNAL='@s9s_mb_2u_lib.s9s_mb_2u(sch_1):m_f_cpu0_sa_cs_n(2)';
NODE_NAME     U2 EE54
 '@S9S_MB_2U_LIB.S9S_MB_2U(SCH_1):PAGE25_I169@PURE_QUANTA.SOCKET4677_AZIF0045P001C01CS(CHIPS)':
 'DDR5_SA_CS_N2': CDS_PINID='DDR5_SA_CS_N2';
NODE_NAME     J12 64
 '@S9S_MB_2U_LIB.S9S_MB_2U(SCH_1):PAGE93_I24@PURE_QUANTA.SCONN288_ADR50017P087CC(CHIPS)':
 'CS0_A_N': CDS_PINID='CS0_A_N';
NET_NAME
'M_F_CPU0_SA_CS_N<3>'
 '@S9S_MB_2U_LIB.S9S_MB_2U(SCH_1):M_F_CPU0_SA_CS_N'<3>:
 C_SIGNAL='@s9s_mb_2u_lib.s9s_mb_2u(sch_1):m_f_cpu0_sa_cs_n(3)';
NODE_NAME     U2 ED53
 '@S9S_MB_2U_LIB.S9S_MB_2U(SCH_1):PAGE25_I169@PURE_QUANTA.SOCKET4677_AZIF0045P001C01CS(CHIPS)':
 'DDR5_SA_CS_N3': CDS_PINID='DDR5_SA_CS_N3';
NODE_NAME     J12 209
 '@S9S_MB_2U_LIB.S9S_MB_2U(SCH_1):PAGE93_I24@PURE_QUANTA.SCONN288_ADR50017P087CC(CHIPS)':
 'CS1_A_N': CDS_PINID='CS1_A_N';
NET_NAME
'M_F_CPU0_SA_DQ<0>'
 '@S9S_MB_2U_LIB.S9S_MB_2U(SCH_1):M_F_CPU0_SA_DQ'<0>:
 C_SIGNAL='@s9s_mb_2u_lib.s9s_mb_2u(sch_1):m_f_cpu0_sa_dq(0)';
NODE_NAME     U2 EB77
 '@S9S_MB_2U_LIB.S9S_MB_2U(SCH_1):PAGE25_I169@PURE_QUANTA.SOCKET4677_AZIF0045P001C01CS(CHIPS)':
 'DDR5_SA_DQ0': CDS_PINID='DDR5_SA_DQ0';
NODE_NAME     J11 7
 '@S9S_MB_2U_LIB.S9S_MB_2U(SCH_1):PAGE92_I25@PURE_QUANTA.SCONN288_ADR50017P130CC(CHIPS)':
 'DQ0_A': CDS_PINID='DQ0_A';
NODE_NAME     J12 7
 '@S9S_MB_2U_LIB.S9S_MB_2U(SCH_1):PAGE93_I24@PURE_QUANTA.SCONN288_ADR50017P087CC(CHIPS)':
 'DQ0_A': CDS_PINID='DQ0_A';
NET_NAME
'M_F_CPU0_SA_DQ<10>'
 '@S9S_MB_2U_LIB.S9S_MB_2U(SCH_1):M_F_CPU0_SA_DQ'<10>:
 C_SIGNAL='@s9s_mb_2u_lib.s9s_mb_2u(sch_1):m_f_cpu0_sa_dq(10)';
NODE_NAME     U2 DY69
 '@S9S_MB_2U_LIB.S9S_MB_2U(SCH_1):PAGE25_I169@PURE_QUANTA.SOCKET4677_AZIF0045P001C01CS(CHIPS)':
 'DDR5_SA_DQ10': CDS_PINID='DDR5_SA_DQ10';
NODE_NAME     J11 163
 '@S9S_MB_2U_LIB.S9S_MB_2U(SCH_1):PAGE92_I25@PURE_QUANTA.SCONN288_ADR50017P130CC(CHIPS)':
 'DQ10_A': CDS_PINID='DQ10_A';
NODE_NAME     J12 163
 '@S9S_MB_2U_LIB.S9S_MB_2U(SCH_1):PAGE93_I24@PURE_QUANTA.SCONN288_ADR50017P087CC(CHIPS)':
 'DQ10_A': CDS_PINID='DQ10_A';
NET_NAME
'M_F_CPU0_SA_DQ<11>'
 '@S9S_MB_2U_LIB.S9S_MB_2U(SCH_1):M_F_CPU0_SA_DQ'<11>:
 C_SIGNAL='@s9s_mb_2u_lib.s9s_mb_2u(sch_1):m_f_cpu0_sa_dq(11)';
NODE_NAME     U2 EA68
 '@S9S_MB_2U_LIB.S9S_MB_2U(SCH_1):PAGE25_I169@PURE_QUANTA.SOCKET4677_AZIF0045P001C01CS(CHIPS)':
 'DDR5_SA_DQ11': CDS_PINID='DDR5_SA_DQ11';
NODE_NAME     J11 165
 '@S9S_MB_2U_LIB.S9S_MB_2U(SCH_1):PAGE92_I25@PURE_QUANTA.SCONN288_ADR50017P130CC(CHIPS)':
 'DQ11_A': CDS_PINID='DQ11_A';
NODE_NAME     J12 165
 '@S9S_MB_2U_LIB.S9S_MB_2U(SCH_1):PAGE93_I24@PURE_QUANTA.SCONN288_ADR50017P087CC(CHIPS)':
 'DQ11_A': CDS_PINID='DQ11_A';
NET_NAME
'M_F_CPU0_SA_DQ<12>'
 '@S9S_MB_2U_LIB.S9S_MB_2U(SCH_1):M_F_CPU0_SA_DQ'<12>:
 C_SIGNAL='@s9s_mb_2u_lib.s9s_mb_2u(sch_1):m_f_cpu0_sa_dq(12)';
NODE_NAME     U2 DU66
 '@S9S_MB_2U_LIB.S9S_MB_2U(SCH_1):PAGE25_I169@PURE_QUANTA.SOCKET4677_AZIF0045P001C01CS(CHIPS)':
 'DDR5_SA_DQ12': CDS_PINID='DDR5_SA_DQ12';
NODE_NAME     J11 25
 '@S9S_MB_2U_LIB.S9S_MB_2U(SCH_1):PAGE92_I25@PURE_QUANTA.SCONN288_ADR50017P130CC(CHIPS)':
 'DQ12_A': CDS_PINID='DQ12_A';
NODE_NAME     J12 25
 '@S9S_MB_2U_LIB.S9S_MB_2U(SCH_1):PAGE93_I24@PURE_QUANTA.SCONN288_ADR50017P087CC(CHIPS)':
 'DQ12_A': CDS_PINID='DQ12_A';
NET_NAME
'M_F_CPU0_SA_DQ<13>'
 '@S9S_MB_2U_LIB.S9S_MB_2U(SCH_1):M_F_CPU0_SA_DQ'<13>:
 C_SIGNAL='@s9s_mb_2u_lib.s9s_mb_2u(sch_1):m_f_cpu0_sa_dq(13)';
NODE_NAME     U2 DV65
 '@S9S_MB_2U_LIB.S9S_MB_2U(SCH_1):PAGE25_I169@PURE_QUANTA.SOCKET4677_AZIF0045P001C01CS(CHIPS)':
 'DDR5_SA_DQ13': CDS_PINID='DDR5_SA_DQ13';
NODE_NAME     J11 27
 '@S9S_MB_2U_LIB.S9S_MB_2U(SCH_1):PAGE92_I25@PURE_QUANTA.SCONN288_ADR50017P130CC(CHIPS)':
 'DQ13_A': CDS_PINID='DQ13_A';
NODE_NAME     J12 27
 '@S9S_MB_2U_LIB.S9S_MB_2U(SCH_1):PAGE93_I24@PURE_QUANTA.SCONN288_ADR50017P087CC(CHIPS)':
 'DQ13_A': CDS_PINID='DQ13_A';
NET_NAME
'M_F_CPU0_SA_DQ<14>'
 '@S9S_MB_2U_LIB.S9S_MB_2U(SCH_1):M_F_CPU0_SA_DQ'<14>:
 C_SIGNAL='@s9s_mb_2u_lib.s9s_mb_2u(sch_1):m_f_cpu0_sa_dq(14)';
NODE_NAME     U2 EA66
 '@S9S_MB_2U_LIB.S9S_MB_2U(SCH_1):PAGE25_I169@PURE_QUANTA.SOCKET4677_AZIF0045P001C01CS(CHIPS)':
 'DDR5_SA_DQ14': CDS_PINID='DDR5_SA_DQ14';
NODE_NAME     J11 170
 '@S9S_MB_2U_LIB.S9S_MB_2U(SCH_1):PAGE92_I25@PURE_QUANTA.SCONN288_ADR50017P130CC(CHIPS)':
 'DQ14_A': CDS_PINID='DQ14_A';
NODE_NAME     J12 170
 '@S9S_MB_2U_LIB.S9S_MB_2U(SCH_1):PAGE93_I24@PURE_QUANTA.SCONN288_ADR50017P087CC(CHIPS)':
 'DQ14_A': CDS_PINID='DQ14_A';
NET_NAME
'M_F_CPU0_SA_DQ<15>'
 '@S9S_MB_2U_LIB.S9S_MB_2U(SCH_1):M_F_CPU0_SA_DQ'<15>:
 C_SIGNAL='@s9s_mb_2u_lib.s9s_mb_2u(sch_1):m_f_cpu0_sa_dq(15)';
NODE_NAME     U2 DY65
 '@S9S_MB_2U_LIB.S9S_MB_2U(SCH_1):PAGE25_I169@PURE_QUANTA.SOCKET4677_AZIF0045P001C01CS(CHIPS)':
 'DDR5_SA_DQ15': CDS_PINID='DDR5_SA_DQ15';
NODE_NAME     J11 172
 '@S9S_MB_2U_LIB.S9S_MB_2U(SCH_1):PAGE92_I25@PURE_QUANTA.SCONN288_ADR50017P130CC(CHIPS)':
 'DQ15_A': CDS_PINID='DQ15_A';
NODE_NAME     J12 172
 '@S9S_MB_2U_LIB.S9S_MB_2U(SCH_1):PAGE93_I24@PURE_QUANTA.SCONN288_ADR50017P087CC(CHIPS)':
 'DQ15_A': CDS_PINID='DQ15_A';
NET_NAME
'M_F_CPU0_SA_DQ<16>'
 '@S9S_MB_2U_LIB.S9S_MB_2U(SCH_1):M_F_CPU0_SA_DQ'<16>:
 C_SIGNAL='@s9s_mb_2u_lib.s9s_mb_2u(sch_1):m_f_cpu0_sa_dq(16)';
NODE_NAME     U2 EE66
 '@S9S_MB_2U_LIB.S9S_MB_2U(SCH_1):PAGE25_I169@PURE_QUANTA.SOCKET4677_AZIF0045P001C01CS(CHIPS)':
 'DDR5_SA_DQ16': CDS_PINID='DDR5_SA_DQ16';
NODE_NAME     J11 29
 '@S9S_MB_2U_LIB.S9S_MB_2U(SCH_1):PAGE92_I25@PURE_QUANTA.SCONN288_ADR50017P130CC(CHIPS)':
 'DQ16_A': CDS_PINID='DQ16_A';
NODE_NAME     J12 29
 '@S9S_MB_2U_LIB.S9S_MB_2U(SCH_1):PAGE93_I24@PURE_QUANTA.SCONN288_ADR50017P087CC(CHIPS)':
 'DQ16_A': CDS_PINID='DQ16_A';
NET_NAME
'M_F_CPU0_SA_DQ<17>'
 '@S9S_MB_2U_LIB.S9S_MB_2U(SCH_1):M_F_CPU0_SA_DQ'<17>:
 C_SIGNAL='@s9s_mb_2u_lib.s9s_mb_2u(sch_1):m_f_cpu0_sa_dq(17)';
NODE_NAME     U2 ED65
 '@S9S_MB_2U_LIB.S9S_MB_2U(SCH_1):PAGE25_I169@PURE_QUANTA.SOCKET4677_AZIF0045P001C01CS(CHIPS)':
 'DDR5_SA_DQ17': CDS_PINID='DDR5_SA_DQ17';
NODE_NAME     J11 31
 '@S9S_MB_2U_LIB.S9S_MB_2U(SCH_1):PAGE92_I25@PURE_QUANTA.SCONN288_ADR50017P130CC(CHIPS)':
 'DQ17_A': CDS_PINID='DQ17_A';
NODE_NAME     J12 31
 '@S9S_MB_2U_LIB.S9S_MB_2U(SCH_1):PAGE93_I24@PURE_QUANTA.SCONN288_ADR50017P087CC(CHIPS)':
 'DQ17_A': CDS_PINID='DQ17_A';
NET_NAME
'M_F_CPU0_SA_DQ<18>'
 '@S9S_MB_2U_LIB.S9S_MB_2U(SCH_1):M_F_CPU0_SA_DQ'<18>:
 C_SIGNAL='@s9s_mb_2u_lib.s9s_mb_2u(sch_1):m_f_cpu0_sa_dq(18)';
NODE_NAME     U2 EG66
 '@S9S_MB_2U_LIB.S9S_MB_2U(SCH_1):PAGE25_I169@PURE_QUANTA.SOCKET4677_AZIF0045P001C01CS(CHIPS)':
 'DDR5_SA_DQ18': CDS_PINID='DDR5_SA_DQ18';
NODE_NAME     J11 174
 '@S9S_MB_2U_LIB.S9S_MB_2U(SCH_1):PAGE92_I25@PURE_QUANTA.SCONN288_ADR50017P130CC(CHIPS)':
 'DQ18_A': CDS_PINID='DQ18_A';
NODE_NAME     J12 174
 '@S9S_MB_2U_LIB.S9S_MB_2U(SCH_1):PAGE93_I24@PURE_QUANTA.SCONN288_ADR50017P087CC(CHIPS)':
 'DQ18_A': CDS_PINID='DQ18_A';
NET_NAME
'M_F_CPU0_SA_DQ<19>'
 '@S9S_MB_2U_LIB.S9S_MB_2U(SCH_1):M_F_CPU0_SA_DQ'<19>:
 C_SIGNAL='@s9s_mb_2u_lib.s9s_mb_2u(sch_1):m_f_cpu0_sa_dq(19)';
NODE_NAME     U2 EH65
 '@S9S_MB_2U_LIB.S9S_MB_2U(SCH_1):PAGE25_I169@PURE_QUANTA.SOCKET4677_AZIF0045P001C01CS(CHIPS)':
 'DDR5_SA_DQ19': CDS_PINID='DDR5_SA_DQ19';
NODE_NAME     J11 176
 '@S9S_MB_2U_LIB.S9S_MB_2U(SCH_1):PAGE92_I25@PURE_QUANTA.SCONN288_ADR50017P130CC(CHIPS)':
 'DQ19_A': CDS_PINID='DQ19_A';
NODE_NAME     J12 176
 '@S9S_MB_2U_LIB.S9S_MB_2U(SCH_1):PAGE93_I24@PURE_QUANTA.SCONN288_ADR50017P087CC(CHIPS)':
 'DQ19_A': CDS_PINID='DQ19_A';
NET_NAME
'M_F_CPU0_SA_DQ<1>'
 '@S9S_MB_2U_LIB.S9S_MB_2U(SCH_1):M_F_CPU0_SA_DQ'<1>:
 C_SIGNAL='@s9s_mb_2u_lib.s9s_mb_2u(sch_1):m_f_cpu0_sa_dq(1)';
NODE_NAME     U2 EH77
 '@S9S_MB_2U_LIB.S9S_MB_2U(SCH_1):PAGE25_I169@PURE_QUANTA.SOCKET4677_AZIF0045P001C01CS(CHIPS)':
 'DDR5_SA_DQ1': CDS_PINID='DDR5_SA_DQ1';
NODE_NAME     J11 9
 '@S9S_MB_2U_LIB.S9S_MB_2U(SCH_1):PAGE92_I25@PURE_QUANTA.SCONN288_ADR50017P130CC(CHIPS)':
 'DQ1_A': CDS_PINID='DQ1_A';
NODE_NAME     J12 9
 '@S9S_MB_2U_LIB.S9S_MB_2U(SCH_1):PAGE93_I24@PURE_QUANTA.SCONN288_ADR50017P087CC(CHIPS)':
 'DQ1_A': CDS_PINID='DQ1_A';
NET_NAME
'M_F_CPU0_SA_DQ<20>'
 '@S9S_MB_2U_LIB.S9S_MB_2U(SCH_1):M_F_CPU0_SA_DQ'<20>:
 C_SIGNAL='@s9s_mb_2u_lib.s9s_mb_2u(sch_1):m_f_cpu0_sa_dq(20)';
NODE_NAME     U2 ED63
 '@S9S_MB_2U_LIB.S9S_MB_2U(SCH_1):PAGE25_I169@PURE_QUANTA.SOCKET4677_AZIF0045P001C01CS(CHIPS)':
 'DDR5_SA_DQ20': CDS_PINID='DDR5_SA_DQ20';
NODE_NAME     J11 36
 '@S9S_MB_2U_LIB.S9S_MB_2U(SCH_1):PAGE92_I25@PURE_QUANTA.SCONN288_ADR50017P130CC(CHIPS)':
 'DQ20_A': CDS_PINID='DQ20_A';
NODE_NAME     J12 36
 '@S9S_MB_2U_LIB.S9S_MB_2U(SCH_1):PAGE93_I24@PURE_QUANTA.SCONN288_ADR50017P087CC(CHIPS)':
 'DQ20_A': CDS_PINID='DQ20_A';
NET_NAME
'M_F_CPU0_SA_DQ<21>'
 '@S9S_MB_2U_LIB.S9S_MB_2U(SCH_1):M_F_CPU0_SA_DQ'<21>:
 C_SIGNAL='@s9s_mb_2u_lib.s9s_mb_2u(sch_1):m_f_cpu0_sa_dq(21)';
NODE_NAME     U2 EE62
 '@S9S_MB_2U_LIB.S9S_MB_2U(SCH_1):PAGE25_I169@PURE_QUANTA.SOCKET4677_AZIF0045P001C01CS(CHIPS)':
 'DDR5_SA_DQ21': CDS_PINID='DDR5_SA_DQ21';
NODE_NAME     J11 38
 '@S9S_MB_2U_LIB.S9S_MB_2U(SCH_1):PAGE92_I25@PURE_QUANTA.SCONN288_ADR50017P130CC(CHIPS)':
 'DQ21_A': CDS_PINID='DQ21_A';
NODE_NAME     J12 38
 '@S9S_MB_2U_LIB.S9S_MB_2U(SCH_1):PAGE93_I24@PURE_QUANTA.SCONN288_ADR50017P087CC(CHIPS)':
 'DQ21_A': CDS_PINID='DQ21_A';
NET_NAME
'M_F_CPU0_SA_DQ<22>'
 '@S9S_MB_2U_LIB.S9S_MB_2U(SCH_1):M_F_CPU0_SA_DQ'<22>:
 C_SIGNAL='@s9s_mb_2u_lib.s9s_mb_2u(sch_1):m_f_cpu0_sa_dq(22)';
NODE_NAME     U2 EH63
 '@S9S_MB_2U_LIB.S9S_MB_2U(SCH_1):PAGE25_I169@PURE_QUANTA.SOCKET4677_AZIF0045P001C01CS(CHIPS)':
 'DDR5_SA_DQ22': CDS_PINID='DDR5_SA_DQ22';
NODE_NAME     J11 181
 '@S9S_MB_2U_LIB.S9S_MB_2U(SCH_1):PAGE92_I25@PURE_QUANTA.SCONN288_ADR50017P130CC(CHIPS)':
 'DQ22_A': CDS_PINID='DQ22_A';
NODE_NAME     J12 181
 '@S9S_MB_2U_LIB.S9S_MB_2U(SCH_1):PAGE93_I24@PURE_QUANTA.SCONN288_ADR50017P087CC(CHIPS)':
 'DQ22_A': CDS_PINID='DQ22_A';
NET_NAME
'M_F_CPU0_SA_DQ<23>'
 '@S9S_MB_2U_LIB.S9S_MB_2U(SCH_1):M_F_CPU0_SA_DQ'<23>:
 C_SIGNAL='@s9s_mb_2u_lib.s9s_mb_2u(sch_1):m_f_cpu0_sa_dq(23)';
NODE_NAME     U2 EG62
 '@S9S_MB_2U_LIB.S9S_MB_2U(SCH_1):PAGE25_I169@PURE_QUANTA.SOCKET4677_AZIF0045P001C01CS(CHIPS)':
 'DDR5_SA_DQ23': CDS_PINID='DDR5_SA_DQ23';
NODE_NAME     J11 183
 '@S9S_MB_2U_LIB.S9S_MB_2U(SCH_1):PAGE92_I25@PURE_QUANTA.SCONN288_ADR50017P130CC(CHIPS)':
 'DQ23_A': CDS_PINID='DQ23_A';
NODE_NAME     J12 183
 '@S9S_MB_2U_LIB.S9S_MB_2U(SCH_1):PAGE93_I24@PURE_QUANTA.SCONN288_ADR50017P087CC(CHIPS)':
 'DQ23_A': CDS_PINID='DQ23_A';
NET_NAME
'M_F_CPU0_SA_DQ<24>'
 '@S9S_MB_2U_LIB.S9S_MB_2U(SCH_1):M_F_CPU0_SA_DQ'<24>:
 C_SIGNAL='@s9s_mb_2u_lib.s9s_mb_2u(sch_1):m_f_cpu0_sa_dq(24)';
NODE_NAME     U2 DV57
 '@S9S_MB_2U_LIB.S9S_MB_2U(SCH_1):PAGE25_I169@PURE_QUANTA.SOCKET4677_AZIF0045P001C01CS(CHIPS)':
 'DDR5_SA_DQ24': CDS_PINID='DDR5_SA_DQ24';
NODE_NAME     J11 40
 '@S9S_MB_2U_LIB.S9S_MB_2U(SCH_1):PAGE92_I25@PURE_QUANTA.SCONN288_ADR50017P130CC(CHIPS)':
 'DQ24_A': CDS_PINID='DQ24_A';
NODE_NAME     J12 40
 '@S9S_MB_2U_LIB.S9S_MB_2U(SCH_1):PAGE93_I24@PURE_QUANTA.SCONN288_ADR50017P087CC(CHIPS)':
 'DQ24_A': CDS_PINID='DQ24_A';
NET_NAME
'M_F_CPU0_SA_DQ<25>'
 '@S9S_MB_2U_LIB.S9S_MB_2U(SCH_1):M_F_CPU0_SA_DQ'<25>:
 C_SIGNAL='@s9s_mb_2u_lib.s9s_mb_2u(sch_1):m_f_cpu0_sa_dq(25)';
NODE_NAME     U2 DU56
 '@S9S_MB_2U_LIB.S9S_MB_2U(SCH_1):PAGE25_I169@PURE_QUANTA.SOCKET4677_AZIF0045P001C01CS(CHIPS)':
 'DDR5_SA_DQ25': CDS_PINID='DDR5_SA_DQ25';
NODE_NAME     J11 42
 '@S9S_MB_2U_LIB.S9S_MB_2U(SCH_1):PAGE92_I25@PURE_QUANTA.SCONN288_ADR50017P130CC(CHIPS)':
 'DQ25_A': CDS_PINID='DQ25_A';
NODE_NAME     J12 42
 '@S9S_MB_2U_LIB.S9S_MB_2U(SCH_1):PAGE93_I24@PURE_QUANTA.SCONN288_ADR50017P087CC(CHIPS)':
 'DQ25_A': CDS_PINID='DQ25_A';
NET_NAME
'M_F_CPU0_SA_DQ<26>'
 '@S9S_MB_2U_LIB.S9S_MB_2U(SCH_1):M_F_CPU0_SA_DQ'<26>:
 C_SIGNAL='@s9s_mb_2u_lib.s9s_mb_2u(sch_1):m_f_cpu0_sa_dq(26)';
NODE_NAME     U2 DY57
 '@S9S_MB_2U_LIB.S9S_MB_2U(SCH_1):PAGE25_I169@PURE_QUANTA.SOCKET4677_AZIF0045P001C01CS(CHIPS)':
 'DDR5_SA_DQ26': CDS_PINID='DDR5_SA_DQ26';
NODE_NAME     J11 185
 '@S9S_MB_2U_LIB.S9S_MB_2U(SCH_1):PAGE92_I25@PURE_QUANTA.SCONN288_ADR50017P130CC(CHIPS)':
 'DQ26_A': CDS_PINID='DQ26_A';
NODE_NAME     J12 185
 '@S9S_MB_2U_LIB.S9S_MB_2U(SCH_1):PAGE93_I24@PURE_QUANTA.SCONN288_ADR50017P087CC(CHIPS)':
 'DQ26_A': CDS_PINID='DQ26_A';
NET_NAME
'M_F_CPU0_SA_DQ<27>'
 '@S9S_MB_2U_LIB.S9S_MB_2U(SCH_1):M_F_CPU0_SA_DQ'<27>:
 C_SIGNAL='@s9s_mb_2u_lib.s9s_mb_2u(sch_1):m_f_cpu0_sa_dq(27)';
NODE_NAME     U2 EA56
 '@S9S_MB_2U_LIB.S9S_MB_2U(SCH_1):PAGE25_I169@PURE_QUANTA.SOCKET4677_AZIF0045P001C01CS(CHIPS)':
 'DDR5_SA_DQ27': CDS_PINID='DDR5_SA_DQ27';
NODE_NAME     J11 187
 '@S9S_MB_2U_LIB.S9S_MB_2U(SCH_1):PAGE92_I25@PURE_QUANTA.SCONN288_ADR50017P130CC(CHIPS)':
 'DQ27_A': CDS_PINID='DQ27_A';
NODE_NAME     J12 187
 '@S9S_MB_2U_LIB.S9S_MB_2U(SCH_1):PAGE93_I24@PURE_QUANTA.SCONN288_ADR50017P087CC(CHIPS)':
 'DQ27_A': CDS_PINID='DQ27_A';
NET_NAME
'M_F_CPU0_SA_DQ<28>'
 '@S9S_MB_2U_LIB.S9S_MB_2U(SCH_1):M_F_CPU0_SA_DQ'<28>:
 C_SIGNAL='@s9s_mb_2u_lib.s9s_mb_2u(sch_1):m_f_cpu0_sa_dq(28)';
NODE_NAME     U2 DU54
 '@S9S_MB_2U_LIB.S9S_MB_2U(SCH_1):PAGE25_I169@PURE_QUANTA.SOCKET4677_AZIF0045P001C01CS(CHIPS)':
 'DDR5_SA_DQ28': CDS_PINID='DDR5_SA_DQ28';
NODE_NAME     J11 47
 '@S9S_MB_2U_LIB.S9S_MB_2U(SCH_1):PAGE92_I25@PURE_QUANTA.SCONN288_ADR50017P130CC(CHIPS)':
 'DQ28_A': CDS_PINID='DQ28_A';
NODE_NAME     J12 47
 '@S9S_MB_2U_LIB.S9S_MB_2U(SCH_1):PAGE93_I24@PURE_QUANTA.SCONN288_ADR50017P087CC(CHIPS)':
 'DQ28_A': CDS_PINID='DQ28_A';
NET_NAME
'M_F_CPU0_SA_DQ<29>'
 '@S9S_MB_2U_LIB.S9S_MB_2U(SCH_1):M_F_CPU0_SA_DQ'<29>:
 C_SIGNAL='@s9s_mb_2u_lib.s9s_mb_2u(sch_1):m_f_cpu0_sa_dq(29)';
NODE_NAME     U2 DV53
 '@S9S_MB_2U_LIB.S9S_MB_2U(SCH_1):PAGE25_I169@PURE_QUANTA.SOCKET4677_AZIF0045P001C01CS(CHIPS)':
 'DDR5_SA_DQ29': CDS_PINID='DDR5_SA_DQ29';
NODE_NAME     J11 49
 '@S9S_MB_2U_LIB.S9S_MB_2U(SCH_1):PAGE92_I25@PURE_QUANTA.SCONN288_ADR50017P130CC(CHIPS)':
 'DQ29_A': CDS_PINID='DQ29_A';
NODE_NAME     J12 49
 '@S9S_MB_2U_LIB.S9S_MB_2U(SCH_1):PAGE93_I24@PURE_QUANTA.SCONN288_ADR50017P087CC(CHIPS)':
 'DQ29_A': CDS_PINID='DQ29_A';
NET_NAME
'M_F_CPU0_SA_DQ<2>'
 '@S9S_MB_2U_LIB.S9S_MB_2U(SCH_1):M_F_CPU0_SA_DQ'<2>:
 C_SIGNAL='@s9s_mb_2u_lib.s9s_mb_2u(sch_1):m_f_cpu0_sa_dq(2)';
NODE_NAME     U2 ED77
 '@S9S_MB_2U_LIB.S9S_MB_2U(SCH_1):PAGE25_I169@PURE_QUANTA.SOCKET4677_AZIF0045P001C01CS(CHIPS)':
 'DDR5_SA_DQ2': CDS_PINID='DDR5_SA_DQ2';
NODE_NAME     J11 152
 '@S9S_MB_2U_LIB.S9S_MB_2U(SCH_1):PAGE92_I25@PURE_QUANTA.SCONN288_ADR50017P130CC(CHIPS)':
 'DQ2_A': CDS_PINID='DQ2_A';
NODE_NAME     J12 152
 '@S9S_MB_2U_LIB.S9S_MB_2U(SCH_1):PAGE93_I24@PURE_QUANTA.SCONN288_ADR50017P087CC(CHIPS)':
 'DQ2_A': CDS_PINID='DQ2_A';
NET_NAME
'M_F_CPU0_SA_DQ<30>'
 '@S9S_MB_2U_LIB.S9S_MB_2U(SCH_1):M_F_CPU0_SA_DQ'<30>:
 C_SIGNAL='@s9s_mb_2u_lib.s9s_mb_2u(sch_1):m_f_cpu0_sa_dq(30)';
NODE_NAME     U2 EA54
 '@S9S_MB_2U_LIB.S9S_MB_2U(SCH_1):PAGE25_I169@PURE_QUANTA.SOCKET4677_AZIF0045P001C01CS(CHIPS)':
 'DDR5_SA_DQ30': CDS_PINID='DDR5_SA_DQ30';
NODE_NAME     J11 192
 '@S9S_MB_2U_LIB.S9S_MB_2U(SCH_1):PAGE92_I25@PURE_QUANTA.SCONN288_ADR50017P130CC(CHIPS)':
 'DQ30_A': CDS_PINID='DQ30_A';
NODE_NAME     J12 192
 '@S9S_MB_2U_LIB.S9S_MB_2U(SCH_1):PAGE93_I24@PURE_QUANTA.SCONN288_ADR50017P087CC(CHIPS)':
 'DQ30_A': CDS_PINID='DQ30_A';
NET_NAME
'M_F_CPU0_SA_DQ<31>'
 '@S9S_MB_2U_LIB.S9S_MB_2U(SCH_1):M_F_CPU0_SA_DQ'<31>:
 C_SIGNAL='@s9s_mb_2u_lib.s9s_mb_2u(sch_1):m_f_cpu0_sa_dq(31)';
NODE_NAME     U2 DY53
 '@S9S_MB_2U_LIB.S9S_MB_2U(SCH_1):PAGE25_I169@PURE_QUANTA.SOCKET4677_AZIF0045P001C01CS(CHIPS)':
 'DDR5_SA_DQ31': CDS_PINID='DDR5_SA_DQ31';
NODE_NAME     J11 194
 '@S9S_MB_2U_LIB.S9S_MB_2U(SCH_1):PAGE92_I25@PURE_QUANTA.SCONN288_ADR50017P130CC(CHIPS)':
 'DQ31_A': CDS_PINID='DQ31_A';
NODE_NAME     J12 194
 '@S9S_MB_2U_LIB.S9S_MB_2U(SCH_1):PAGE93_I24@PURE_QUANTA.SCONN288_ADR50017P087CC(CHIPS)':
 'DQ31_A': CDS_PINID='DQ31_A';
NET_NAME
'M_F_CPU0_SA_DQ<3>'
 '@S9S_MB_2U_LIB.S9S_MB_2U(SCH_1):M_F_CPU0_SA_DQ'<3>:
 C_SIGNAL='@s9s_mb_2u_lib.s9s_mb_2u(sch_1):m_f_cpu0_sa_dq(3)';
NODE_NAME     U2 EG78
 '@S9S_MB_2U_LIB.S9S_MB_2U(SCH_1):PAGE25_I169@PURE_QUANTA.SOCKET4677_AZIF0045P001C01CS(CHIPS)':
 'DDR5_SA_DQ3': CDS_PINID='DDR5_SA_DQ3';
NODE_NAME     J11 154
 '@S9S_MB_2U_LIB.S9S_MB_2U(SCH_1):PAGE92_I25@PURE_QUANTA.SCONN288_ADR50017P130CC(CHIPS)':
 'DQ3_A': CDS_PINID='DQ3_A';
NODE_NAME     J12 154
 '@S9S_MB_2U_LIB.S9S_MB_2U(SCH_1):PAGE93_I24@PURE_QUANTA.SCONN288_ADR50017P087CC(CHIPS)':
 'DQ3_A': CDS_PINID='DQ3_A';
NET_NAME
'M_F_CPU0_SA_DQ<4>'
 '@S9S_MB_2U_LIB.S9S_MB_2U(SCH_1):M_F_CPU0_SA_DQ'<4>:
 C_SIGNAL='@s9s_mb_2u_lib.s9s_mb_2u(sch_1):m_f_cpu0_sa_dq(4)';
NODE_NAME     U2 ED75
 '@S9S_MB_2U_LIB.S9S_MB_2U(SCH_1):PAGE25_I169@PURE_QUANTA.SOCKET4677_AZIF0045P001C01CS(CHIPS)':
 'DDR5_SA_DQ4': CDS_PINID='DDR5_SA_DQ4';
NODE_NAME     J11 14
 '@S9S_MB_2U_LIB.S9S_MB_2U(SCH_1):PAGE92_I25@PURE_QUANTA.SCONN288_ADR50017P130CC(CHIPS)':
 'DQ4_A': CDS_PINID='DQ4_A';
NODE_NAME     J12 14
 '@S9S_MB_2U_LIB.S9S_MB_2U(SCH_1):PAGE93_I24@PURE_QUANTA.SCONN288_ADR50017P087CC(CHIPS)':
 'DQ4_A': CDS_PINID='DQ4_A';
NET_NAME
'M_F_CPU0_SA_DQ<5>'
 '@S9S_MB_2U_LIB.S9S_MB_2U(SCH_1):M_F_CPU0_SA_DQ'<5>:
 C_SIGNAL='@s9s_mb_2u_lib.s9s_mb_2u(sch_1):m_f_cpu0_sa_dq(5)';
NODE_NAME     U2 EE74
 '@S9S_MB_2U_LIB.S9S_MB_2U(SCH_1):PAGE25_I169@PURE_QUANTA.SOCKET4677_AZIF0045P001C01CS(CHIPS)':
 'DDR5_SA_DQ5': CDS_PINID='DDR5_SA_DQ5';
NODE_NAME     J11 16
 '@S9S_MB_2U_LIB.S9S_MB_2U(SCH_1):PAGE92_I25@PURE_QUANTA.SCONN288_ADR50017P130CC(CHIPS)':
 'DQ5_A': CDS_PINID='DQ5_A';
NODE_NAME     J12 16
 '@S9S_MB_2U_LIB.S9S_MB_2U(SCH_1):PAGE93_I24@PURE_QUANTA.SCONN288_ADR50017P087CC(CHIPS)':
 'DQ5_A': CDS_PINID='DQ5_A';
NET_NAME
'M_F_CPU0_SA_DQ<6>'
 '@S9S_MB_2U_LIB.S9S_MB_2U(SCH_1):M_F_CPU0_SA_DQ'<6>:
 C_SIGNAL='@s9s_mb_2u_lib.s9s_mb_2u(sch_1):m_f_cpu0_sa_dq(6)';
NODE_NAME     U2 EH75
 '@S9S_MB_2U_LIB.S9S_MB_2U(SCH_1):PAGE25_I169@PURE_QUANTA.SOCKET4677_AZIF0045P001C01CS(CHIPS)':
 'DDR5_SA_DQ6': CDS_PINID='DDR5_SA_DQ6';
NODE_NAME     J11 159
 '@S9S_MB_2U_LIB.S9S_MB_2U(SCH_1):PAGE92_I25@PURE_QUANTA.SCONN288_ADR50017P130CC(CHIPS)':
 'DQ6_A': CDS_PINID='DQ6_A';
NODE_NAME     J12 159
 '@S9S_MB_2U_LIB.S9S_MB_2U(SCH_1):PAGE93_I24@PURE_QUANTA.SCONN288_ADR50017P087CC(CHIPS)':
 'DQ6_A': CDS_PINID='DQ6_A';
NET_NAME
'M_F_CPU0_SA_DQ<7>'
 '@S9S_MB_2U_LIB.S9S_MB_2U(SCH_1):M_F_CPU0_SA_DQ'<7>:
 C_SIGNAL='@s9s_mb_2u_lib.s9s_mb_2u(sch_1):m_f_cpu0_sa_dq(7)';
NODE_NAME     U2 EG74
 '@S9S_MB_2U_LIB.S9S_MB_2U(SCH_1):PAGE25_I169@PURE_QUANTA.SOCKET4677_AZIF0045P001C01CS(CHIPS)':
 'DDR5_SA_DQ7': CDS_PINID='DDR5_SA_DQ7';
NODE_NAME     J11 161
 '@S9S_MB_2U_LIB.S9S_MB_2U(SCH_1):PAGE92_I25@PURE_QUANTA.SCONN288_ADR50017P130CC(CHIPS)':
 'DQ7_A': CDS_PINID='DQ7_A';
NODE_NAME     J12 161
 '@S9S_MB_2U_LIB.S9S_MB_2U(SCH_1):PAGE93_I24@PURE_QUANTA.SCONN288_ADR50017P087CC(CHIPS)':
 'DQ7_A': CDS_PINID='DQ7_A';
NET_NAME
'M_F_CPU0_SA_DQ<8>'
 '@S9S_MB_2U_LIB.S9S_MB_2U(SCH_1):M_F_CPU0_SA_DQ'<8>:
 C_SIGNAL='@s9s_mb_2u_lib.s9s_mb_2u(sch_1):m_f_cpu0_sa_dq(8)';
NODE_NAME     U2 DV69
 '@S9S_MB_2U_LIB.S9S_MB_2U(SCH_1):PAGE25_I169@PURE_QUANTA.SOCKET4677_AZIF0045P001C01CS(CHIPS)':
 'DDR5_SA_DQ8': CDS_PINID='DDR5_SA_DQ8';
NODE_NAME     J11 18
 '@S9S_MB_2U_LIB.S9S_MB_2U(SCH_1):PAGE92_I25@PURE_QUANTA.SCONN288_ADR50017P130CC(CHIPS)':
 'DQ8_A': CDS_PINID='DQ8_A';
NODE_NAME     J12 18
 '@S9S_MB_2U_LIB.S9S_MB_2U(SCH_1):PAGE93_I24@PURE_QUANTA.SCONN288_ADR50017P087CC(CHIPS)':
 'DQ8_A': CDS_PINID='DQ8_A';
NET_NAME
'M_F_CPU0_SA_DQ<9>'
 '@S9S_MB_2U_LIB.S9S_MB_2U(SCH_1):M_F_CPU0_SA_DQ'<9>:
 C_SIGNAL='@s9s_mb_2u_lib.s9s_mb_2u(sch_1):m_f_cpu0_sa_dq(9)';
NODE_NAME     U2 DU68
 '@S9S_MB_2U_LIB.S9S_MB_2U(SCH_1):PAGE25_I169@PURE_QUANTA.SOCKET4677_AZIF0045P001C01CS(CHIPS)':
 'DDR5_SA_DQ9': CDS_PINID='DDR5_SA_DQ9';
NODE_NAME     J11 20
 '@S9S_MB_2U_LIB.S9S_MB_2U(SCH_1):PAGE92_I25@PURE_QUANTA.SCONN288_ADR50017P130CC(CHIPS)':
 'DQ9_A': CDS_PINID='DQ9_A';
NODE_NAME     J12 20
 '@S9S_MB_2U_LIB.S9S_MB_2U(SCH_1):PAGE93_I24@PURE_QUANTA.SCONN288_ADR50017P087CC(CHIPS)':
 'DQ9_A': CDS_PINID='DQ9_A';
NET_NAME
'M_F_CPU0_SA_DQS_DN<0>'
 '@S9S_MB_2U_LIB.S9S_MB_2U(SCH_1):M_F_CPU0_SA_DQS_DN'<0>:
 C_SIGNAL='@s9s_mb_2u_lib.s9s_mb_2u(sch_1):m_f_cpu0_sa_dqs_dn(0)';
NODE_NAME     U2 EE76
 '@S9S_MB_2U_LIB.S9S_MB_2U(SCH_1):PAGE25_I169@PURE_QUANTA.SOCKET4677_AZIF0045P001C01CS(CHIPS)':
 'DDR5_SA_DQS_DN0': CDS_PINID='DDR5_SA_DQS_DN0';
NODE_NAME     J11 12
 '@S9S_MB_2U_LIB.S9S_MB_2U(SCH_1):PAGE92_I178@PURE_QUANTA.SCONN288_ADR50017P130CC(CHIPS)':
 'DQS0_A_C': CDS_PINID='DQS0_A_C';
NODE_NAME     J12 12
 '@S9S_MB_2U_LIB.S9S_MB_2U(SCH_1):PAGE93_I178@PURE_QUANTA.SCONN288_ADR50017P087CC(CHIPS)':
 'DQS0_A_C': CDS_PINID='DQS0_A_C';
NET_NAME
'M_F_CPU0_SA_DQS_DN<1>'
 '@S9S_MB_2U_LIB.S9S_MB_2U(SCH_1):M_F_CPU0_SA_DQS_DN'<1>:
 C_SIGNAL='@s9s_mb_2u_lib.s9s_mb_2u(sch_1):m_f_cpu0_sa_dqs_dn(1)';
NODE_NAME     U2 DT67
 '@S9S_MB_2U_LIB.S9S_MB_2U(SCH_1):PAGE25_I169@PURE_QUANTA.SOCKET4677_AZIF0045P001C01CS(CHIPS)':
 'DDR5_SA_DQS_DN1': CDS_PINID='DDR5_SA_DQS_DN1';
NODE_NAME     J11 23
 '@S9S_MB_2U_LIB.S9S_MB_2U(SCH_1):PAGE92_I178@PURE_QUANTA.SCONN288_ADR50017P130CC(CHIPS)':
 'DQS1_A_C': CDS_PINID='DQS1_A_C';
NODE_NAME     J12 23
 '@S9S_MB_2U_LIB.S9S_MB_2U(SCH_1):PAGE93_I178@PURE_QUANTA.SCONN288_ADR50017P087CC(CHIPS)':
 'DQS1_A_C': CDS_PINID='DQS1_A_C';
NET_NAME
'M_F_CPU0_SA_DQS_DN<2>'
 '@S9S_MB_2U_LIB.S9S_MB_2U(SCH_1):M_F_CPU0_SA_DQS_DN'<2>:
 C_SIGNAL='@s9s_mb_2u_lib.s9s_mb_2u(sch_1):m_f_cpu0_sa_dqs_dn(2)';
NODE_NAME     U2 EC64
 '@S9S_MB_2U_LIB.S9S_MB_2U(SCH_1):PAGE25_I169@PURE_QUANTA.SOCKET4677_AZIF0045P001C01CS(CHIPS)':
 'DDR5_SA_DQS_DN2': CDS_PINID='DDR5_SA_DQS_DN2';
NODE_NAME     J11 34
 '@S9S_MB_2U_LIB.S9S_MB_2U(SCH_1):PAGE92_I178@PURE_QUANTA.SCONN288_ADR50017P130CC(CHIPS)':
 'DQS2_A_C': CDS_PINID='DQS2_A_C';
NODE_NAME     J12 34
 '@S9S_MB_2U_LIB.S9S_MB_2U(SCH_1):PAGE93_I178@PURE_QUANTA.SCONN288_ADR50017P087CC(CHIPS)':
 'DQS2_A_C': CDS_PINID='DQS2_A_C';
NET_NAME
'M_F_CPU0_SA_DQS_DN<3>'
 '@S9S_MB_2U_LIB.S9S_MB_2U(SCH_1):M_F_CPU0_SA_DQS_DN'<3>:
 C_SIGNAL='@s9s_mb_2u_lib.s9s_mb_2u(sch_1):m_f_cpu0_sa_dqs_dn(3)';
NODE_NAME     U2 DV55
 '@S9S_MB_2U_LIB.S9S_MB_2U(SCH_1):PAGE25_I169@PURE_QUANTA.SOCKET4677_AZIF0045P001C01CS(CHIPS)':
 'DDR5_SA_DQS_DN3': CDS_PINID='DDR5_SA_DQS_DN3';
NODE_NAME     J11 45
 '@S9S_MB_2U_LIB.S9S_MB_2U(SCH_1):PAGE92_I178@PURE_QUANTA.SCONN288_ADR50017P130CC(CHIPS)':
 'DQS3_A_C': CDS_PINID='DQS3_A_C';
NODE_NAME     J12 45
 '@S9S_MB_2U_LIB.S9S_MB_2U(SCH_1):PAGE93_I178@PURE_QUANTA.SCONN288_ADR50017P087CC(CHIPS)':
 'DQS3_A_C': CDS_PINID='DQS3_A_C';
NET_NAME
'M_F_CPU0_SA_DQS_DN<4>'
 '@S9S_MB_2U_LIB.S9S_MB_2U(SCH_1):M_F_CPU0_SA_DQS_DN'<4>:
 C_SIGNAL='@s9s_mb_2u_lib.s9s_mb_2u(sch_1):m_f_cpu0_sa_dqs_dn(4)';
NODE_NAME     U2 EE58
 '@S9S_MB_2U_LIB.S9S_MB_2U(SCH_1):PAGE25_I169@PURE_QUANTA.SOCKET4677_AZIF0045P001C01CS(CHIPS)':
 'DDR5_SA_DQS_DN4': CDS_PINID='DDR5_SA_DQS_DN4';
NODE_NAME     J11 56
 '@S9S_MB_2U_LIB.S9S_MB_2U(SCH_1):PAGE92_I178@PURE_QUANTA.SCONN288_ADR50017P130CC(CHIPS)':
 'DQS4_A_C': CDS_PINID='DQS4_A_C';
NODE_NAME     J12 56
 '@S9S_MB_2U_LIB.S9S_MB_2U(SCH_1):PAGE93_I178@PURE_QUANTA.SCONN288_ADR50017P087CC(CHIPS)':
 'DQS4_A_C': CDS_PINID='DQS4_A_C';
NET_NAME
'M_F_CPU0_SA_DQS_DN<5>'
 '@S9S_MB_2U_LIB.S9S_MB_2U(SCH_1):M_F_CPU0_SA_DQS_DN'<5>:
 C_SIGNAL='@s9s_mb_2u_lib.s9s_mb_2u(sch_1):m_f_cpu0_sa_dqs_dn(5)';
NODE_NAME     U2 EJ76
 '@S9S_MB_2U_LIB.S9S_MB_2U(SCH_1):PAGE25_I169@PURE_QUANTA.SOCKET4677_AZIF0045P001C01CS(CHIPS)':
 'DDR5_SA_DQS_DN5': CDS_PINID='DDR5_SA_DQS_DN5';
NODE_NAME     J11 156
 '@S9S_MB_2U_LIB.S9S_MB_2U(SCH_1):PAGE92_I178@PURE_QUANTA.SCONN288_ADR50017P130CC(CHIPS)':
 'DQS5_A_C||TDQS5_A_C||DQS5_A_T||TDQS5_A_T': CDS_PINID='\dqs5_a_c||tdqs5_a_c||dqs5_a_t||tdqs5_a_t\';
NODE_NAME     J12 156
 '@S9S_MB_2U_LIB.S9S_MB_2U(SCH_1):PAGE93_I178@PURE_QUANTA.SCONN288_ADR50017P087CC(CHIPS)':
 'DQS5_A_C||TDQS5_A_C||DQS5_A_T||TDQS5_A_T': CDS_PINID='\dqs5_a_c||tdqs5_a_c||dqs5_a_t||tdqs5_a_t\';
NET_NAME
'M_F_CPU0_SA_DQS_DN<6>'
 '@S9S_MB_2U_LIB.S9S_MB_2U(SCH_1):M_F_CPU0_SA_DQS_DN'<6>:
 C_SIGNAL='@s9s_mb_2u_lib.s9s_mb_2u(sch_1):m_f_cpu0_sa_dqs_dn(6)';
NODE_NAME     U2 EB67
 '@S9S_MB_2U_LIB.S9S_MB_2U(SCH_1):PAGE25_I169@PURE_QUANTA.SOCKET4677_AZIF0045P001C01CS(CHIPS)':
 'DDR5_SA_DQS_DN6': CDS_PINID='DDR5_SA_DQS_DN6';
NODE_NAME     J11 167
 '@S9S_MB_2U_LIB.S9S_MB_2U(SCH_1):PAGE92_I178@PURE_QUANTA.SCONN288_ADR50017P130CC(CHIPS)':
 'DQS6_A_C||TDQS6_A_C||DQS6_A_T||TDQS6_A_T': CDS_PINID='\dqs6_a_c||tdqs6_a_c||dqs6_a_t||tdqs6_a_t\';
NODE_NAME     J12 167
 '@S9S_MB_2U_LIB.S9S_MB_2U(SCH_1):PAGE93_I178@PURE_QUANTA.SCONN288_ADR50017P087CC(CHIPS)':
 'DQS6_A_C||TDQS6_A_C||DQS6_A_T||TDQS6_A_T': CDS_PINID='\dqs6_a_c||tdqs6_a_c||dqs6_a_t||tdqs6_a_t\';
NET_NAME
'M_F_CPU0_SA_DQS_DN<7>'
 '@S9S_MB_2U_LIB.S9S_MB_2U(SCH_1):M_F_CPU0_SA_DQS_DN'<7>:
 C_SIGNAL='@s9s_mb_2u_lib.s9s_mb_2u(sch_1):m_f_cpu0_sa_dqs_dn(7)';
NODE_NAME     U2 EJ64
 '@S9S_MB_2U_LIB.S9S_MB_2U(SCH_1):PAGE25_I169@PURE_QUANTA.SOCKET4677_AZIF0045P001C01CS(CHIPS)':
 'DDR5_SA_DQS_DN7': CDS_PINID='DDR5_SA_DQS_DN7';
NODE_NAME     J11 178
 '@S9S_MB_2U_LIB.S9S_MB_2U(SCH_1):PAGE92_I178@PURE_QUANTA.SCONN288_ADR50017P130CC(CHIPS)':
 'DQS7_A_C||TDQS7_A_C': CDS_PINID='\dqs7_a_c||tdqs7_a_c\';
NODE_NAME     J12 178
 '@S9S_MB_2U_LIB.S9S_MB_2U(SCH_1):PAGE93_I178@PURE_QUANTA.SCONN288_ADR50017P087CC(CHIPS)':
 'DQS7_A_C||TDQS7_A_C': CDS_PINID='\dqs7_a_c||tdqs7_a_c\';
NET_NAME
'M_F_CPU0_SA_DQS_DN<8>'
 '@S9S_MB_2U_LIB.S9S_MB_2U(SCH_1):M_F_CPU0_SA_DQS_DN'<8>:
 C_SIGNAL='@s9s_mb_2u_lib.s9s_mb_2u(sch_1):m_f_cpu0_sa_dqs_dn(8)';
NODE_NAME     U2 EB55
 '@S9S_MB_2U_LIB.S9S_MB_2U(SCH_1):PAGE25_I169@PURE_QUANTA.SOCKET4677_AZIF0045P001C01CS(CHIPS)':
 'DDR5_SA_DQS_DN8': CDS_PINID='DDR5_SA_DQS_DN8';
NODE_NAME     J11 189
 '@S9S_MB_2U_LIB.S9S_MB_2U(SCH_1):PAGE92_I178@PURE_QUANTA.SCONN288_ADR50017P130CC(CHIPS)':
 'DQS8_A_C||TDQS8_A_C': CDS_PINID='\dqs8_a_c||tdqs8_a_c\';
NODE_NAME     J12 189
 '@S9S_MB_2U_LIB.S9S_MB_2U(SCH_1):PAGE93_I178@PURE_QUANTA.SCONN288_ADR50017P087CC(CHIPS)':
 'DQS8_A_C||TDQS8_A_C': CDS_PINID='\dqs8_a_c||tdqs8_a_c\';
NET_NAME
'M_F_CPU0_SA_DQS_DN<9>'
 '@S9S_MB_2U_LIB.S9S_MB_2U(SCH_1):M_F_CPU0_SA_DQS_DN'<9>:
 C_SIGNAL='@s9s_mb_2u_lib.s9s_mb_2u(sch_1):m_f_cpu0_sa_dqs_dn(9)';
NODE_NAME     U2 EJ58
 '@S9S_MB_2U_LIB.S9S_MB_2U(SCH_1):PAGE25_I169@PURE_QUANTA.SOCKET4677_AZIF0045P001C01CS(CHIPS)':
 'DDR5_SA_DQS_DN9': CDS_PINID='DDR5_SA_DQS_DN9';
NODE_NAME     J11 200
 '@S9S_MB_2U_LIB.S9S_MB_2U(SCH_1):PAGE92_I178@PURE_QUANTA.SCONN288_ADR50017P130CC(CHIPS)':
 'DQS9_A_C||TDQS9_A_C': CDS_PINID='\dqs9_a_c||tdqs9_a_c\';
NODE_NAME     J12 200
 '@S9S_MB_2U_LIB.S9S_MB_2U(SCH_1):PAGE93_I178@PURE_QUANTA.SCONN288_ADR50017P087CC(CHIPS)':
 'DQS9_A_C||TDQS9_A_C': CDS_PINID='\dqs9_a_c||tdqs9_a_c\';
NET_NAME
'M_F_CPU0_SA_DQS_DP<0>'
 '@S9S_MB_2U_LIB.S9S_MB_2U(SCH_1):M_F_CPU0_SA_DQS_DP'<0>:
 C_SIGNAL='@s9s_mb_2u_lib.s9s_mb_2u(sch_1):m_f_cpu0_sa_dqs_dp(0)';
NODE_NAME     U2 EC76
 '@S9S_MB_2U_LIB.S9S_MB_2U(SCH_1):PAGE25_I169@PURE_QUANTA.SOCKET4677_AZIF0045P001C01CS(CHIPS)':
 'DDR5_SA_DQS_DP0': CDS_PINID='DDR5_SA_DQS_DP0';
NODE_NAME     J11 11
 '@S9S_MB_2U_LIB.S9S_MB_2U(SCH_1):PAGE92_I178@PURE_QUANTA.SCONN288_ADR50017P130CC(CHIPS)':
 'DQS0_A_T': CDS_PINID='DQS0_A_T';
NODE_NAME     J12 11
 '@S9S_MB_2U_LIB.S9S_MB_2U(SCH_1):PAGE93_I178@PURE_QUANTA.SCONN288_ADR50017P087CC(CHIPS)':
 'DQS0_A_T': CDS_PINID='DQS0_A_T';
NET_NAME
'M_F_CPU0_SA_DQS_DP<1>'
 '@S9S_MB_2U_LIB.S9S_MB_2U(SCH_1):M_F_CPU0_SA_DQS_DP'<1>:
 C_SIGNAL='@s9s_mb_2u_lib.s9s_mb_2u(sch_1):m_f_cpu0_sa_dqs_dp(1)';
NODE_NAME     U2 DV67
 '@S9S_MB_2U_LIB.S9S_MB_2U(SCH_1):PAGE25_I169@PURE_QUANTA.SOCKET4677_AZIF0045P001C01CS(CHIPS)':
 'DDR5_SA_DQS_DP1': CDS_PINID='DDR5_SA_DQS_DP1';
NODE_NAME     J11 22
 '@S9S_MB_2U_LIB.S9S_MB_2U(SCH_1):PAGE92_I178@PURE_QUANTA.SCONN288_ADR50017P130CC(CHIPS)':
 'DQS1_A_T': CDS_PINID='DQS1_A_T';
NODE_NAME     J12 22
 '@S9S_MB_2U_LIB.S9S_MB_2U(SCH_1):PAGE93_I178@PURE_QUANTA.SCONN288_ADR50017P087CC(CHIPS)':
 'DQS1_A_T': CDS_PINID='DQS1_A_T';
NET_NAME
'M_F_CPU0_SA_DQS_DP<2>'
 '@S9S_MB_2U_LIB.S9S_MB_2U(SCH_1):M_F_CPU0_SA_DQS_DP'<2>:
 C_SIGNAL='@s9s_mb_2u_lib.s9s_mb_2u(sch_1):m_f_cpu0_sa_dqs_dp(2)';
NODE_NAME     U2 EE64
 '@S9S_MB_2U_LIB.S9S_MB_2U(SCH_1):PAGE25_I169@PURE_QUANTA.SOCKET4677_AZIF0045P001C01CS(CHIPS)':
 'DDR5_SA_DQS_DP2': CDS_PINID='DDR5_SA_DQS_DP2';
NODE_NAME     J11 33
 '@S9S_MB_2U_LIB.S9S_MB_2U(SCH_1):PAGE92_I178@PURE_QUANTA.SCONN288_ADR50017P130CC(CHIPS)':
 'DQS2_A_T': CDS_PINID='DQS2_A_T';
NODE_NAME     J12 33
 '@S9S_MB_2U_LIB.S9S_MB_2U(SCH_1):PAGE93_I178@PURE_QUANTA.SCONN288_ADR50017P087CC(CHIPS)':
 'DQS2_A_T': CDS_PINID='DQS2_A_T';
NET_NAME
'M_F_CPU0_SA_DQS_DP<3>'
 '@S9S_MB_2U_LIB.S9S_MB_2U(SCH_1):M_F_CPU0_SA_DQS_DP'<3>:
 C_SIGNAL='@s9s_mb_2u_lib.s9s_mb_2u(sch_1):m_f_cpu0_sa_dqs_dp(3)';
NODE_NAME     U2 DT55
 '@S9S_MB_2U_LIB.S9S_MB_2U(SCH_1):PAGE25_I169@PURE_QUANTA.SOCKET4677_AZIF0045P001C01CS(CHIPS)':
 'DDR5_SA_DQS_DP3': CDS_PINID='DDR5_SA_DQS_DP3';
NODE_NAME     J11 44
 '@S9S_MB_2U_LIB.S9S_MB_2U(SCH_1):PAGE92_I178@PURE_QUANTA.SCONN288_ADR50017P130CC(CHIPS)':
 'DQS3_A_T': CDS_PINID='DQS3_A_T';
NODE_NAME     J12 44
 '@S9S_MB_2U_LIB.S9S_MB_2U(SCH_1):PAGE93_I178@PURE_QUANTA.SCONN288_ADR50017P087CC(CHIPS)':
 'DQS3_A_T': CDS_PINID='DQS3_A_T';
NET_NAME
'M_F_CPU0_SA_DQS_DP<4>'
 '@S9S_MB_2U_LIB.S9S_MB_2U(SCH_1):M_F_CPU0_SA_DQS_DP'<4>:
 C_SIGNAL='@s9s_mb_2u_lib.s9s_mb_2u(sch_1):m_f_cpu0_sa_dqs_dp(4)';
NODE_NAME     U2 EC58
 '@S9S_MB_2U_LIB.S9S_MB_2U(SCH_1):PAGE25_I169@PURE_QUANTA.SOCKET4677_AZIF0045P001C01CS(CHIPS)':
 'DDR5_SA_DQS_DP4': CDS_PINID='DDR5_SA_DQS_DP4';
NODE_NAME     J11 55
 '@S9S_MB_2U_LIB.S9S_MB_2U(SCH_1):PAGE92_I178@PURE_QUANTA.SCONN288_ADR50017P130CC(CHIPS)':
 'DQS4_A_T': CDS_PINID='DQS4_A_T';
NODE_NAME     J12 55
 '@S9S_MB_2U_LIB.S9S_MB_2U(SCH_1):PAGE93_I178@PURE_QUANTA.SCONN288_ADR50017P087CC(CHIPS)':
 'DQS4_A_T': CDS_PINID='DQS4_A_T';
NET_NAME
'M_F_CPU0_SA_DQS_DP<5>'
 '@S9S_MB_2U_LIB.S9S_MB_2U(SCH_1):M_F_CPU0_SA_DQS_DP'<5>:
 C_SIGNAL='@s9s_mb_2u_lib.s9s_mb_2u(sch_1):m_f_cpu0_sa_dqs_dp(5)';
NODE_NAME     U2 EG76
 '@S9S_MB_2U_LIB.S9S_MB_2U(SCH_1):PAGE25_I169@PURE_QUANTA.SOCKET4677_AZIF0045P001C01CS(CHIPS)':
 'DDR5_SA_DQS_DP5': CDS_PINID='DDR5_SA_DQS_DP5';
NODE_NAME     J11 157
 '@S9S_MB_2U_LIB.S9S_MB_2U(SCH_1):PAGE92_I178@PURE_QUANTA.SCONN288_ADR50017P130CC(CHIPS)':
 'DQS5_A_T||TDQS5_A_T': CDS_PINID='\dqs5_a_t||tdqs5_a_t\';
NODE_NAME     J12 157
 '@S9S_MB_2U_LIB.S9S_MB_2U(SCH_1):PAGE93_I178@PURE_QUANTA.SCONN288_ADR50017P087CC(CHIPS)':
 'DQS5_A_T||TDQS5_A_T': CDS_PINID='\dqs5_a_t||tdqs5_a_t\';
NET_NAME
'M_F_CPU0_SA_DQS_DP<6>'
 '@S9S_MB_2U_LIB.S9S_MB_2U(SCH_1):M_F_CPU0_SA_DQS_DP'<6>:
 C_SIGNAL='@s9s_mb_2u_lib.s9s_mb_2u(sch_1):m_f_cpu0_sa_dqs_dp(6)';
NODE_NAME     U2 DY67
 '@S9S_MB_2U_LIB.S9S_MB_2U(SCH_1):PAGE25_I169@PURE_QUANTA.SOCKET4677_AZIF0045P001C01CS(CHIPS)':
 'DDR5_SA_DQS_DP6': CDS_PINID='DDR5_SA_DQS_DP6';
NODE_NAME     J11 168
 '@S9S_MB_2U_LIB.S9S_MB_2U(SCH_1):PAGE92_I178@PURE_QUANTA.SCONN288_ADR50017P130CC(CHIPS)':
 'DQS6_A_T||TDQS6_A_T': CDS_PINID='\dqs6_a_t||tdqs6_a_t\';
NODE_NAME     J12 168
 '@S9S_MB_2U_LIB.S9S_MB_2U(SCH_1):PAGE93_I178@PURE_QUANTA.SCONN288_ADR50017P087CC(CHIPS)':
 'DQS6_A_T||TDQS6_A_T': CDS_PINID='\dqs6_a_t||tdqs6_a_t\';
NET_NAME
'M_F_CPU0_SA_DQS_DP<7>'
 '@S9S_MB_2U_LIB.S9S_MB_2U(SCH_1):M_F_CPU0_SA_DQS_DP'<7>:
 C_SIGNAL='@s9s_mb_2u_lib.s9s_mb_2u(sch_1):m_f_cpu0_sa_dqs_dp(7)';
NODE_NAME     U2 EG64
 '@S9S_MB_2U_LIB.S9S_MB_2U(SCH_1):PAGE25_I169@PURE_QUANTA.SOCKET4677_AZIF0045P001C01CS(CHIPS)':
 'DDR5_SA_DQS_DP7': CDS_PINID='DDR5_SA_DQS_DP7';
NODE_NAME     J11 179
 '@S9S_MB_2U_LIB.S9S_MB_2U(SCH_1):PAGE92_I178@PURE_QUANTA.SCONN288_ADR50017P130CC(CHIPS)':
 'DQS7_A_T||TDQS7_A_T': CDS_PINID='\dqs7_a_t||tdqs7_a_t\';
NODE_NAME     J12 179
 '@S9S_MB_2U_LIB.S9S_MB_2U(SCH_1):PAGE93_I178@PURE_QUANTA.SCONN288_ADR50017P087CC(CHIPS)':
 'DQS7_A_T||TDQS7_A_T': CDS_PINID='\dqs7_a_t||tdqs7_a_t\';
NET_NAME
'M_F_CPU0_SA_DQS_DP<8>'
 '@S9S_MB_2U_LIB.S9S_MB_2U(SCH_1):M_F_CPU0_SA_DQS_DP'<8>:
 C_SIGNAL='@s9s_mb_2u_lib.s9s_mb_2u(sch_1):m_f_cpu0_sa_dqs_dp(8)';
NODE_NAME     U2 DY55
 '@S9S_MB_2U_LIB.S9S_MB_2U(SCH_1):PAGE25_I169@PURE_QUANTA.SOCKET4677_AZIF0045P001C01CS(CHIPS)':
 'DDR5_SA_DQS_DP8': CDS_PINID='DDR5_SA_DQS_DP8';
NODE_NAME     J11 190
 '@S9S_MB_2U_LIB.S9S_MB_2U(SCH_1):PAGE92_I178@PURE_QUANTA.SCONN288_ADR50017P130CC(CHIPS)':
 'DQS8_A_T||TDQS8_A_T': CDS_PINID='\dqs8_a_t||tdqs8_a_t\';
NODE_NAME     J12 190
 '@S9S_MB_2U_LIB.S9S_MB_2U(SCH_1):PAGE93_I178@PURE_QUANTA.SCONN288_ADR50017P087CC(CHIPS)':
 'DQS8_A_T||TDQS8_A_T': CDS_PINID='\dqs8_a_t||tdqs8_a_t\';
NET_NAME
'M_F_CPU0_SA_DQS_DP<9>'
 '@S9S_MB_2U_LIB.S9S_MB_2U(SCH_1):M_F_CPU0_SA_DQS_DP'<9>:
 C_SIGNAL='@s9s_mb_2u_lib.s9s_mb_2u(sch_1):m_f_cpu0_sa_dqs_dp(9)';
NODE_NAME     U2 EG58
 '@S9S_MB_2U_LIB.S9S_MB_2U(SCH_1):PAGE25_I169@PURE_QUANTA.SOCKET4677_AZIF0045P001C01CS(CHIPS)':
 'DDR5_SA_DQS_DP9': CDS_PINID='DDR5_SA_DQS_DP9';
NODE_NAME     J11 201
 '@S9S_MB_2U_LIB.S9S_MB_2U(SCH_1):PAGE92_I178@PURE_QUANTA.SCONN288_ADR50017P130CC(CHIPS)':
 'DQS9_A_T||TDQS9_A_T': CDS_PINID='\dqs9_a_t||tdqs9_a_t\';
NODE_NAME     J12 201
 '@S9S_MB_2U_LIB.S9S_MB_2U(SCH_1):PAGE93_I178@PURE_QUANTA.SCONN288_ADR50017P087CC(CHIPS)':
 'DQS9_A_T||TDQS9_A_T': CDS_PINID='\dqs9_a_t||tdqs9_a_t\';
NET_NAME
'M_F_CPU0_SA_PAR'
 '@S9S_MB_2U_LIB.S9S_MB_2U(SCH_1):M_F_CPU0_SA_PAR':
 C_SIGNAL='@s9s_mb_2u_lib.s9s_mb_2u(sch_1):m_f_cpu0_sa_par';
NODE_NAME     U2 EA50
 '@S9S_MB_2U_LIB.S9S_MB_2U(SCH_1):PAGE25_I169@PURE_QUANTA.SOCKET4677_AZIF0045P001C01CS(CHIPS)':
 'DDR5_SA_PAR': CDS_PINID='DDR5_SA_PAR';
NODE_NAME     J11 74
 '@S9S_MB_2U_LIB.S9S_MB_2U(SCH_1):PAGE92_I25@PURE_QUANTA.SCONN288_ADR50017P130CC(CHIPS)':
 'PAR_A': CDS_PINID='PAR_A';
NODE_NAME     J12 74
 '@S9S_MB_2U_LIB.S9S_MB_2U(SCH_1):PAGE93_I24@PURE_QUANTA.SCONN288_ADR50017P087CC(CHIPS)':
 'PAR_A': CDS_PINID='PAR_A';
NET_NAME
'M_F_CPU0_SA_RSP<0>'
 '@S9S_MB_2U_LIB.S9S_MB_2U(SCH_1):M_F_CPU0_SA_RSP'<0>:
 C_SIGNAL='@s9s_mb_2u_lib.s9s_mb_2u(sch_1):m_f_cpu0_sa_rsp(0)';
NODE_NAME     U2 DN48
 '@S9S_MB_2U_LIB.S9S_MB_2U(SCH_1):PAGE25_I169@PURE_QUANTA.SOCKET4677_AZIF0045P001C01CS(CHIPS)':
 'DDR5_A_RSP0': CDS_PINID='DDR5_A_RSP0';
NODE_NAME     J11 86
 '@S9S_MB_2U_LIB.S9S_MB_2U(SCH_1):PAGE92_I25@PURE_QUANTA.SCONN288_ADR50017P130CC(CHIPS)':
 'LBD||RSP_A_N': CDS_PINID='\lbd||rsp_a_n\';
NET_NAME
'M_F_CPU0_SA_RSP<1>'
 '@S9S_MB_2U_LIB.S9S_MB_2U(SCH_1):M_F_CPU0_SA_RSP'<1>:
 C_SIGNAL='@s9s_mb_2u_lib.s9s_mb_2u(sch_1):m_f_cpu0_sa_rsp(1)';
NODE_NAME     U2 DP47
 '@S9S_MB_2U_LIB.S9S_MB_2U(SCH_1):PAGE25_I169@PURE_QUANTA.SOCKET4677_AZIF0045P001C01CS(CHIPS)':
 'DDR5_A_RSP1': CDS_PINID='DDR5_A_RSP1';
NODE_NAME     J12 86
 '@S9S_MB_2U_LIB.S9S_MB_2U(SCH_1):PAGE93_I24@PURE_QUANTA.SCONN288_ADR50017P087CC(CHIPS)':
 'LBD||RSP_A_N': CDS_PINID='\lbd||rsp_a_n\';
NET_NAME
'M_F_CPU0_SB_CA<0>'
 '@S9S_MB_2U_LIB.S9S_MB_2U(SCH_1):M_F_CPU0_SB_CA'<0>:
 C_SIGNAL='@s9s_mb_2u_lib.s9s_mb_2u(sch_1):m_f_cpu0_sb_ca(0)';
NODE_NAME     U2 DV51
 '@S9S_MB_2U_LIB.S9S_MB_2U(SCH_1):PAGE25_I169@PURE_QUANTA.SOCKET4677_AZIF0045P001C01CS(CHIPS)':
 'DDR5_SB_CA0': CDS_PINID='DDR5_SB_CA0';
NODE_NAME     J11 76
 '@S9S_MB_2U_LIB.S9S_MB_2U(SCH_1):PAGE92_I25@PURE_QUANTA.SCONN288_ADR50017P130CC(CHIPS)':
 'CA0_B': CDS_PINID='CA0_B';
NODE_NAME     J12 76
 '@S9S_MB_2U_LIB.S9S_MB_2U(SCH_1):PAGE93_I24@PURE_QUANTA.SCONN288_ADR50017P087CC(CHIPS)':
 'CA0_B': CDS_PINID='CA0_B';
NET_NAME
'M_F_CPU0_SB_CA<1>'
 '@S9S_MB_2U_LIB.S9S_MB_2U(SCH_1):M_F_CPU0_SB_CA'<1>:
 C_SIGNAL='@s9s_mb_2u_lib.s9s_mb_2u(sch_1):m_f_cpu0_sb_ca(1)';
NODE_NAME     U2 DU50
 '@S9S_MB_2U_LIB.S9S_MB_2U(SCH_1):PAGE25_I169@PURE_QUANTA.SOCKET4677_AZIF0045P001C01CS(CHIPS)':
 'DDR5_SB_CA1': CDS_PINID='DDR5_SB_CA1';
NODE_NAME     J11 221
 '@S9S_MB_2U_LIB.S9S_MB_2U(SCH_1):PAGE92_I25@PURE_QUANTA.SCONN288_ADR50017P130CC(CHIPS)':
 'CA1_B': CDS_PINID='CA1_B';
NODE_NAME     J12 221
 '@S9S_MB_2U_LIB.S9S_MB_2U(SCH_1):PAGE93_I24@PURE_QUANTA.SCONN288_ADR50017P087CC(CHIPS)':
 'CA1_B': CDS_PINID='CA1_B';
NET_NAME
'M_F_CPU0_SB_CA<2>'
 '@S9S_MB_2U_LIB.S9S_MB_2U(SCH_1):M_F_CPU0_SB_CA'<2>:
 C_SIGNAL='@s9s_mb_2u_lib.s9s_mb_2u(sch_1):m_f_cpu0_sb_ca(2)';
NODE_NAME     U2 EE41
 '@S9S_MB_2U_LIB.S9S_MB_2U(SCH_1):PAGE25_I169@PURE_QUANTA.SOCKET4677_AZIF0045P001C01CS(CHIPS)':
 'DDR5_SB_CA2': CDS_PINID='DDR5_SB_CA2';
NODE_NAME     J11 78
 '@S9S_MB_2U_LIB.S9S_MB_2U(SCH_1):PAGE92_I25@PURE_QUANTA.SCONN288_ADR50017P130CC(CHIPS)':
 'CA2_B': CDS_PINID='CA2_B';
NODE_NAME     J12 78
 '@S9S_MB_2U_LIB.S9S_MB_2U(SCH_1):PAGE93_I24@PURE_QUANTA.SCONN288_ADR50017P087CC(CHIPS)':
 'CA2_B': CDS_PINID='CA2_B';
NET_NAME
'M_F_CPU0_SB_CA<3>'
 '@S9S_MB_2U_LIB.S9S_MB_2U(SCH_1):M_F_CPU0_SB_CA'<3>:
 C_SIGNAL='@s9s_mb_2u_lib.s9s_mb_2u(sch_1):m_f_cpu0_sb_ca(3)';
NODE_NAME     U2 EG41
 '@S9S_MB_2U_LIB.S9S_MB_2U(SCH_1):PAGE25_I169@PURE_QUANTA.SOCKET4677_AZIF0045P001C01CS(CHIPS)':
 'DDR5_SB_CA3': CDS_PINID='DDR5_SB_CA3';
NODE_NAME     J11 223
 '@S9S_MB_2U_LIB.S9S_MB_2U(SCH_1):PAGE92_I25@PURE_QUANTA.SCONN288_ADR50017P130CC(CHIPS)':
 'CA3_B': CDS_PINID='CA3_B';
NODE_NAME     J12 223
 '@S9S_MB_2U_LIB.S9S_MB_2U(SCH_1):PAGE93_I24@PURE_QUANTA.SCONN288_ADR50017P087CC(CHIPS)':
 'CA3_B': CDS_PINID='CA3_B';
NET_NAME
'M_F_CPU0_SB_CA<4>'
 '@S9S_MB_2U_LIB.S9S_MB_2U(SCH_1):M_F_CPU0_SB_CA'<4>:
 C_SIGNAL='@s9s_mb_2u_lib.s9s_mb_2u(sch_1):m_f_cpu0_sb_ca(4)';
NODE_NAME     U2 ED40
 '@S9S_MB_2U_LIB.S9S_MB_2U(SCH_1):PAGE25_I169@PURE_QUANTA.SOCKET4677_AZIF0045P001C01CS(CHIPS)':
 'DDR5_SB_CA4': CDS_PINID='DDR5_SB_CA4';
NODE_NAME     J11 80
 '@S9S_MB_2U_LIB.S9S_MB_2U(SCH_1):PAGE92_I25@PURE_QUANTA.SCONN288_ADR50017P130CC(CHIPS)':
 'CA4_B': CDS_PINID='CA4_B';
NODE_NAME     J12 80
 '@S9S_MB_2U_LIB.S9S_MB_2U(SCH_1):PAGE93_I24@PURE_QUANTA.SCONN288_ADR50017P087CC(CHIPS)':
 'CA4_B': CDS_PINID='CA4_B';
NET_NAME
'M_F_CPU0_SB_CA<5>'
 '@S9S_MB_2U_LIB.S9S_MB_2U(SCH_1):M_F_CPU0_SB_CA'<5>:
 C_SIGNAL='@s9s_mb_2u_lib.s9s_mb_2u(sch_1):m_f_cpu0_sb_ca(5)';
NODE_NAME     U2 EH40
 '@S9S_MB_2U_LIB.S9S_MB_2U(SCH_1):PAGE25_I169@PURE_QUANTA.SOCKET4677_AZIF0045P001C01CS(CHIPS)':
 'DDR5_SB_CA5': CDS_PINID='DDR5_SB_CA5';
NODE_NAME     J11 225
 '@S9S_MB_2U_LIB.S9S_MB_2U(SCH_1):PAGE92_I25@PURE_QUANTA.SCONN288_ADR50017P130CC(CHIPS)':
 'CA5_B': CDS_PINID='CA5_B';
NODE_NAME     J12 225
 '@S9S_MB_2U_LIB.S9S_MB_2U(SCH_1):PAGE93_I24@PURE_QUANTA.SCONN288_ADR50017P087CC(CHIPS)':
 'CA5_B': CDS_PINID='CA5_B';
NET_NAME
'M_F_CPU0_SB_CA<6>'
 '@S9S_MB_2U_LIB.S9S_MB_2U(SCH_1):M_F_CPU0_SB_CA'<6>:
 C_SIGNAL='@s9s_mb_2u_lib.s9s_mb_2u(sch_1):m_f_cpu0_sb_ca(6)';
NODE_NAME     U2 EC39
 '@S9S_MB_2U_LIB.S9S_MB_2U(SCH_1):PAGE25_I169@PURE_QUANTA.SOCKET4677_AZIF0045P001C01CS(CHIPS)':
 'DDR5_SB_CA6': CDS_PINID='DDR5_SB_CA6';
NODE_NAME     J11 82
 '@S9S_MB_2U_LIB.S9S_MB_2U(SCH_1):PAGE92_I25@PURE_QUANTA.SCONN288_ADR50017P130CC(CHIPS)':
 'CA6_B': CDS_PINID='CA6_B';
NODE_NAME     J12 82
 '@S9S_MB_2U_LIB.S9S_MB_2U(SCH_1):PAGE93_I24@PURE_QUANTA.SCONN288_ADR50017P087CC(CHIPS)':
 'CA6_B': CDS_PINID='CA6_B';
NET_NAME
'M_F_CPU0_SB_CB<0>'
 '@S9S_MB_2U_LIB.S9S_MB_2U(SCH_1):M_F_CPU0_SB_CB'<0>:
 C_SIGNAL='@s9s_mb_2u_lib.s9s_mb_2u(sch_1):m_f_cpu0_sb_cb(0)';
NODE_NAME     U2 ED32
 '@S9S_MB_2U_LIB.S9S_MB_2U(SCH_1):PAGE25_I169@PURE_QUANTA.SOCKET4677_AZIF0045P001C01CS(CHIPS)':
 'DDR5_SB_ECC0': CDS_PINID='DDR5_SB_ECC0';
NODE_NAME     J11 96
 '@S9S_MB_2U_LIB.S9S_MB_2U(SCH_1):PAGE92_I25@PURE_QUANTA.SCONN288_ADR50017P130CC(CHIPS)':
 'CB0_B': CDS_PINID='CB0_B';
NODE_NAME     J12 96
 '@S9S_MB_2U_LIB.S9S_MB_2U(SCH_1):PAGE93_I24@PURE_QUANTA.SCONN288_ADR50017P087CC(CHIPS)':
 'CB0_B': CDS_PINID='CB0_B';
NET_NAME
'M_F_CPU0_SB_CB<1>'
 '@S9S_MB_2U_LIB.S9S_MB_2U(SCH_1):M_F_CPU0_SB_CB'<1>:
 C_SIGNAL='@s9s_mb_2u_lib.s9s_mb_2u(sch_1):m_f_cpu0_sb_cb(1)';
NODE_NAME     U2 EE31
 '@S9S_MB_2U_LIB.S9S_MB_2U(SCH_1):PAGE25_I169@PURE_QUANTA.SOCKET4677_AZIF0045P001C01CS(CHIPS)':
 'DDR5_SB_ECC1': CDS_PINID='DDR5_SB_ECC1';
NODE_NAME     J11 98
 '@S9S_MB_2U_LIB.S9S_MB_2U(SCH_1):PAGE92_I25@PURE_QUANTA.SCONN288_ADR50017P130CC(CHIPS)':
 'CB1_B': CDS_PINID='CB1_B';
NODE_NAME     J12 98
 '@S9S_MB_2U_LIB.S9S_MB_2U(SCH_1):PAGE93_I24@PURE_QUANTA.SCONN288_ADR50017P087CC(CHIPS)':
 'CB1_B': CDS_PINID='CB1_B';
NET_NAME
'M_F_CPU0_SB_CB<2>'
 '@S9S_MB_2U_LIB.S9S_MB_2U(SCH_1):M_F_CPU0_SB_CB'<2>:
 C_SIGNAL='@s9s_mb_2u_lib.s9s_mb_2u(sch_1):m_f_cpu0_sb_cb(2)';
NODE_NAME     U2 EH32
 '@S9S_MB_2U_LIB.S9S_MB_2U(SCH_1):PAGE25_I169@PURE_QUANTA.SOCKET4677_AZIF0045P001C01CS(CHIPS)':
 'DDR5_SB_ECC2': CDS_PINID='DDR5_SB_ECC2';
NODE_NAME     J11 241
 '@S9S_MB_2U_LIB.S9S_MB_2U(SCH_1):PAGE92_I25@PURE_QUANTA.SCONN288_ADR50017P130CC(CHIPS)':
 'CB2_B': CDS_PINID='CB2_B';
NODE_NAME     J12 241
 '@S9S_MB_2U_LIB.S9S_MB_2U(SCH_1):PAGE93_I24@PURE_QUANTA.SCONN288_ADR50017P087CC(CHIPS)':
 'CB2_B': CDS_PINID='CB2_B';
NET_NAME
'M_F_CPU0_SB_CB<3>'
 '@S9S_MB_2U_LIB.S9S_MB_2U(SCH_1):M_F_CPU0_SB_CB'<3>:
 C_SIGNAL='@s9s_mb_2u_lib.s9s_mb_2u(sch_1):m_f_cpu0_sb_cb(3)';
NODE_NAME     U2 EG31
 '@S9S_MB_2U_LIB.S9S_MB_2U(SCH_1):PAGE25_I169@PURE_QUANTA.SOCKET4677_AZIF0045P001C01CS(CHIPS)':
 'DDR5_SB_ECC3': CDS_PINID='DDR5_SB_ECC3';
NODE_NAME     J11 243
 '@S9S_MB_2U_LIB.S9S_MB_2U(SCH_1):PAGE92_I25@PURE_QUANTA.SCONN288_ADR50017P130CC(CHIPS)':
 'CB3_B': CDS_PINID='CB3_B';
NODE_NAME     J12 243
 '@S9S_MB_2U_LIB.S9S_MB_2U(SCH_1):PAGE93_I24@PURE_QUANTA.SCONN288_ADR50017P087CC(CHIPS)':
 'CB3_B': CDS_PINID='CB3_B';
NET_NAME
'M_F_CPU0_SB_CB<4>'
 '@S9S_MB_2U_LIB.S9S_MB_2U(SCH_1):M_F_CPU0_SB_CB'<4>:
 C_SIGNAL='@s9s_mb_2u_lib.s9s_mb_2u(sch_1):m_f_cpu0_sb_cb(4)';
NODE_NAME     U2 EE35
 '@S9S_MB_2U_LIB.S9S_MB_2U(SCH_1):PAGE25_I169@PURE_QUANTA.SOCKET4677_AZIF0045P001C01CS(CHIPS)':
 'DDR5_SB_ECC4': CDS_PINID='DDR5_SB_ECC4';
NODE_NAME     J11 89
 '@S9S_MB_2U_LIB.S9S_MB_2U(SCH_1):PAGE92_I25@PURE_QUANTA.SCONN288_ADR50017P130CC(CHIPS)':
 'CB4_B': CDS_PINID='CB4_B';
NODE_NAME     J12 89
 '@S9S_MB_2U_LIB.S9S_MB_2U(SCH_1):PAGE93_I24@PURE_QUANTA.SCONN288_ADR50017P087CC(CHIPS)':
 'CB4_B': CDS_PINID='CB4_B';
NET_NAME
'M_F_CPU0_SB_CB<5>'
 '@S9S_MB_2U_LIB.S9S_MB_2U(SCH_1):M_F_CPU0_SB_CB'<5>:
 C_SIGNAL='@s9s_mb_2u_lib.s9s_mb_2u(sch_1):m_f_cpu0_sb_cb(5)';
NODE_NAME     U2 ED34
 '@S9S_MB_2U_LIB.S9S_MB_2U(SCH_1):PAGE25_I169@PURE_QUANTA.SOCKET4677_AZIF0045P001C01CS(CHIPS)':
 'DDR5_SB_ECC5': CDS_PINID='DDR5_SB_ECC5';
NODE_NAME     J11 91
 '@S9S_MB_2U_LIB.S9S_MB_2U(SCH_1):PAGE92_I25@PURE_QUANTA.SCONN288_ADR50017P130CC(CHIPS)':
 'CB5_B': CDS_PINID='CB5_B';
NODE_NAME     J12 91
 '@S9S_MB_2U_LIB.S9S_MB_2U(SCH_1):PAGE93_I24@PURE_QUANTA.SCONN288_ADR50017P087CC(CHIPS)':
 'CB5_B': CDS_PINID='CB5_B';
NET_NAME
'M_F_CPU0_SB_CB<6>'
 '@S9S_MB_2U_LIB.S9S_MB_2U(SCH_1):M_F_CPU0_SB_CB'<6>:
 C_SIGNAL='@s9s_mb_2u_lib.s9s_mb_2u(sch_1):m_f_cpu0_sb_cb(6)';
NODE_NAME     U2 EG35
 '@S9S_MB_2U_LIB.S9S_MB_2U(SCH_1):PAGE25_I169@PURE_QUANTA.SOCKET4677_AZIF0045P001C01CS(CHIPS)':
 'DDR5_SB_ECC6': CDS_PINID='DDR5_SB_ECC6';
NODE_NAME     J11 234
 '@S9S_MB_2U_LIB.S9S_MB_2U(SCH_1):PAGE92_I25@PURE_QUANTA.SCONN288_ADR50017P130CC(CHIPS)':
 'CB6_B': CDS_PINID='CB6_B';
NODE_NAME     J12 234
 '@S9S_MB_2U_LIB.S9S_MB_2U(SCH_1):PAGE93_I24@PURE_QUANTA.SCONN288_ADR50017P087CC(CHIPS)':
 'CB6_B': CDS_PINID='CB6_B';
NET_NAME
'M_F_CPU0_SB_CB<7>'
 '@S9S_MB_2U_LIB.S9S_MB_2U(SCH_1):M_F_CPU0_SB_CB'<7>:
 C_SIGNAL='@s9s_mb_2u_lib.s9s_mb_2u(sch_1):m_f_cpu0_sb_cb(7)';
NODE_NAME     U2 EH34
 '@S9S_MB_2U_LIB.S9S_MB_2U(SCH_1):PAGE25_I169@PURE_QUANTA.SOCKET4677_AZIF0045P001C01CS(CHIPS)':
 'DDR5_SB_ECC7': CDS_PINID='DDR5_SB_ECC7';
NODE_NAME     J11 236
 '@S9S_MB_2U_LIB.S9S_MB_2U(SCH_1):PAGE92_I25@PURE_QUANTA.SCONN288_ADR50017P130CC(CHIPS)':
 'CB7_B': CDS_PINID='CB7_B';
NODE_NAME     J12 236
 '@S9S_MB_2U_LIB.S9S_MB_2U(SCH_1):PAGE93_I24@PURE_QUANTA.SCONN288_ADR50017P087CC(CHIPS)':
 'CB7_B': CDS_PINID='CB7_B';
NET_NAME
'M_F_CPU0_SB_CS_N<0>'
 '@S9S_MB_2U_LIB.S9S_MB_2U(SCH_1):M_F_CPU0_SB_CS_N'<0>:
 C_SIGNAL='@s9s_mb_2u_lib.s9s_mb_2u(sch_1):m_f_cpu0_sb_cs_n(0)';
NODE_NAME     U2 EH38
 '@S9S_MB_2U_LIB.S9S_MB_2U(SCH_1):PAGE25_I169@PURE_QUANTA.SOCKET4677_AZIF0045P001C01CS(CHIPS)':
 'DDR5_SB_CS_N0': CDS_PINID='DDR5_SB_CS_N0';
NODE_NAME     J11 84
 '@S9S_MB_2U_LIB.S9S_MB_2U(SCH_1):PAGE92_I25@PURE_QUANTA.SCONN288_ADR50017P130CC(CHIPS)':
 'CS0_B_N': CDS_PINID='CS0_B_N';
NET_NAME
'M_F_CPU0_SB_CS_N<1>'
 '@S9S_MB_2U_LIB.S9S_MB_2U(SCH_1):M_F_CPU0_SB_CS_N'<1>:
 C_SIGNAL='@s9s_mb_2u_lib.s9s_mb_2u(sch_1):m_f_cpu0_sb_cs_n(1)';
NODE_NAME     U2 EG37
 '@S9S_MB_2U_LIB.S9S_MB_2U(SCH_1):PAGE25_I169@PURE_QUANTA.SOCKET4677_AZIF0045P001C01CS(CHIPS)':
 'DDR5_SB_CS_N1': CDS_PINID='DDR5_SB_CS_N1';
NODE_NAME     J11 229
 '@S9S_MB_2U_LIB.S9S_MB_2U(SCH_1):PAGE92_I25@PURE_QUANTA.SCONN288_ADR50017P130CC(CHIPS)':
 'CS1_B_N': CDS_PINID='CS1_B_N';
NET_NAME
'M_F_CPU0_SB_CS_N<2>'
 '@S9S_MB_2U_LIB.S9S_MB_2U(SCH_1):M_F_CPU0_SB_CS_N'<2>:
 C_SIGNAL='@s9s_mb_2u_lib.s9s_mb_2u(sch_1):m_f_cpu0_sb_cs_n(2)';
NODE_NAME     U2 ED38
 '@S9S_MB_2U_LIB.S9S_MB_2U(SCH_1):PAGE25_I169@PURE_QUANTA.SOCKET4677_AZIF0045P001C01CS(CHIPS)':
 'DDR5_SB_CS_N2': CDS_PINID='DDR5_SB_CS_N2';
NODE_NAME     J12 84
 '@S9S_MB_2U_LIB.S9S_MB_2U(SCH_1):PAGE93_I24@PURE_QUANTA.SCONN288_ADR50017P087CC(CHIPS)':
 'CS0_B_N': CDS_PINID='CS0_B_N';
NET_NAME
'M_F_CPU0_SB_CS_N<3>'
 '@S9S_MB_2U_LIB.S9S_MB_2U(SCH_1):M_F_CPU0_SB_CS_N'<3>:
 C_SIGNAL='@s9s_mb_2u_lib.s9s_mb_2u(sch_1):m_f_cpu0_sb_cs_n(3)';
NODE_NAME     U2 EE37
 '@S9S_MB_2U_LIB.S9S_MB_2U(SCH_1):PAGE25_I169@PURE_QUANTA.SOCKET4677_AZIF0045P001C01CS(CHIPS)':
 'DDR5_SB_CS_N3': CDS_PINID='DDR5_SB_CS_N3';
NODE_NAME     J12 229
 '@S9S_MB_2U_LIB.S9S_MB_2U(SCH_1):PAGE93_I24@PURE_QUANTA.SCONN288_ADR50017P087CC(CHIPS)':
 'CS1_B_N': CDS_PINID='CS1_B_N';
NET_NAME
'M_F_CPU0_SB_DQ<0>'
 '@S9S_MB_2U_LIB.S9S_MB_2U(SCH_1):M_F_CPU0_SB_DQ'<0>:
 C_SIGNAL='@s9s_mb_2u_lib.s9s_mb_2u(sch_1):m_f_cpu0_sb_dq(0)';
NODE_NAME     U2 DV32
 '@S9S_MB_2U_LIB.S9S_MB_2U(SCH_1):PAGE25_I169@PURE_QUANTA.SOCKET4677_AZIF0045P001C01CS(CHIPS)':
 'DDR5_SB_DQ0': CDS_PINID='DDR5_SB_DQ0';
NODE_NAME     J11 100
 '@S9S_MB_2U_LIB.S9S_MB_2U(SCH_1):PAGE92_I25@PURE_QUANTA.SCONN288_ADR50017P130CC(CHIPS)':
 'DQ0_B': CDS_PINID='DQ0_B';
NODE_NAME     J12 100
 '@S9S_MB_2U_LIB.S9S_MB_2U(SCH_1):PAGE93_I24@PURE_QUANTA.SCONN288_ADR50017P087CC(CHIPS)':
 'DQ0_B': CDS_PINID='DQ0_B';
NET_NAME
'M_F_CPU0_SB_DQ<10>'
 '@S9S_MB_2U_LIB.S9S_MB_2U(SCH_1):M_F_CPU0_SB_DQ'<10>:
 C_SIGNAL='@s9s_mb_2u_lib.s9s_mb_2u(sch_1):m_f_cpu0_sb_dq(10)';
NODE_NAME     U2 EG23
 '@S9S_MB_2U_LIB.S9S_MB_2U(SCH_1):PAGE25_I169@PURE_QUANTA.SOCKET4677_AZIF0045P001C01CS(CHIPS)':
 'DDR5_SB_DQ10': CDS_PINID='DDR5_SB_DQ10';
NODE_NAME     J11 256
 '@S9S_MB_2U_LIB.S9S_MB_2U(SCH_1):PAGE92_I25@PURE_QUANTA.SCONN288_ADR50017P130CC(CHIPS)':
 'DQ10_B': CDS_PINID='DQ10_B';
NODE_NAME     J12 256
 '@S9S_MB_2U_LIB.S9S_MB_2U(SCH_1):PAGE93_I24@PURE_QUANTA.SCONN288_ADR50017P087CC(CHIPS)':
 'DQ10_B': CDS_PINID='DQ10_B';
NET_NAME
'M_F_CPU0_SB_DQ<11>'
 '@S9S_MB_2U_LIB.S9S_MB_2U(SCH_1):M_F_CPU0_SB_DQ'<11>:
 C_SIGNAL='@s9s_mb_2u_lib.s9s_mb_2u(sch_1):m_f_cpu0_sb_dq(11)';
NODE_NAME     U2 EH22
 '@S9S_MB_2U_LIB.S9S_MB_2U(SCH_1):PAGE25_I169@PURE_QUANTA.SOCKET4677_AZIF0045P001C01CS(CHIPS)':
 'DDR5_SB_DQ11': CDS_PINID='DDR5_SB_DQ11';
NODE_NAME     J11 258
 '@S9S_MB_2U_LIB.S9S_MB_2U(SCH_1):PAGE92_I25@PURE_QUANTA.SCONN288_ADR50017P130CC(CHIPS)':
 'DQ11_B': CDS_PINID='DQ11_B';
NODE_NAME     J12 258
 '@S9S_MB_2U_LIB.S9S_MB_2U(SCH_1):PAGE93_I24@PURE_QUANTA.SCONN288_ADR50017P087CC(CHIPS)':
 'DQ11_B': CDS_PINID='DQ11_B';
NET_NAME
'M_F_CPU0_SB_DQ<12>'
 '@S9S_MB_2U_LIB.S9S_MB_2U(SCH_1):M_F_CPU0_SB_DQ'<12>:
 C_SIGNAL='@s9s_mb_2u_lib.s9s_mb_2u(sch_1):m_f_cpu0_sb_dq(12)';
NODE_NAME     U2 ED20
 '@S9S_MB_2U_LIB.S9S_MB_2U(SCH_1):PAGE25_I169@PURE_QUANTA.SOCKET4677_AZIF0045P001C01CS(CHIPS)':
 'DDR5_SB_DQ12': CDS_PINID='DDR5_SB_DQ12';
NODE_NAME     J11 118
 '@S9S_MB_2U_LIB.S9S_MB_2U(SCH_1):PAGE92_I25@PURE_QUANTA.SCONN288_ADR50017P130CC(CHIPS)':
 'DQ12_B': CDS_PINID='DQ12_B';
NODE_NAME     J12 118
 '@S9S_MB_2U_LIB.S9S_MB_2U(SCH_1):PAGE93_I24@PURE_QUANTA.SCONN288_ADR50017P087CC(CHIPS)':
 'DQ12_B': CDS_PINID='DQ12_B';
NET_NAME
'M_F_CPU0_SB_DQ<13>'
 '@S9S_MB_2U_LIB.S9S_MB_2U(SCH_1):M_F_CPU0_SB_DQ'<13>:
 C_SIGNAL='@s9s_mb_2u_lib.s9s_mb_2u(sch_1):m_f_cpu0_sb_dq(13)';
NODE_NAME     U2 EE19
 '@S9S_MB_2U_LIB.S9S_MB_2U(SCH_1):PAGE25_I169@PURE_QUANTA.SOCKET4677_AZIF0045P001C01CS(CHIPS)':
 'DDR5_SB_DQ13': CDS_PINID='DDR5_SB_DQ13';
NODE_NAME     J11 120
 '@S9S_MB_2U_LIB.S9S_MB_2U(SCH_1):PAGE92_I25@PURE_QUANTA.SCONN288_ADR50017P130CC(CHIPS)':
 'DQ13_B': CDS_PINID='DQ13_B';
NODE_NAME     J12 120
 '@S9S_MB_2U_LIB.S9S_MB_2U(SCH_1):PAGE93_I24@PURE_QUANTA.SCONN288_ADR50017P087CC(CHIPS)':
 'DQ13_B': CDS_PINID='DQ13_B';
NET_NAME
'M_F_CPU0_SB_DQ<14>'
 '@S9S_MB_2U_LIB.S9S_MB_2U(SCH_1):M_F_CPU0_SB_DQ'<14>:
 C_SIGNAL='@s9s_mb_2u_lib.s9s_mb_2u(sch_1):m_f_cpu0_sb_dq(14)';
NODE_NAME     U2 EH20
 '@S9S_MB_2U_LIB.S9S_MB_2U(SCH_1):PAGE25_I169@PURE_QUANTA.SOCKET4677_AZIF0045P001C01CS(CHIPS)':
 'DDR5_SB_DQ14': CDS_PINID='DDR5_SB_DQ14';
NODE_NAME     J11 263
 '@S9S_MB_2U_LIB.S9S_MB_2U(SCH_1):PAGE92_I25@PURE_QUANTA.SCONN288_ADR50017P130CC(CHIPS)':
 'DQ14_B': CDS_PINID='DQ14_B';
NODE_NAME     J12 263
 '@S9S_MB_2U_LIB.S9S_MB_2U(SCH_1):PAGE93_I24@PURE_QUANTA.SCONN288_ADR50017P087CC(CHIPS)':
 'DQ14_B': CDS_PINID='DQ14_B';
NET_NAME
'M_F_CPU0_SB_DQ<15>'
 '@S9S_MB_2U_LIB.S9S_MB_2U(SCH_1):M_F_CPU0_SB_DQ'<15>:
 C_SIGNAL='@s9s_mb_2u_lib.s9s_mb_2u(sch_1):m_f_cpu0_sb_dq(15)';
NODE_NAME     U2 EG19
 '@S9S_MB_2U_LIB.S9S_MB_2U(SCH_1):PAGE25_I169@PURE_QUANTA.SOCKET4677_AZIF0045P001C01CS(CHIPS)':
 'DDR5_SB_DQ15': CDS_PINID='DDR5_SB_DQ15';
NODE_NAME     J11 265
 '@S9S_MB_2U_LIB.S9S_MB_2U(SCH_1):PAGE92_I25@PURE_QUANTA.SCONN288_ADR50017P130CC(CHIPS)':
 'DQ15_B': CDS_PINID='DQ15_B';
NODE_NAME     J12 265
 '@S9S_MB_2U_LIB.S9S_MB_2U(SCH_1):PAGE93_I24@PURE_QUANTA.SCONN288_ADR50017P087CC(CHIPS)':
 'DQ15_B': CDS_PINID='DQ15_B';
NET_NAME
'M_F_CPU0_SB_DQ<16>'
 '@S9S_MB_2U_LIB.S9S_MB_2U(SCH_1):M_F_CPU0_SB_DQ'<16>:
 C_SIGNAL='@s9s_mb_2u_lib.s9s_mb_2u(sch_1):m_f_cpu0_sb_dq(16)';
NODE_NAME     U2 EM14
 '@S9S_MB_2U_LIB.S9S_MB_2U(SCH_1):PAGE25_I169@PURE_QUANTA.SOCKET4677_AZIF0045P001C01CS(CHIPS)':
 'DDR5_SB_DQ16': CDS_PINID='DDR5_SB_DQ16';
NODE_NAME     J11 122
 '@S9S_MB_2U_LIB.S9S_MB_2U(SCH_1):PAGE92_I25@PURE_QUANTA.SCONN288_ADR50017P130CC(CHIPS)':
 'DQ16_B': CDS_PINID='DQ16_B';
NODE_NAME     J12 122
 '@S9S_MB_2U_LIB.S9S_MB_2U(SCH_1):PAGE93_I24@PURE_QUANTA.SCONN288_ADR50017P087CC(CHIPS)':
 'DQ16_B': CDS_PINID='DQ16_B';
NET_NAME
'M_F_CPU0_SB_DQ<17>'
 '@S9S_MB_2U_LIB.S9S_MB_2U(SCH_1):M_F_CPU0_SB_DQ'<17>:
 C_SIGNAL='@s9s_mb_2u_lib.s9s_mb_2u(sch_1):m_f_cpu0_sb_dq(17)';
NODE_NAME     U2 EL13
 '@S9S_MB_2U_LIB.S9S_MB_2U(SCH_1):PAGE25_I169@PURE_QUANTA.SOCKET4677_AZIF0045P001C01CS(CHIPS)':
 'DDR5_SB_DQ17': CDS_PINID='DDR5_SB_DQ17';
NODE_NAME     J11 124
 '@S9S_MB_2U_LIB.S9S_MB_2U(SCH_1):PAGE92_I25@PURE_QUANTA.SCONN288_ADR50017P130CC(CHIPS)':
 'DQ17_B': CDS_PINID='DQ17_B';
NODE_NAME     J12 124
 '@S9S_MB_2U_LIB.S9S_MB_2U(SCH_1):PAGE93_I24@PURE_QUANTA.SCONN288_ADR50017P087CC(CHIPS)':
 'DQ17_B': CDS_PINID='DQ17_B';
NET_NAME
'M_F_CPU0_SB_DQ<18>'
 '@S9S_MB_2U_LIB.S9S_MB_2U(SCH_1):M_F_CPU0_SB_DQ'<18>:
 C_SIGNAL='@s9s_mb_2u_lib.s9s_mb_2u(sch_1):m_f_cpu0_sb_dq(18)';
NODE_NAME     U2 EP14
 '@S9S_MB_2U_LIB.S9S_MB_2U(SCH_1):PAGE25_I169@PURE_QUANTA.SOCKET4677_AZIF0045P001C01CS(CHIPS)':
 'DDR5_SB_DQ18': CDS_PINID='DDR5_SB_DQ18';
NODE_NAME     J11 267
 '@S9S_MB_2U_LIB.S9S_MB_2U(SCH_1):PAGE92_I25@PURE_QUANTA.SCONN288_ADR50017P130CC(CHIPS)':
 'DQ18_B': CDS_PINID='DQ18_B';
NODE_NAME     J12 267
 '@S9S_MB_2U_LIB.S9S_MB_2U(SCH_1):PAGE93_I24@PURE_QUANTA.SCONN288_ADR50017P087CC(CHIPS)':
 'DQ18_B': CDS_PINID='DQ18_B';
NET_NAME
'M_F_CPU0_SB_DQ<19>'
 '@S9S_MB_2U_LIB.S9S_MB_2U(SCH_1):M_F_CPU0_SB_DQ'<19>:
 C_SIGNAL='@s9s_mb_2u_lib.s9s_mb_2u(sch_1):m_f_cpu0_sb_dq(19)';
NODE_NAME     U2 ER13
 '@S9S_MB_2U_LIB.S9S_MB_2U(SCH_1):PAGE25_I169@PURE_QUANTA.SOCKET4677_AZIF0045P001C01CS(CHIPS)':
 'DDR5_SB_DQ19': CDS_PINID='DDR5_SB_DQ19';
NODE_NAME     J11 269
 '@S9S_MB_2U_LIB.S9S_MB_2U(SCH_1):PAGE92_I25@PURE_QUANTA.SCONN288_ADR50017P130CC(CHIPS)':
 'DQ19_B': CDS_PINID='DQ19_B';
NODE_NAME     J12 269
 '@S9S_MB_2U_LIB.S9S_MB_2U(SCH_1):PAGE93_I24@PURE_QUANTA.SCONN288_ADR50017P087CC(CHIPS)':
 'DQ19_B': CDS_PINID='DQ19_B';
NET_NAME
'M_F_CPU0_SB_DQ<1>'
 '@S9S_MB_2U_LIB.S9S_MB_2U(SCH_1):M_F_CPU0_SB_DQ'<1>:
 C_SIGNAL='@s9s_mb_2u_lib.s9s_mb_2u(sch_1):m_f_cpu0_sb_dq(1)';
NODE_NAME     U2 DU31
 '@S9S_MB_2U_LIB.S9S_MB_2U(SCH_1):PAGE25_I169@PURE_QUANTA.SOCKET4677_AZIF0045P001C01CS(CHIPS)':
 'DDR5_SB_DQ1': CDS_PINID='DDR5_SB_DQ1';
NODE_NAME     J11 102
 '@S9S_MB_2U_LIB.S9S_MB_2U(SCH_1):PAGE92_I25@PURE_QUANTA.SCONN288_ADR50017P130CC(CHIPS)':
 'DQ1_B': CDS_PINID='DQ1_B';
NODE_NAME     J12 102
 '@S9S_MB_2U_LIB.S9S_MB_2U(SCH_1):PAGE93_I24@PURE_QUANTA.SCONN288_ADR50017P087CC(CHIPS)':
 'DQ1_B': CDS_PINID='DQ1_B';
NET_NAME
'M_F_CPU0_SB_DQ<20>'
 '@S9S_MB_2U_LIB.S9S_MB_2U(SCH_1):M_F_CPU0_SB_DQ'<20>:
 C_SIGNAL='@s9s_mb_2u_lib.s9s_mb_2u(sch_1):m_f_cpu0_sb_dq(20)';
NODE_NAME     U2 EL11
 '@S9S_MB_2U_LIB.S9S_MB_2U(SCH_1):PAGE25_I169@PURE_QUANTA.SOCKET4677_AZIF0045P001C01CS(CHIPS)':
 'DDR5_SB_DQ20': CDS_PINID='DDR5_SB_DQ20';
NODE_NAME     J11 129
 '@S9S_MB_2U_LIB.S9S_MB_2U(SCH_1):PAGE92_I25@PURE_QUANTA.SCONN288_ADR50017P130CC(CHIPS)':
 'DQ20_B': CDS_PINID='DQ20_B';
NODE_NAME     J12 129
 '@S9S_MB_2U_LIB.S9S_MB_2U(SCH_1):PAGE93_I24@PURE_QUANTA.SCONN288_ADR50017P087CC(CHIPS)':
 'DQ20_B': CDS_PINID='DQ20_B';
NET_NAME
'M_F_CPU0_SB_DQ<21>'
 '@S9S_MB_2U_LIB.S9S_MB_2U(SCH_1):M_F_CPU0_SB_DQ'<21>:
 C_SIGNAL='@s9s_mb_2u_lib.s9s_mb_2u(sch_1):m_f_cpu0_sb_dq(21)';
NODE_NAME     U2 EM10
 '@S9S_MB_2U_LIB.S9S_MB_2U(SCH_1):PAGE25_I169@PURE_QUANTA.SOCKET4677_AZIF0045P001C01CS(CHIPS)':
 'DDR5_SB_DQ21': CDS_PINID='DDR5_SB_DQ21';
NODE_NAME     J11 131
 '@S9S_MB_2U_LIB.S9S_MB_2U(SCH_1):PAGE92_I25@PURE_QUANTA.SCONN288_ADR50017P130CC(CHIPS)':
 'DQ21_B': CDS_PINID='DQ21_B';
NODE_NAME     J12 131
 '@S9S_MB_2U_LIB.S9S_MB_2U(SCH_1):PAGE93_I24@PURE_QUANTA.SCONN288_ADR50017P087CC(CHIPS)':
 'DQ21_B': CDS_PINID='DQ21_B';
NET_NAME
'M_F_CPU0_SB_DQ<22>'
 '@S9S_MB_2U_LIB.S9S_MB_2U(SCH_1):M_F_CPU0_SB_DQ'<22>:
 C_SIGNAL='@s9s_mb_2u_lib.s9s_mb_2u(sch_1):m_f_cpu0_sb_dq(22)';
NODE_NAME     U2 ER11
 '@S9S_MB_2U_LIB.S9S_MB_2U(SCH_1):PAGE25_I169@PURE_QUANTA.SOCKET4677_AZIF0045P001C01CS(CHIPS)':
 'DDR5_SB_DQ22': CDS_PINID='DDR5_SB_DQ22';
NODE_NAME     J11 274
 '@S9S_MB_2U_LIB.S9S_MB_2U(SCH_1):PAGE92_I25@PURE_QUANTA.SCONN288_ADR50017P130CC(CHIPS)':
 'DQ22_B': CDS_PINID='DQ22_B';
NODE_NAME     J12 274
 '@S9S_MB_2U_LIB.S9S_MB_2U(SCH_1):PAGE93_I24@PURE_QUANTA.SCONN288_ADR50017P087CC(CHIPS)':
 'DQ22_B': CDS_PINID='DQ22_B';
NET_NAME
'M_F_CPU0_SB_DQ<23>'
 '@S9S_MB_2U_LIB.S9S_MB_2U(SCH_1):M_F_CPU0_SB_DQ'<23>:
 C_SIGNAL='@s9s_mb_2u_lib.s9s_mb_2u(sch_1):m_f_cpu0_sb_dq(23)';
NODE_NAME     U2 EP10
 '@S9S_MB_2U_LIB.S9S_MB_2U(SCH_1):PAGE25_I169@PURE_QUANTA.SOCKET4677_AZIF0045P001C01CS(CHIPS)':
 'DDR5_SB_DQ23': CDS_PINID='DDR5_SB_DQ23';
NODE_NAME     J11 276
 '@S9S_MB_2U_LIB.S9S_MB_2U(SCH_1):PAGE92_I25@PURE_QUANTA.SCONN288_ADR50017P130CC(CHIPS)':
 'DQ23_B': CDS_PINID='DQ23_B';
NODE_NAME     J12 276
 '@S9S_MB_2U_LIB.S9S_MB_2U(SCH_1):PAGE93_I24@PURE_QUANTA.SCONN288_ADR50017P087CC(CHIPS)':
 'DQ23_B': CDS_PINID='DQ23_B';
NET_NAME
'M_F_CPU0_SB_DQ<24>'
 '@S9S_MB_2U_LIB.S9S_MB_2U(SCH_1):M_F_CPU0_SB_DQ'<24>:
 C_SIGNAL='@s9s_mb_2u_lib.s9s_mb_2u(sch_1):m_f_cpu0_sb_dq(24)';
NODE_NAME     U2 DV20
 '@S9S_MB_2U_LIB.S9S_MB_2U(SCH_1):PAGE25_I169@PURE_QUANTA.SOCKET4677_AZIF0045P001C01CS(CHIPS)':
 'DDR5_SB_DQ24': CDS_PINID='DDR5_SB_DQ24';
NODE_NAME     J11 133
 '@S9S_MB_2U_LIB.S9S_MB_2U(SCH_1):PAGE92_I25@PURE_QUANTA.SCONN288_ADR50017P130CC(CHIPS)':
 'DQ24_B': CDS_PINID='DQ24_B';
NODE_NAME     J12 133
 '@S9S_MB_2U_LIB.S9S_MB_2U(SCH_1):PAGE93_I24@PURE_QUANTA.SCONN288_ADR50017P087CC(CHIPS)':
 'DQ24_B': CDS_PINID='DQ24_B';
NET_NAME
'M_F_CPU0_SB_DQ<25>'
 '@S9S_MB_2U_LIB.S9S_MB_2U(SCH_1):M_F_CPU0_SB_DQ'<25>:
 C_SIGNAL='@s9s_mb_2u_lib.s9s_mb_2u(sch_1):m_f_cpu0_sb_dq(25)';
NODE_NAME     U2 DU19
 '@S9S_MB_2U_LIB.S9S_MB_2U(SCH_1):PAGE25_I169@PURE_QUANTA.SOCKET4677_AZIF0045P001C01CS(CHIPS)':
 'DDR5_SB_DQ25': CDS_PINID='DDR5_SB_DQ25';
NODE_NAME     J11 135
 '@S9S_MB_2U_LIB.S9S_MB_2U(SCH_1):PAGE92_I25@PURE_QUANTA.SCONN288_ADR50017P130CC(CHIPS)':
 'DQ25_B': CDS_PINID='DQ25_B';
NODE_NAME     J12 135
 '@S9S_MB_2U_LIB.S9S_MB_2U(SCH_1):PAGE93_I24@PURE_QUANTA.SCONN288_ADR50017P087CC(CHIPS)':
 'DQ25_B': CDS_PINID='DQ25_B';
NET_NAME
'M_F_CPU0_SB_DQ<26>'
 '@S9S_MB_2U_LIB.S9S_MB_2U(SCH_1):M_F_CPU0_SB_DQ'<26>:
 C_SIGNAL='@s9s_mb_2u_lib.s9s_mb_2u(sch_1):m_f_cpu0_sb_dq(26)';
NODE_NAME     U2 DY20
 '@S9S_MB_2U_LIB.S9S_MB_2U(SCH_1):PAGE25_I169@PURE_QUANTA.SOCKET4677_AZIF0045P001C01CS(CHIPS)':
 'DDR5_SB_DQ26': CDS_PINID='DDR5_SB_DQ26';
NODE_NAME     J11 278
 '@S9S_MB_2U_LIB.S9S_MB_2U(SCH_1):PAGE92_I25@PURE_QUANTA.SCONN288_ADR50017P130CC(CHIPS)':
 'DQ26_B': CDS_PINID='DQ26_B';
NODE_NAME     J12 278
 '@S9S_MB_2U_LIB.S9S_MB_2U(SCH_1):PAGE93_I24@PURE_QUANTA.SCONN288_ADR50017P087CC(CHIPS)':
 'DQ26_B': CDS_PINID='DQ26_B';
NET_NAME
'M_F_CPU0_SB_DQ<27>'
 '@S9S_MB_2U_LIB.S9S_MB_2U(SCH_1):M_F_CPU0_SB_DQ'<27>:
 C_SIGNAL='@s9s_mb_2u_lib.s9s_mb_2u(sch_1):m_f_cpu0_sb_dq(27)';
NODE_NAME     U2 EA19
 '@S9S_MB_2U_LIB.S9S_MB_2U(SCH_1):PAGE25_I169@PURE_QUANTA.SOCKET4677_AZIF0045P001C01CS(CHIPS)':
 'DDR5_SB_DQ27': CDS_PINID='DDR5_SB_DQ27';
NODE_NAME     J11 280
 '@S9S_MB_2U_LIB.S9S_MB_2U(SCH_1):PAGE92_I25@PURE_QUANTA.SCONN288_ADR50017P130CC(CHIPS)':
 'DQ27_B': CDS_PINID='DQ27_B';
NODE_NAME     J12 280
 '@S9S_MB_2U_LIB.S9S_MB_2U(SCH_1):PAGE93_I24@PURE_QUANTA.SCONN288_ADR50017P087CC(CHIPS)':
 'DQ27_B': CDS_PINID='DQ27_B';
NET_NAME
'M_F_CPU0_SB_DQ<28>'
 '@S9S_MB_2U_LIB.S9S_MB_2U(SCH_1):M_F_CPU0_SB_DQ'<28>:
 C_SIGNAL='@s9s_mb_2u_lib.s9s_mb_2u(sch_1):m_f_cpu0_sb_dq(28)';
NODE_NAME     U2 EA17
 '@S9S_MB_2U_LIB.S9S_MB_2U(SCH_1):PAGE25_I169@PURE_QUANTA.SOCKET4677_AZIF0045P001C01CS(CHIPS)':
 'DDR5_SB_DQ28': CDS_PINID='DDR5_SB_DQ28';
NODE_NAME     J11 140
 '@S9S_MB_2U_LIB.S9S_MB_2U(SCH_1):PAGE92_I25@PURE_QUANTA.SCONN288_ADR50017P130CC(CHIPS)':
 'DQ28_B': CDS_PINID='DQ28_B';
NODE_NAME     J12 140
 '@S9S_MB_2U_LIB.S9S_MB_2U(SCH_1):PAGE93_I24@PURE_QUANTA.SCONN288_ADR50017P087CC(CHIPS)':
 'DQ28_B': CDS_PINID='DQ28_B';
NET_NAME
'M_F_CPU0_SB_DQ<29>'
 '@S9S_MB_2U_LIB.S9S_MB_2U(SCH_1):M_F_CPU0_SB_DQ'<29>:
 C_SIGNAL='@s9s_mb_2u_lib.s9s_mb_2u(sch_1):m_f_cpu0_sb_dq(29)';
NODE_NAME     U2 DU17
 '@S9S_MB_2U_LIB.S9S_MB_2U(SCH_1):PAGE25_I169@PURE_QUANTA.SOCKET4677_AZIF0045P001C01CS(CHIPS)':
 'DDR5_SB_DQ29': CDS_PINID='DDR5_SB_DQ29';
NODE_NAME     J11 142
 '@S9S_MB_2U_LIB.S9S_MB_2U(SCH_1):PAGE92_I25@PURE_QUANTA.SCONN288_ADR50017P130CC(CHIPS)':
 'DQ29_B': CDS_PINID='DQ29_B';
NODE_NAME     J12 142
 '@S9S_MB_2U_LIB.S9S_MB_2U(SCH_1):PAGE93_I24@PURE_QUANTA.SCONN288_ADR50017P087CC(CHIPS)':
 'DQ29_B': CDS_PINID='DQ29_B';
NET_NAME
'M_F_CPU0_SB_DQ<2>'
 '@S9S_MB_2U_LIB.S9S_MB_2U(SCH_1):M_F_CPU0_SB_DQ'<2>:
 C_SIGNAL='@s9s_mb_2u_lib.s9s_mb_2u(sch_1):m_f_cpu0_sb_dq(2)';
NODE_NAME     U2 DY32
 '@S9S_MB_2U_LIB.S9S_MB_2U(SCH_1):PAGE25_I169@PURE_QUANTA.SOCKET4677_AZIF0045P001C01CS(CHIPS)':
 'DDR5_SB_DQ2': CDS_PINID='DDR5_SB_DQ2';
NODE_NAME     J11 245
 '@S9S_MB_2U_LIB.S9S_MB_2U(SCH_1):PAGE92_I25@PURE_QUANTA.SCONN288_ADR50017P130CC(CHIPS)':
 'DQ2_B': CDS_PINID='DQ2_B';
NODE_NAME     J12 245
 '@S9S_MB_2U_LIB.S9S_MB_2U(SCH_1):PAGE93_I24@PURE_QUANTA.SCONN288_ADR50017P087CC(CHIPS)':
 'DQ2_B': CDS_PINID='DQ2_B';
NET_NAME
'M_F_CPU0_SB_DQ<30>'
 '@S9S_MB_2U_LIB.S9S_MB_2U(SCH_1):M_F_CPU0_SB_DQ'<30>:
 C_SIGNAL='@s9s_mb_2u_lib.s9s_mb_2u(sch_1):m_f_cpu0_sb_dq(30)';
NODE_NAME     U2 EC17
 '@S9S_MB_2U_LIB.S9S_MB_2U(SCH_1):PAGE25_I169@PURE_QUANTA.SOCKET4677_AZIF0045P001C01CS(CHIPS)':
 'DDR5_SB_DQ30': CDS_PINID='DDR5_SB_DQ30';
NODE_NAME     J11 285
 '@S9S_MB_2U_LIB.S9S_MB_2U(SCH_1):PAGE92_I25@PURE_QUANTA.SCONN288_ADR50017P130CC(CHIPS)':
 'DQ30_B': CDS_PINID='DQ30_B';
NODE_NAME     J12 285
 '@S9S_MB_2U_LIB.S9S_MB_2U(SCH_1):PAGE93_I24@PURE_QUANTA.SCONN288_ADR50017P087CC(CHIPS)':
 'DQ30_B': CDS_PINID='DQ30_B';
NET_NAME
'M_F_CPU0_SB_DQ<31>'
 '@S9S_MB_2U_LIB.S9S_MB_2U(SCH_1):M_F_CPU0_SB_DQ'<31>:
 C_SIGNAL='@s9s_mb_2u_lib.s9s_mb_2u(sch_1):m_f_cpu0_sb_dq(31)';
NODE_NAME     U2 DR17
 '@S9S_MB_2U_LIB.S9S_MB_2U(SCH_1):PAGE25_I169@PURE_QUANTA.SOCKET4677_AZIF0045P001C01CS(CHIPS)':
 'DDR5_SB_DQ31': CDS_PINID='DDR5_SB_DQ31';
NODE_NAME     J11 287
 '@S9S_MB_2U_LIB.S9S_MB_2U(SCH_1):PAGE92_I25@PURE_QUANTA.SCONN288_ADR50017P130CC(CHIPS)':
 'DQ31_B': CDS_PINID='DQ31_B';
NODE_NAME     J12 287
 '@S9S_MB_2U_LIB.S9S_MB_2U(SCH_1):PAGE93_I24@PURE_QUANTA.SCONN288_ADR50017P087CC(CHIPS)':
 'DQ31_B': CDS_PINID='DQ31_B';
NET_NAME
'M_F_CPU0_SB_DQ<3>'
 '@S9S_MB_2U_LIB.S9S_MB_2U(SCH_1):M_F_CPU0_SB_DQ'<3>:
 C_SIGNAL='@s9s_mb_2u_lib.s9s_mb_2u(sch_1):m_f_cpu0_sb_dq(3)';
NODE_NAME     U2 EA31
 '@S9S_MB_2U_LIB.S9S_MB_2U(SCH_1):PAGE25_I169@PURE_QUANTA.SOCKET4677_AZIF0045P001C01CS(CHIPS)':
 'DDR5_SB_DQ3': CDS_PINID='DDR5_SB_DQ3';
NODE_NAME     J11 247
 '@S9S_MB_2U_LIB.S9S_MB_2U(SCH_1):PAGE92_I25@PURE_QUANTA.SCONN288_ADR50017P130CC(CHIPS)':
 'DQ3_B': CDS_PINID='DQ3_B';
NODE_NAME     J12 247
 '@S9S_MB_2U_LIB.S9S_MB_2U(SCH_1):PAGE93_I24@PURE_QUANTA.SCONN288_ADR50017P087CC(CHIPS)':
 'DQ3_B': CDS_PINID='DQ3_B';
NET_NAME
'M_F_CPU0_SB_DQ<4>'
 '@S9S_MB_2U_LIB.S9S_MB_2U(SCH_1):M_F_CPU0_SB_DQ'<4>:
 C_SIGNAL='@s9s_mb_2u_lib.s9s_mb_2u(sch_1):m_f_cpu0_sb_dq(4)';
NODE_NAME     U2 DU29
 '@S9S_MB_2U_LIB.S9S_MB_2U(SCH_1):PAGE25_I169@PURE_QUANTA.SOCKET4677_AZIF0045P001C01CS(CHIPS)':
 'DDR5_SB_DQ4': CDS_PINID='DDR5_SB_DQ4';
NODE_NAME     J11 107
 '@S9S_MB_2U_LIB.S9S_MB_2U(SCH_1):PAGE92_I25@PURE_QUANTA.SCONN288_ADR50017P130CC(CHIPS)':
 'DQ4_B': CDS_PINID='DQ4_B';
NODE_NAME     J12 107
 '@S9S_MB_2U_LIB.S9S_MB_2U(SCH_1):PAGE93_I24@PURE_QUANTA.SCONN288_ADR50017P087CC(CHIPS)':
 'DQ4_B': CDS_PINID='DQ4_B';
NET_NAME
'M_F_CPU0_SB_DQ<5>'
 '@S9S_MB_2U_LIB.S9S_MB_2U(SCH_1):M_F_CPU0_SB_DQ'<5>:
 C_SIGNAL='@s9s_mb_2u_lib.s9s_mb_2u(sch_1):m_f_cpu0_sb_dq(5)';
NODE_NAME     U2 DV28
 '@S9S_MB_2U_LIB.S9S_MB_2U(SCH_1):PAGE25_I169@PURE_QUANTA.SOCKET4677_AZIF0045P001C01CS(CHIPS)':
 'DDR5_SB_DQ5': CDS_PINID='DDR5_SB_DQ5';
NODE_NAME     J11 109
 '@S9S_MB_2U_LIB.S9S_MB_2U(SCH_1):PAGE92_I25@PURE_QUANTA.SCONN288_ADR50017P130CC(CHIPS)':
 'DQ5_B': CDS_PINID='DQ5_B';
NODE_NAME     J12 109
 '@S9S_MB_2U_LIB.S9S_MB_2U(SCH_1):PAGE93_I24@PURE_QUANTA.SCONN288_ADR50017P087CC(CHIPS)':
 'DQ5_B': CDS_PINID='DQ5_B';
NET_NAME
'M_F_CPU0_SB_DQ<6>'
 '@S9S_MB_2U_LIB.S9S_MB_2U(SCH_1):M_F_CPU0_SB_DQ'<6>:
 C_SIGNAL='@s9s_mb_2u_lib.s9s_mb_2u(sch_1):m_f_cpu0_sb_dq(6)';
NODE_NAME     U2 EA29
 '@S9S_MB_2U_LIB.S9S_MB_2U(SCH_1):PAGE25_I169@PURE_QUANTA.SOCKET4677_AZIF0045P001C01CS(CHIPS)':
 'DDR5_SB_DQ6': CDS_PINID='DDR5_SB_DQ6';
NODE_NAME     J11 252
 '@S9S_MB_2U_LIB.S9S_MB_2U(SCH_1):PAGE92_I25@PURE_QUANTA.SCONN288_ADR50017P130CC(CHIPS)':
 'DQ6_B': CDS_PINID='DQ6_B';
NODE_NAME     J12 252
 '@S9S_MB_2U_LIB.S9S_MB_2U(SCH_1):PAGE93_I24@PURE_QUANTA.SCONN288_ADR50017P087CC(CHIPS)':
 'DQ6_B': CDS_PINID='DQ6_B';
NET_NAME
'M_F_CPU0_SB_DQ<7>'
 '@S9S_MB_2U_LIB.S9S_MB_2U(SCH_1):M_F_CPU0_SB_DQ'<7>:
 C_SIGNAL='@s9s_mb_2u_lib.s9s_mb_2u(sch_1):m_f_cpu0_sb_dq(7)';
NODE_NAME     U2 DY28
 '@S9S_MB_2U_LIB.S9S_MB_2U(SCH_1):PAGE25_I169@PURE_QUANTA.SOCKET4677_AZIF0045P001C01CS(CHIPS)':
 'DDR5_SB_DQ7': CDS_PINID='DDR5_SB_DQ7';
NODE_NAME     J11 254
 '@S9S_MB_2U_LIB.S9S_MB_2U(SCH_1):PAGE92_I25@PURE_QUANTA.SCONN288_ADR50017P130CC(CHIPS)':
 'DQ7_B': CDS_PINID='DQ7_B';
NODE_NAME     J12 254
 '@S9S_MB_2U_LIB.S9S_MB_2U(SCH_1):PAGE93_I24@PURE_QUANTA.SCONN288_ADR50017P087CC(CHIPS)':
 'DQ7_B': CDS_PINID='DQ7_B';
NET_NAME
'M_F_CPU0_SB_DQ<8>'
 '@S9S_MB_2U_LIB.S9S_MB_2U(SCH_1):M_F_CPU0_SB_DQ'<8>:
 C_SIGNAL='@s9s_mb_2u_lib.s9s_mb_2u(sch_1):m_f_cpu0_sb_dq(8)';
NODE_NAME     U2 EE23
 '@S9S_MB_2U_LIB.S9S_MB_2U(SCH_1):PAGE25_I169@PURE_QUANTA.SOCKET4677_AZIF0045P001C01CS(CHIPS)':
 'DDR5_SB_DQ8': CDS_PINID='DDR5_SB_DQ8';
NODE_NAME     J11 111
 '@S9S_MB_2U_LIB.S9S_MB_2U(SCH_1):PAGE92_I25@PURE_QUANTA.SCONN288_ADR50017P130CC(CHIPS)':
 'DQ8_B': CDS_PINID='DQ8_B';
NODE_NAME     J12 111
 '@S9S_MB_2U_LIB.S9S_MB_2U(SCH_1):PAGE93_I24@PURE_QUANTA.SCONN288_ADR50017P087CC(CHIPS)':
 'DQ8_B': CDS_PINID='DQ8_B';
NET_NAME
'M_F_CPU0_SB_DQ<9>'
 '@S9S_MB_2U_LIB.S9S_MB_2U(SCH_1):M_F_CPU0_SB_DQ'<9>:
 C_SIGNAL='@s9s_mb_2u_lib.s9s_mb_2u(sch_1):m_f_cpu0_sb_dq(9)';
NODE_NAME     U2 ED22
 '@S9S_MB_2U_LIB.S9S_MB_2U(SCH_1):PAGE25_I169@PURE_QUANTA.SOCKET4677_AZIF0045P001C01CS(CHIPS)':
 'DDR5_SB_DQ9': CDS_PINID='DDR5_SB_DQ9';
NODE_NAME     J11 113
 '@S9S_MB_2U_LIB.S9S_MB_2U(SCH_1):PAGE92_I25@PURE_QUANTA.SCONN288_ADR50017P130CC(CHIPS)':
 'DQ9_B': CDS_PINID='DQ9_B';
NODE_NAME     J12 113
 '@S9S_MB_2U_LIB.S9S_MB_2U(SCH_1):PAGE93_I24@PURE_QUANTA.SCONN288_ADR50017P087CC(CHIPS)':
 'DQ9_B': CDS_PINID='DQ9_B';
NET_NAME
'M_F_CPU0_SB_DQS_DN<0>'
 '@S9S_MB_2U_LIB.S9S_MB_2U(SCH_1):M_F_CPU0_SB_DQS_DN'<0>:
 C_SIGNAL='@s9s_mb_2u_lib.s9s_mb_2u(sch_1):m_f_cpu0_sb_dqs_dn(0)';
NODE_NAME     U2 DV30
 '@S9S_MB_2U_LIB.S9S_MB_2U(SCH_1):PAGE25_I169@PURE_QUANTA.SOCKET4677_AZIF0045P001C01CS(CHIPS)':
 'DDR5_SB_DQS_DN0': CDS_PINID='DDR5_SB_DQS_DN0';
NODE_NAME     J11 105
 '@S9S_MB_2U_LIB.S9S_MB_2U(SCH_1):PAGE92_I178@PURE_QUANTA.SCONN288_ADR50017P130CC(CHIPS)':
 'DQS0_B_C': CDS_PINID='DQS0_B_C';
NODE_NAME     J12 105
 '@S9S_MB_2U_LIB.S9S_MB_2U(SCH_1):PAGE93_I178@PURE_QUANTA.SCONN288_ADR50017P087CC(CHIPS)':
 'DQS0_B_C': CDS_PINID='DQS0_B_C';
NET_NAME
'M_F_CPU0_SB_DQS_DN<1>'
 '@S9S_MB_2U_LIB.S9S_MB_2U(SCH_1):M_F_CPU0_SB_DQS_DN'<1>:
 C_SIGNAL='@s9s_mb_2u_lib.s9s_mb_2u(sch_1):m_f_cpu0_sb_dqs_dn(1)';
NODE_NAME     U2 EE21
 '@S9S_MB_2U_LIB.S9S_MB_2U(SCH_1):PAGE25_I169@PURE_QUANTA.SOCKET4677_AZIF0045P001C01CS(CHIPS)':
 'DDR5_SB_DQS_DN1': CDS_PINID='DDR5_SB_DQS_DN1';
NODE_NAME     J11 116
 '@S9S_MB_2U_LIB.S9S_MB_2U(SCH_1):PAGE92_I178@PURE_QUANTA.SCONN288_ADR50017P130CC(CHIPS)':
 'DQS1_B_C': CDS_PINID='DQS1_B_C';
NODE_NAME     J12 116
 '@S9S_MB_2U_LIB.S9S_MB_2U(SCH_1):PAGE93_I178@PURE_QUANTA.SCONN288_ADR50017P087CC(CHIPS)':
 'DQS1_B_C': CDS_PINID='DQS1_B_C';
NET_NAME
'M_F_CPU0_SB_DQS_DN<2>'
 '@S9S_MB_2U_LIB.S9S_MB_2U(SCH_1):M_F_CPU0_SB_DQS_DN'<2>:
 C_SIGNAL='@s9s_mb_2u_lib.s9s_mb_2u(sch_1):m_f_cpu0_sb_dqs_dn(2)';
NODE_NAME     U2 EM12
 '@S9S_MB_2U_LIB.S9S_MB_2U(SCH_1):PAGE25_I169@PURE_QUANTA.SOCKET4677_AZIF0045P001C01CS(CHIPS)':
 'DDR5_SB_DQS_DN2': CDS_PINID='DDR5_SB_DQS_DN2';
NODE_NAME     J11 127
 '@S9S_MB_2U_LIB.S9S_MB_2U(SCH_1):PAGE92_I178@PURE_QUANTA.SCONN288_ADR50017P130CC(CHIPS)':
 'DQS2_B_C': CDS_PINID='DQS2_B_C';
NODE_NAME     J12 127
 '@S9S_MB_2U_LIB.S9S_MB_2U(SCH_1):PAGE93_I178@PURE_QUANTA.SCONN288_ADR50017P087CC(CHIPS)':
 'DQS2_B_C': CDS_PINID='DQS2_B_C';
NET_NAME
'M_F_CPU0_SB_DQS_DN<3>'
 '@S9S_MB_2U_LIB.S9S_MB_2U(SCH_1):M_F_CPU0_SB_DQS_DN'<3>:
 C_SIGNAL='@s9s_mb_2u_lib.s9s_mb_2u(sch_1):m_f_cpu0_sb_dqs_dn(3)';
NODE_NAME     U2 DT18
 '@S9S_MB_2U_LIB.S9S_MB_2U(SCH_1):PAGE25_I169@PURE_QUANTA.SOCKET4677_AZIF0045P001C01CS(CHIPS)':
 'DDR5_SB_DQS_DN3': CDS_PINID='DDR5_SB_DQS_DN3';
NODE_NAME     J11 138
 '@S9S_MB_2U_LIB.S9S_MB_2U(SCH_1):PAGE92_I178@PURE_QUANTA.SCONN288_ADR50017P130CC(CHIPS)':
 'DQS3_B_C': CDS_PINID='DQS3_B_C';
NODE_NAME     J12 138
 '@S9S_MB_2U_LIB.S9S_MB_2U(SCH_1):PAGE93_I178@PURE_QUANTA.SCONN288_ADR50017P087CC(CHIPS)':
 'DQS3_B_C': CDS_PINID='DQS3_B_C';
NET_NAME
'M_F_CPU0_SB_DQS_DN<4>'
 '@S9S_MB_2U_LIB.S9S_MB_2U(SCH_1):M_F_CPU0_SB_DQS_DN'<4>:
 C_SIGNAL='@s9s_mb_2u_lib.s9s_mb_2u(sch_1):m_f_cpu0_sb_dqs_dn(4)';
NODE_NAME     U2 EJ33
 '@S9S_MB_2U_LIB.S9S_MB_2U(SCH_1):PAGE25_I169@PURE_QUANTA.SOCKET4677_AZIF0045P001C01CS(CHIPS)':
 'DDR5_SB_DQS_DN4': CDS_PINID='DDR5_SB_DQS_DN4';
NODE_NAME     J11 238
 '@S9S_MB_2U_LIB.S9S_MB_2U(SCH_1):PAGE92_I178@PURE_QUANTA.SCONN288_ADR50017P130CC(CHIPS)':
 'DQS4_B_C': CDS_PINID='DQS4_B_C';
NODE_NAME     J12 238
 '@S9S_MB_2U_LIB.S9S_MB_2U(SCH_1):PAGE93_I178@PURE_QUANTA.SCONN288_ADR50017P087CC(CHIPS)':
 'DQS4_B_C': CDS_PINID='DQS4_B_C';
NET_NAME
'M_F_CPU0_SB_DQS_DN<5>'
 '@S9S_MB_2U_LIB.S9S_MB_2U(SCH_1):M_F_CPU0_SB_DQS_DN'<5>:
 C_SIGNAL='@s9s_mb_2u_lib.s9s_mb_2u(sch_1):m_f_cpu0_sb_dqs_dn(5)';
NODE_NAME     U2 EB30
 '@S9S_MB_2U_LIB.S9S_MB_2U(SCH_1):PAGE25_I169@PURE_QUANTA.SOCKET4677_AZIF0045P001C01CS(CHIPS)':
 'DDR5_SB_DQS_DN5': CDS_PINID='DDR5_SB_DQS_DN5';
NODE_NAME     J11 249
 '@S9S_MB_2U_LIB.S9S_MB_2U(SCH_1):PAGE92_I178@PURE_QUANTA.SCONN288_ADR50017P130CC(CHIPS)':
 'DQS5_B_C||TDQS5_B_C': CDS_PINID='\dqs5_b_c||tdqs5_b_c\';
NODE_NAME     J12 249
 '@S9S_MB_2U_LIB.S9S_MB_2U(SCH_1):PAGE93_I178@PURE_QUANTA.SCONN288_ADR50017P087CC(CHIPS)':
 'DQS5_B_C||TDQS5_B_C': CDS_PINID='\dqs5_b_c||tdqs5_b_c\';
NET_NAME
'M_F_CPU0_SB_DQS_DN<6>'
 '@S9S_MB_2U_LIB.S9S_MB_2U(SCH_1):M_F_CPU0_SB_DQS_DN'<6>:
 C_SIGNAL='@s9s_mb_2u_lib.s9s_mb_2u(sch_1):m_f_cpu0_sb_dqs_dn(6)';
NODE_NAME     U2 EJ21
 '@S9S_MB_2U_LIB.S9S_MB_2U(SCH_1):PAGE25_I169@PURE_QUANTA.SOCKET4677_AZIF0045P001C01CS(CHIPS)':
 'DDR5_SB_DQS_DN6': CDS_PINID='DDR5_SB_DQS_DN6';
NODE_NAME     J11 260
 '@S9S_MB_2U_LIB.S9S_MB_2U(SCH_1):PAGE92_I178@PURE_QUANTA.SCONN288_ADR50017P130CC(CHIPS)':
 'DQS6_B_C||TDQS6_B_C': CDS_PINID='\dqs6_b_c||tdqs6_b_c\';
NODE_NAME     J12 260
 '@S9S_MB_2U_LIB.S9S_MB_2U(SCH_1):PAGE93_I178@PURE_QUANTA.SCONN288_ADR50017P087CC(CHIPS)':
 'DQS6_B_C||TDQS6_B_C': CDS_PINID='\dqs6_b_c||tdqs6_b_c\';
NET_NAME
'M_F_CPU0_SB_DQS_DN<7>'
 '@S9S_MB_2U_LIB.S9S_MB_2U(SCH_1):M_F_CPU0_SB_DQS_DN'<7>:
 C_SIGNAL='@s9s_mb_2u_lib.s9s_mb_2u(sch_1):m_f_cpu0_sb_dqs_dn(7)';
NODE_NAME     U2 ET12
 '@S9S_MB_2U_LIB.S9S_MB_2U(SCH_1):PAGE25_I169@PURE_QUANTA.SOCKET4677_AZIF0045P001C01CS(CHIPS)':
 'DDR5_SB_DQS_DN7': CDS_PINID='DDR5_SB_DQS_DN7';
NODE_NAME     J11 271
 '@S9S_MB_2U_LIB.S9S_MB_2U(SCH_1):PAGE92_I178@PURE_QUANTA.SCONN288_ADR50017P130CC(CHIPS)':
 'DQS7_B_C||TDQS7_B_C': CDS_PINID='\dqs7_b_c||tdqs7_b_c\';
NODE_NAME     J12 271
 '@S9S_MB_2U_LIB.S9S_MB_2U(SCH_1):PAGE93_I178@PURE_QUANTA.SCONN288_ADR50017P087CC(CHIPS)':
 'DQS7_B_C||TDQS7_B_C': CDS_PINID='\dqs7_b_c||tdqs7_b_c\';
NET_NAME
'M_F_CPU0_SB_DQS_DN<8>'
 '@S9S_MB_2U_LIB.S9S_MB_2U(SCH_1):M_F_CPU0_SB_DQS_DN'<8>:
 C_SIGNAL='@s9s_mb_2u_lib.s9s_mb_2u(sch_1):m_f_cpu0_sb_dqs_dn(8)';
NODE_NAME     U2 DY18
 '@S9S_MB_2U_LIB.S9S_MB_2U(SCH_1):PAGE25_I169@PURE_QUANTA.SOCKET4677_AZIF0045P001C01CS(CHIPS)':
 'DDR5_SB_DQS_DN8': CDS_PINID='DDR5_SB_DQS_DN8';
NODE_NAME     J11 282
 '@S9S_MB_2U_LIB.S9S_MB_2U(SCH_1):PAGE92_I178@PURE_QUANTA.SCONN288_ADR50017P130CC(CHIPS)':
 'DQS8_B_C||TDQS8_B_C': CDS_PINID='\dqs8_b_c||tdqs8_b_c\';
NODE_NAME     J12 282
 '@S9S_MB_2U_LIB.S9S_MB_2U(SCH_1):PAGE93_I178@PURE_QUANTA.SCONN288_ADR50017P087CC(CHIPS)':
 'DQS8_B_C||TDQS8_B_C': CDS_PINID='\dqs8_b_c||tdqs8_b_c\';
NET_NAME
'M_F_CPU0_SB_DQS_DN<9>'
 '@S9S_MB_2U_LIB.S9S_MB_2U(SCH_1):M_F_CPU0_SB_DQS_DN'<9>:
 C_SIGNAL='@s9s_mb_2u_lib.s9s_mb_2u(sch_1):m_f_cpu0_sb_dqs_dn(9)';
NODE_NAME     U2 EE33
 '@S9S_MB_2U_LIB.S9S_MB_2U(SCH_1):PAGE25_I169@PURE_QUANTA.SOCKET4677_AZIF0045P001C01CS(CHIPS)':
 'DDR5_SB_DQS_DN9': CDS_PINID='DDR5_SB_DQS_DN9';
NODE_NAME     J11 94
 '@S9S_MB_2U_LIB.S9S_MB_2U(SCH_1):PAGE92_I178@PURE_QUANTA.SCONN288_ADR50017P130CC(CHIPS)':
 'DQS9_B_C||TDQS9_B_C': CDS_PINID='\dqs9_b_c||tdqs9_b_c\';
NODE_NAME     J12 94
 '@S9S_MB_2U_LIB.S9S_MB_2U(SCH_1):PAGE93_I178@PURE_QUANTA.SCONN288_ADR50017P087CC(CHIPS)':
 'DQS9_B_C||TDQS9_B_C': CDS_PINID='\dqs9_b_c||tdqs9_b_c\';
NET_NAME
'M_F_CPU0_SB_DQS_DP<0>'
 '@S9S_MB_2U_LIB.S9S_MB_2U(SCH_1):M_F_CPU0_SB_DQS_DP'<0>:
 C_SIGNAL='@s9s_mb_2u_lib.s9s_mb_2u(sch_1):m_f_cpu0_sb_dqs_dp(0)';
NODE_NAME     U2 DT30
 '@S9S_MB_2U_LIB.S9S_MB_2U(SCH_1):PAGE25_I169@PURE_QUANTA.SOCKET4677_AZIF0045P001C01CS(CHIPS)':
 'DDR5_SB_DQS_DP0': CDS_PINID='DDR5_SB_DQS_DP0';
NODE_NAME     J11 104
 '@S9S_MB_2U_LIB.S9S_MB_2U(SCH_1):PAGE92_I178@PURE_QUANTA.SCONN288_ADR50017P130CC(CHIPS)':
 'DQS0_B_T': CDS_PINID='DQS0_B_T';
NODE_NAME     J12 104
 '@S9S_MB_2U_LIB.S9S_MB_2U(SCH_1):PAGE93_I178@PURE_QUANTA.SCONN288_ADR50017P087CC(CHIPS)':
 'DQS0_B_T': CDS_PINID='DQS0_B_T';
NET_NAME
'M_F_CPU0_SB_DQS_DP<1>'
 '@S9S_MB_2U_LIB.S9S_MB_2U(SCH_1):M_F_CPU0_SB_DQS_DP'<1>:
 C_SIGNAL='@s9s_mb_2u_lib.s9s_mb_2u(sch_1):m_f_cpu0_sb_dqs_dp(1)';
NODE_NAME     U2 EC21
 '@S9S_MB_2U_LIB.S9S_MB_2U(SCH_1):PAGE25_I169@PURE_QUANTA.SOCKET4677_AZIF0045P001C01CS(CHIPS)':
 'DDR5_SB_DQS_DP1': CDS_PINID='DDR5_SB_DQS_DP1';
NODE_NAME     J11 115
 '@S9S_MB_2U_LIB.S9S_MB_2U(SCH_1):PAGE92_I178@PURE_QUANTA.SCONN288_ADR50017P130CC(CHIPS)':
 'DQS1_B_T': CDS_PINID='DQS1_B_T';
NODE_NAME     J12 115
 '@S9S_MB_2U_LIB.S9S_MB_2U(SCH_1):PAGE93_I178@PURE_QUANTA.SCONN288_ADR50017P087CC(CHIPS)':
 'DQS1_B_T': CDS_PINID='DQS1_B_T';
NET_NAME
'M_F_CPU0_SB_DQS_DP<2>'
 '@S9S_MB_2U_LIB.S9S_MB_2U(SCH_1):M_F_CPU0_SB_DQS_DP'<2>:
 C_SIGNAL='@s9s_mb_2u_lib.s9s_mb_2u(sch_1):m_f_cpu0_sb_dqs_dp(2)';
NODE_NAME     U2 EK12
 '@S9S_MB_2U_LIB.S9S_MB_2U(SCH_1):PAGE25_I169@PURE_QUANTA.SOCKET4677_AZIF0045P001C01CS(CHIPS)':
 'DDR5_SB_DQS_DP2': CDS_PINID='DDR5_SB_DQS_DP2';
NODE_NAME     J11 126
 '@S9S_MB_2U_LIB.S9S_MB_2U(SCH_1):PAGE92_I178@PURE_QUANTA.SCONN288_ADR50017P130CC(CHIPS)':
 'DQS2_B_T': CDS_PINID='DQS2_B_T';
NODE_NAME     J12 126
 '@S9S_MB_2U_LIB.S9S_MB_2U(SCH_1):PAGE93_I178@PURE_QUANTA.SCONN288_ADR50017P087CC(CHIPS)':
 'DQS2_B_T': CDS_PINID='DQS2_B_T';
NET_NAME
'M_F_CPU0_SB_DQS_DP<3>'
 '@S9S_MB_2U_LIB.S9S_MB_2U(SCH_1):M_F_CPU0_SB_DQS_DP'<3>:
 C_SIGNAL='@s9s_mb_2u_lib.s9s_mb_2u(sch_1):m_f_cpu0_sb_dqs_dp(3)';
NODE_NAME     U2 DV18
 '@S9S_MB_2U_LIB.S9S_MB_2U(SCH_1):PAGE25_I169@PURE_QUANTA.SOCKET4677_AZIF0045P001C01CS(CHIPS)':
 'DDR5_SB_DQS_DP3': CDS_PINID='DDR5_SB_DQS_DP3';
NODE_NAME     J11 137
 '@S9S_MB_2U_LIB.S9S_MB_2U(SCH_1):PAGE92_I178@PURE_QUANTA.SCONN288_ADR50017P130CC(CHIPS)':
 'DQS3_B_T': CDS_PINID='DQS3_B_T';
NODE_NAME     J12 137
 '@S9S_MB_2U_LIB.S9S_MB_2U(SCH_1):PAGE93_I178@PURE_QUANTA.SCONN288_ADR50017P087CC(CHIPS)':
 'DQS3_B_T': CDS_PINID='DQS3_B_T';
NET_NAME
'M_F_CPU0_SB_DQS_DP<4>'
 '@S9S_MB_2U_LIB.S9S_MB_2U(SCH_1):M_F_CPU0_SB_DQS_DP'<4>:
 C_SIGNAL='@s9s_mb_2u_lib.s9s_mb_2u(sch_1):m_f_cpu0_sb_dqs_dp(4)';
NODE_NAME     U2 EG33
 '@S9S_MB_2U_LIB.S9S_MB_2U(SCH_1):PAGE25_I169@PURE_QUANTA.SOCKET4677_AZIF0045P001C01CS(CHIPS)':
 'DDR5_SB_DQS_DP4': CDS_PINID='DDR5_SB_DQS_DP4';
NODE_NAME     J11 239
 '@S9S_MB_2U_LIB.S9S_MB_2U(SCH_1):PAGE92_I178@PURE_QUANTA.SCONN288_ADR50017P130CC(CHIPS)':
 'DQS4_B_T': CDS_PINID='DQS4_B_T';
NODE_NAME     J12 239
 '@S9S_MB_2U_LIB.S9S_MB_2U(SCH_1):PAGE93_I178@PURE_QUANTA.SCONN288_ADR50017P087CC(CHIPS)':
 'DQS4_B_T': CDS_PINID='DQS4_B_T';
NET_NAME
'M_F_CPU0_SB_DQS_DP<5>'
 '@S9S_MB_2U_LIB.S9S_MB_2U(SCH_1):M_F_CPU0_SB_DQS_DP'<5>:
 C_SIGNAL='@s9s_mb_2u_lib.s9s_mb_2u(sch_1):m_f_cpu0_sb_dqs_dp(5)';
NODE_NAME     U2 DY30
 '@S9S_MB_2U_LIB.S9S_MB_2U(SCH_1):PAGE25_I169@PURE_QUANTA.SOCKET4677_AZIF0045P001C01CS(CHIPS)':
 'DDR5_SB_DQS_DP5': CDS_PINID='DDR5_SB_DQS_DP5';
NODE_NAME     J11 250
 '@S9S_MB_2U_LIB.S9S_MB_2U(SCH_1):PAGE92_I178@PURE_QUANTA.SCONN288_ADR50017P130CC(CHIPS)':
 'DQS5_B_T||TDQS5_B_T': CDS_PINID='\dqs5_b_t||tdqs5_b_t\';
NODE_NAME     J12 250
 '@S9S_MB_2U_LIB.S9S_MB_2U(SCH_1):PAGE93_I178@PURE_QUANTA.SCONN288_ADR50017P087CC(CHIPS)':
 'DQS5_B_T||TDQS5_B_T': CDS_PINID='\dqs5_b_t||tdqs5_b_t\';
NET_NAME
'M_F_CPU0_SB_DQS_DP<6>'
 '@S9S_MB_2U_LIB.S9S_MB_2U(SCH_1):M_F_CPU0_SB_DQS_DP'<6>:
 C_SIGNAL='@s9s_mb_2u_lib.s9s_mb_2u(sch_1):m_f_cpu0_sb_dqs_dp(6)';
NODE_NAME     U2 EG21
 '@S9S_MB_2U_LIB.S9S_MB_2U(SCH_1):PAGE25_I169@PURE_QUANTA.SOCKET4677_AZIF0045P001C01CS(CHIPS)':
 'DDR5_SB_DQS_DP6': CDS_PINID='DDR5_SB_DQS_DP6';
NODE_NAME     J11 261
 '@S9S_MB_2U_LIB.S9S_MB_2U(SCH_1):PAGE92_I178@PURE_QUANTA.SCONN288_ADR50017P130CC(CHIPS)':
 'DQS6_B_T||TDQS6_B_T': CDS_PINID='\dqs6_b_t||tdqs6_b_t\';
NODE_NAME     J12 261
 '@S9S_MB_2U_LIB.S9S_MB_2U(SCH_1):PAGE93_I178@PURE_QUANTA.SCONN288_ADR50017P087CC(CHIPS)':
 'DQS6_B_T||TDQS6_B_T': CDS_PINID='\dqs6_b_t||tdqs6_b_t\';
NET_NAME
'M_F_CPU0_SB_DQS_DP<7>'
 '@S9S_MB_2U_LIB.S9S_MB_2U(SCH_1):M_F_CPU0_SB_DQS_DP'<7>:
 C_SIGNAL='@s9s_mb_2u_lib.s9s_mb_2u(sch_1):m_f_cpu0_sb_dqs_dp(7)';
NODE_NAME     U2 EP12
 '@S9S_MB_2U_LIB.S9S_MB_2U(SCH_1):PAGE25_I169@PURE_QUANTA.SOCKET4677_AZIF0045P001C01CS(CHIPS)':
 'DDR5_SB_DQS_DP7': CDS_PINID='DDR5_SB_DQS_DP7';
NODE_NAME     J11 272
 '@S9S_MB_2U_LIB.S9S_MB_2U(SCH_1):PAGE92_I178@PURE_QUANTA.SCONN288_ADR50017P130CC(CHIPS)':
 'DQS7_B_T||TDQS7_B_T': CDS_PINID='\dqs7_b_t||tdqs7_b_t\';
NODE_NAME     J12 272
 '@S9S_MB_2U_LIB.S9S_MB_2U(SCH_1):PAGE93_I178@PURE_QUANTA.SCONN288_ADR50017P087CC(CHIPS)':
 'DQS7_B_T||TDQS7_B_T': CDS_PINID='\dqs7_b_t||tdqs7_b_t\';
NET_NAME
'M_F_CPU0_SB_DQS_DP<8>'
 '@S9S_MB_2U_LIB.S9S_MB_2U(SCH_1):M_F_CPU0_SB_DQS_DP'<8>:
 C_SIGNAL='@s9s_mb_2u_lib.s9s_mb_2u(sch_1):m_f_cpu0_sb_dqs_dp(8)';
NODE_NAME     U2 EB18
 '@S9S_MB_2U_LIB.S9S_MB_2U(SCH_1):PAGE25_I169@PURE_QUANTA.SOCKET4677_AZIF0045P001C01CS(CHIPS)':
 'DDR5_SB_DQS_DP8': CDS_PINID='DDR5_SB_DQS_DP8';
NODE_NAME     J11 283
 '@S9S_MB_2U_LIB.S9S_MB_2U(SCH_1):PAGE92_I178@PURE_QUANTA.SCONN288_ADR50017P130CC(CHIPS)':
 'DQS8_B_T||TDQS8_B_T': CDS_PINID='\dqs8_b_t||tdqs8_b_t\';
NODE_NAME     J12 283
 '@S9S_MB_2U_LIB.S9S_MB_2U(SCH_1):PAGE93_I178@PURE_QUANTA.SCONN288_ADR50017P087CC(CHIPS)':
 'DQS8_B_T||TDQS8_B_T': CDS_PINID='\dqs8_b_t||tdqs8_b_t\';
NET_NAME
'M_F_CPU0_SB_DQS_DP<9>'
 '@S9S_MB_2U_LIB.S9S_MB_2U(SCH_1):M_F_CPU0_SB_DQS_DP'<9>:
 C_SIGNAL='@s9s_mb_2u_lib.s9s_mb_2u(sch_1):m_f_cpu0_sb_dqs_dp(9)';
NODE_NAME     U2 EC33
 '@S9S_MB_2U_LIB.S9S_MB_2U(SCH_1):PAGE25_I169@PURE_QUANTA.SOCKET4677_AZIF0045P001C01CS(CHIPS)':
 'DDR5_SB_DQS_DP9': CDS_PINID='DDR5_SB_DQS_DP9';
NODE_NAME     J11 93
 '@S9S_MB_2U_LIB.S9S_MB_2U(SCH_1):PAGE92_I178@PURE_QUANTA.SCONN288_ADR50017P130CC(CHIPS)':
 'DQS9_B_T||TDQS9_B_T||DBI4_B_N': CDS_PINID='\dqs9_b_t||tdqs9_b_t||dbi4_b_n\';
NODE_NAME     J12 93
 '@S9S_MB_2U_LIB.S9S_MB_2U(SCH_1):PAGE93_I178@PURE_QUANTA.SCONN288_ADR50017P087CC(CHIPS)':
 'DQS9_B_T||TDQS9_B_T||DBI4_B_N': CDS_PINID='\dqs9_b_t||tdqs9_b_t||dbi4_b_n\';
NET_NAME
'M_F_CPU0_SB_PAR'
 '@S9S_MB_2U_LIB.S9S_MB_2U(SCH_1):M_F_CPU0_SB_PAR':
 C_SIGNAL='@s9s_mb_2u_lib.s9s_mb_2u(sch_1):m_f_cpu0_sb_par';
NODE_NAME     U2 EJ39
 '@S9S_MB_2U_LIB.S9S_MB_2U(SCH_1):PAGE25_I169@PURE_QUANTA.SOCKET4677_AZIF0045P001C01CS(CHIPS)':
 'DDR5_SB_PAR': CDS_PINID='DDR5_SB_PAR';
NODE_NAME     J11 227
 '@S9S_MB_2U_LIB.S9S_MB_2U(SCH_1):PAGE92_I25@PURE_QUANTA.SCONN288_ADR50017P130CC(CHIPS)':
 'PAR_B': CDS_PINID='PAR_B';
NODE_NAME     J12 227
 '@S9S_MB_2U_LIB.S9S_MB_2U(SCH_1):PAGE93_I24@PURE_QUANTA.SCONN288_ADR50017P087CC(CHIPS)':
 'PAR_B': CDS_PINID='PAR_B';
NET_NAME
'M_F_CPU0_SB_RSP<0>'
 '@S9S_MB_2U_LIB.S9S_MB_2U(SCH_1):M_F_CPU0_SB_RSP'<0>:
 C_SIGNAL='@s9s_mb_2u_lib.s9s_mb_2u(sch_1):m_f_cpu0_sb_rsp(0)';
NODE_NAME     U2 DL48
 '@S9S_MB_2U_LIB.S9S_MB_2U(SCH_1):PAGE25_I169@PURE_QUANTA.SOCKET4677_AZIF0045P001C01CS(CHIPS)':
 'DDR5_B_RSP0': CDS_PINID='DDR5_B_RSP0';
NODE_NAME     J11 87
 '@S9S_MB_2U_LIB.S9S_MB_2U(SCH_1):PAGE92_I25@PURE_QUANTA.SCONN288_ADR50017P130CC(CHIPS)':
 'LBS||RSP_B_N': CDS_PINID='\lbs||rsp_b_n\';
NET_NAME
'M_F_CPU0_SB_RSP<1>'
 '@S9S_MB_2U_LIB.S9S_MB_2U(SCH_1):M_F_CPU0_SB_RSP'<1>:
 C_SIGNAL='@s9s_mb_2u_lib.s9s_mb_2u(sch_1):m_f_cpu0_sb_rsp(1)';
NODE_NAME     U2 DK47
 '@S9S_MB_2U_LIB.S9S_MB_2U(SCH_1):PAGE25_I169@PURE_QUANTA.SOCKET4677_AZIF0045P001C01CS(CHIPS)':
 'DDR5_B_RSP1': CDS_PINID='DDR5_B_RSP1';
NODE_NAME     J12 87
 '@S9S_MB_2U_LIB.S9S_MB_2U(SCH_1):PAGE93_I24@PURE_QUANTA.SCONN288_ADR50017P087CC(CHIPS)':
 'LBS||RSP_B_N': CDS_PINID='\lbs||rsp_b_n\';
NET_NAME
'M_F_CPU1_ALERT_N'
 '@S9S_MB_2U_LIB.S9S_MB_2U(SCH_1):M_F_CPU1_ALERT_N':
 C_SIGNAL='@s9s_mb_2u_lib.s9s_mb_2u(sch_1):m_f_cpu1_alert_n';
NODE_NAME     U1 CW48
 '@S9S_MB_2U_LIB.S9S_MB_2U(SCH_1):PAGE56_I168@PURE_QUANTA.SOCKET4677_AZIF0045P001C01CS(CHIPS)':
 'DDR5_ALERT_N': CDS_PINID='DDR5_ALERT_N';
NODE_NAME     J27 62
 '@S9S_MB_2U_LIB.S9S_MB_2U(SCH_1):PAGE108_I179@PURE_QUANTA.SCONN288_ADR50017P130CC(CHIPS)':
 'ALERT_N': CDS_PINID='ALERT_N';
NODE_NAME     J28 62
 '@S9S_MB_2U_LIB.S9S_MB_2U(SCH_1):PAGE109_I47@PURE_QUANTA.SCONN288_ADR50017P087CC(CHIPS)':
 'ALERT_N': CDS_PINID='ALERT_N';
NET_NAME
'M_F_CPU1_CLK_DN<0>'
 '@S9S_MB_2U_LIB.S9S_MB_2U(SCH_1):M_F_CPU1_CLK_DN'<0>:
 C_SIGNAL='@s9s_mb_2u_lib.s9s_mb_2u(sch_1):m_f_cpu1_clk_dn(0)';
NODE_NAME     U1 DY49
 '@S9S_MB_2U_LIB.S9S_MB_2U(SCH_1):PAGE56_I168@PURE_QUANTA.SOCKET4677_AZIF0045P001C01CS(CHIPS)':
 'DDR5_CLK_DN0': CDS_PINID='DDR5_CLK_DN0';
NODE_NAME     J27 218
 '@S9S_MB_2U_LIB.S9S_MB_2U(SCH_1):PAGE108_I179@PURE_QUANTA.SCONN288_ADR50017P130CC(CHIPS)':
 'CK_C': CDS_PINID='CK_C';
NET_NAME
'M_F_CPU1_CLK_DN<1>'
 '@S9S_MB_2U_LIB.S9S_MB_2U(SCH_1):M_F_CPU1_CLK_DN'<1>:
 C_SIGNAL='@s9s_mb_2u_lib.s9s_mb_2u(sch_1):m_f_cpu1_clk_dn(1)';
NODE_NAME     U1 DV49
 '@S9S_MB_2U_LIB.S9S_MB_2U(SCH_1):PAGE56_I168@PURE_QUANTA.SOCKET4677_AZIF0045P001C01CS(CHIPS)':
 'DDR5_CLK_DN1': CDS_PINID='DDR5_CLK_DN1';
NODE_NAME     J28 218
 '@S9S_MB_2U_LIB.S9S_MB_2U(SCH_1):PAGE109_I47@PURE_QUANTA.SCONN288_ADR50017P087CC(CHIPS)':
 'CK_C': CDS_PINID='CK_C';
NET_NAME
'M_F_CPU1_CLK_DP<0>'
 '@S9S_MB_2U_LIB.S9S_MB_2U(SCH_1):M_F_CPU1_CLK_DP'<0>:
 C_SIGNAL='@s9s_mb_2u_lib.s9s_mb_2u(sch_1):m_f_cpu1_clk_dp(0)';
NODE_NAME     U1 EB49
 '@S9S_MB_2U_LIB.S9S_MB_2U(SCH_1):PAGE56_I168@PURE_QUANTA.SOCKET4677_AZIF0045P001C01CS(CHIPS)':
 'DDR5_CLK_DP0': CDS_PINID='DDR5_CLK_DP0';
NODE_NAME     J27 217
 '@S9S_MB_2U_LIB.S9S_MB_2U(SCH_1):PAGE108_I179@PURE_QUANTA.SCONN288_ADR50017P130CC(CHIPS)':
 'CK_T': CDS_PINID='CK_T';
NET_NAME
'M_F_CPU1_CLK_DP<1>'
 '@S9S_MB_2U_LIB.S9S_MB_2U(SCH_1):M_F_CPU1_CLK_DP'<1>:
 C_SIGNAL='@s9s_mb_2u_lib.s9s_mb_2u(sch_1):m_f_cpu1_clk_dp(1)';
NODE_NAME     U1 DT49
 '@S9S_MB_2U_LIB.S9S_MB_2U(SCH_1):PAGE56_I168@PURE_QUANTA.SOCKET4677_AZIF0045P001C01CS(CHIPS)':
 'DDR5_CLK_DP1': CDS_PINID='DDR5_CLK_DP1';
NODE_NAME     J28 217
 '@S9S_MB_2U_LIB.S9S_MB_2U(SCH_1):PAGE109_I47@PURE_QUANTA.SCONN288_ADR50017P087CC(CHIPS)':
 'CK_T': CDS_PINID='CK_T';
NET_NAME
'M_F_CPU1_SA_CA<0>'
 '@S9S_MB_2U_LIB.S9S_MB_2U(SCH_1):M_F_CPU1_SA_CA'<0>:
 C_SIGNAL='@s9s_mb_2u_lib.s9s_mb_2u(sch_1):m_f_cpu1_sa_ca(0)';
NODE_NAME     U1 EC52
 '@S9S_MB_2U_LIB.S9S_MB_2U(SCH_1):PAGE56_I168@PURE_QUANTA.SOCKET4677_AZIF0045P001C01CS(CHIPS)':
 'DDR5_SA_CA0': CDS_PINID='DDR5_SA_CA0';
NODE_NAME     J27 66
 '@S9S_MB_2U_LIB.S9S_MB_2U(SCH_1):PAGE108_I179@PURE_QUANTA.SCONN288_ADR50017P130CC(CHIPS)':
 'CA0_A': CDS_PINID='CA0_A';
NODE_NAME     J28 66
 '@S9S_MB_2U_LIB.S9S_MB_2U(SCH_1):PAGE109_I47@PURE_QUANTA.SCONN288_ADR50017P087CC(CHIPS)':
 'CA0_A': CDS_PINID='CA0_A';
NET_NAME
'M_F_CPU1_SA_CA<1>'
 '@S9S_MB_2U_LIB.S9S_MB_2U(SCH_1):M_F_CPU1_SA_CA'<1>:
 C_SIGNAL='@s9s_mb_2u_lib.s9s_mb_2u(sch_1):m_f_cpu1_sa_ca(1)';
NODE_NAME     U1 EJ52
 '@S9S_MB_2U_LIB.S9S_MB_2U(SCH_1):PAGE56_I168@PURE_QUANTA.SOCKET4677_AZIF0045P001C01CS(CHIPS)':
 'DDR5_SA_CA1': CDS_PINID='DDR5_SA_CA1';
NODE_NAME     J27 211
 '@S9S_MB_2U_LIB.S9S_MB_2U(SCH_1):PAGE108_I179@PURE_QUANTA.SCONN288_ADR50017P130CC(CHIPS)':
 'CA1_A': CDS_PINID='CA1_A';
NODE_NAME     J28 211
 '@S9S_MB_2U_LIB.S9S_MB_2U(SCH_1):PAGE109_I47@PURE_QUANTA.SCONN288_ADR50017P087CC(CHIPS)':
 'CA1_A': CDS_PINID='CA1_A';
NET_NAME
'M_F_CPU1_SA_CA<2>'
 '@S9S_MB_2U_LIB.S9S_MB_2U(SCH_1):M_F_CPU1_SA_CA'<2>:
 C_SIGNAL='@s9s_mb_2u_lib.s9s_mb_2u(sch_1):m_f_cpu1_sa_ca(2)';
NODE_NAME     U1 ED51
 '@S9S_MB_2U_LIB.S9S_MB_2U(SCH_1):PAGE56_I168@PURE_QUANTA.SOCKET4677_AZIF0045P001C01CS(CHIPS)':
 'DDR5_SA_CA2': CDS_PINID='DDR5_SA_CA2';
NODE_NAME     J27 68
 '@S9S_MB_2U_LIB.S9S_MB_2U(SCH_1):PAGE108_I179@PURE_QUANTA.SCONN288_ADR50017P130CC(CHIPS)':
 'CA2_A': CDS_PINID='CA2_A';
NODE_NAME     J28 68
 '@S9S_MB_2U_LIB.S9S_MB_2U(SCH_1):PAGE109_I47@PURE_QUANTA.SCONN288_ADR50017P087CC(CHIPS)':
 'CA2_A': CDS_PINID='CA2_A';
NET_NAME
'M_F_CPU1_SA_CA<3>'
 '@S9S_MB_2U_LIB.S9S_MB_2U(SCH_1):M_F_CPU1_SA_CA'<3>:
 C_SIGNAL='@s9s_mb_2u_lib.s9s_mb_2u(sch_1):m_f_cpu1_sa_ca(3)';
NODE_NAME     U1 EH51
 '@S9S_MB_2U_LIB.S9S_MB_2U(SCH_1):PAGE56_I168@PURE_QUANTA.SOCKET4677_AZIF0045P001C01CS(CHIPS)':
 'DDR5_SA_CA3': CDS_PINID='DDR5_SA_CA3';
NODE_NAME     J27 213
 '@S9S_MB_2U_LIB.S9S_MB_2U(SCH_1):PAGE108_I179@PURE_QUANTA.SCONN288_ADR50017P130CC(CHIPS)':
 'CA3_A': CDS_PINID='CA3_A';
NODE_NAME     J28 213
 '@S9S_MB_2U_LIB.S9S_MB_2U(SCH_1):PAGE109_I47@PURE_QUANTA.SCONN288_ADR50017P087CC(CHIPS)':
 'CA3_A': CDS_PINID='CA3_A';
NET_NAME
'M_F_CPU1_SA_CA<4>'
 '@S9S_MB_2U_LIB.S9S_MB_2U(SCH_1):M_F_CPU1_SA_CA'<4>:
 C_SIGNAL='@s9s_mb_2u_lib.s9s_mb_2u(sch_1):m_f_cpu1_sa_ca(4)';
NODE_NAME     U1 EE50
 '@S9S_MB_2U_LIB.S9S_MB_2U(SCH_1):PAGE56_I168@PURE_QUANTA.SOCKET4677_AZIF0045P001C01CS(CHIPS)':
 'DDR5_SA_CA4': CDS_PINID='DDR5_SA_CA4';
NODE_NAME     J27 70
 '@S9S_MB_2U_LIB.S9S_MB_2U(SCH_1):PAGE108_I179@PURE_QUANTA.SCONN288_ADR50017P130CC(CHIPS)':
 'CA4_A': CDS_PINID='CA4_A';
NODE_NAME     J28 70
 '@S9S_MB_2U_LIB.S9S_MB_2U(SCH_1):PAGE109_I47@PURE_QUANTA.SCONN288_ADR50017P087CC(CHIPS)':
 'CA4_A': CDS_PINID='CA4_A';
NET_NAME
'M_F_CPU1_SA_CA<5>'
 '@S9S_MB_2U_LIB.S9S_MB_2U(SCH_1):M_F_CPU1_SA_CA'<5>:
 C_SIGNAL='@s9s_mb_2u_lib.s9s_mb_2u(sch_1):m_f_cpu1_sa_ca(5)';
NODE_NAME     U1 EG50
 '@S9S_MB_2U_LIB.S9S_MB_2U(SCH_1):PAGE56_I168@PURE_QUANTA.SOCKET4677_AZIF0045P001C01CS(CHIPS)':
 'DDR5_SA_CA5': CDS_PINID='DDR5_SA_CA5';
NODE_NAME     J27 215
 '@S9S_MB_2U_LIB.S9S_MB_2U(SCH_1):PAGE108_I179@PURE_QUANTA.SCONN288_ADR50017P130CC(CHIPS)':
 'CA5_A': CDS_PINID='CA5_A';
NODE_NAME     J28 215
 '@S9S_MB_2U_LIB.S9S_MB_2U(SCH_1):PAGE109_I47@PURE_QUANTA.SCONN288_ADR50017P087CC(CHIPS)':
 'CA5_A': CDS_PINID='CA5_A';
NET_NAME
'M_F_CPU1_SA_CA<6>'
 '@S9S_MB_2U_LIB.S9S_MB_2U(SCH_1):M_F_CPU1_SA_CA'<6>:
 C_SIGNAL='@s9s_mb_2u_lib.s9s_mb_2u(sch_1):m_f_cpu1_sa_ca(6)';
NODE_NAME     U1 DY51
 '@S9S_MB_2U_LIB.S9S_MB_2U(SCH_1):PAGE56_I168@PURE_QUANTA.SOCKET4677_AZIF0045P001C01CS(CHIPS)':
 'DDR5_SA_CA6': CDS_PINID='DDR5_SA_CA6';
NODE_NAME     J27 72
 '@S9S_MB_2U_LIB.S9S_MB_2U(SCH_1):PAGE108_I179@PURE_QUANTA.SCONN288_ADR50017P130CC(CHIPS)':
 'CA6_A': CDS_PINID='CA6_A';
NODE_NAME     J28 72
 '@S9S_MB_2U_LIB.S9S_MB_2U(SCH_1):PAGE109_I47@PURE_QUANTA.SCONN288_ADR50017P087CC(CHIPS)':
 'CA6_A': CDS_PINID='CA6_A';
NET_NAME
'M_F_CPU1_SA_CB<0>'
 '@S9S_MB_2U_LIB.S9S_MB_2U(SCH_1):M_F_CPU1_SA_CB'<0>:
 C_SIGNAL='@s9s_mb_2u_lib.s9s_mb_2u(sch_1):m_f_cpu1_sa_cb(0)';
NODE_NAME     U1 EE60
 '@S9S_MB_2U_LIB.S9S_MB_2U(SCH_1):PAGE56_I168@PURE_QUANTA.SOCKET4677_AZIF0045P001C01CS(CHIPS)':
 'DDR5_SA_ECC0': CDS_PINID='DDR5_SA_ECC0';
NODE_NAME     J27 51
 '@S9S_MB_2U_LIB.S9S_MB_2U(SCH_1):PAGE108_I179@PURE_QUANTA.SCONN288_ADR50017P130CC(CHIPS)':
 'CB0_A': CDS_PINID='CB0_A';
NODE_NAME     J28 51
 '@S9S_MB_2U_LIB.S9S_MB_2U(SCH_1):PAGE109_I47@PURE_QUANTA.SCONN288_ADR50017P087CC(CHIPS)':
 'CB0_A': CDS_PINID='CB0_A';
NET_NAME
'M_F_CPU1_SA_CB<1>'
 '@S9S_MB_2U_LIB.S9S_MB_2U(SCH_1):M_F_CPU1_SA_CB'<1>:
 C_SIGNAL='@s9s_mb_2u_lib.s9s_mb_2u(sch_1):m_f_cpu1_sa_cb(1)';
NODE_NAME     U1 ED59
 '@S9S_MB_2U_LIB.S9S_MB_2U(SCH_1):PAGE56_I168@PURE_QUANTA.SOCKET4677_AZIF0045P001C01CS(CHIPS)':
 'DDR5_SA_ECC1': CDS_PINID='DDR5_SA_ECC1';
NODE_NAME     J27 53
 '@S9S_MB_2U_LIB.S9S_MB_2U(SCH_1):PAGE108_I179@PURE_QUANTA.SCONN288_ADR50017P130CC(CHIPS)':
 'CB1_A': CDS_PINID='CB1_A';
NODE_NAME     J28 53
 '@S9S_MB_2U_LIB.S9S_MB_2U(SCH_1):PAGE109_I47@PURE_QUANTA.SCONN288_ADR50017P087CC(CHIPS)':
 'CB1_A': CDS_PINID='CB1_A';
NET_NAME
'M_F_CPU1_SA_CB<2>'
 '@S9S_MB_2U_LIB.S9S_MB_2U(SCH_1):M_F_CPU1_SA_CB'<2>:
 C_SIGNAL='@s9s_mb_2u_lib.s9s_mb_2u(sch_1):m_f_cpu1_sa_cb(2)';
NODE_NAME     U1 EG60
 '@S9S_MB_2U_LIB.S9S_MB_2U(SCH_1):PAGE56_I168@PURE_QUANTA.SOCKET4677_AZIF0045P001C01CS(CHIPS)':
 'DDR5_SA_ECC2': CDS_PINID='DDR5_SA_ECC2';
NODE_NAME     J27 196
 '@S9S_MB_2U_LIB.S9S_MB_2U(SCH_1):PAGE108_I179@PURE_QUANTA.SCONN288_ADR50017P130CC(CHIPS)':
 'CB2_A': CDS_PINID='CB2_A';
NODE_NAME     J28 196
 '@S9S_MB_2U_LIB.S9S_MB_2U(SCH_1):PAGE109_I47@PURE_QUANTA.SCONN288_ADR50017P087CC(CHIPS)':
 'CB2_A': CDS_PINID='CB2_A';
NET_NAME
'M_F_CPU1_SA_CB<3>'
 '@S9S_MB_2U_LIB.S9S_MB_2U(SCH_1):M_F_CPU1_SA_CB'<3>:
 C_SIGNAL='@s9s_mb_2u_lib.s9s_mb_2u(sch_1):m_f_cpu1_sa_cb(3)';
NODE_NAME     U1 EH59
 '@S9S_MB_2U_LIB.S9S_MB_2U(SCH_1):PAGE56_I168@PURE_QUANTA.SOCKET4677_AZIF0045P001C01CS(CHIPS)':
 'DDR5_SA_ECC3': CDS_PINID='DDR5_SA_ECC3';
NODE_NAME     J27 198
 '@S9S_MB_2U_LIB.S9S_MB_2U(SCH_1):PAGE108_I179@PURE_QUANTA.SCONN288_ADR50017P130CC(CHIPS)':
 'CB3_A': CDS_PINID='CB3_A';
NODE_NAME     J28 198
 '@S9S_MB_2U_LIB.S9S_MB_2U(SCH_1):PAGE109_I47@PURE_QUANTA.SCONN288_ADR50017P087CC(CHIPS)':
 'CB3_A': CDS_PINID='CB3_A';
NET_NAME
'M_F_CPU1_SA_CB<4>'
 '@S9S_MB_2U_LIB.S9S_MB_2U(SCH_1):M_F_CPU1_SA_CB'<4>:
 C_SIGNAL='@s9s_mb_2u_lib.s9s_mb_2u(sch_1):m_f_cpu1_sa_cb(4)';
NODE_NAME     U1 ED57
 '@S9S_MB_2U_LIB.S9S_MB_2U(SCH_1):PAGE56_I168@PURE_QUANTA.SOCKET4677_AZIF0045P001C01CS(CHIPS)':
 'DDR5_SA_ECC4': CDS_PINID='DDR5_SA_ECC4';
NODE_NAME     J27 58
 '@S9S_MB_2U_LIB.S9S_MB_2U(SCH_1):PAGE108_I179@PURE_QUANTA.SCONN288_ADR50017P130CC(CHIPS)':
 'CB4_A': CDS_PINID='CB4_A';
NODE_NAME     J28 58
 '@S9S_MB_2U_LIB.S9S_MB_2U(SCH_1):PAGE109_I47@PURE_QUANTA.SCONN288_ADR50017P087CC(CHIPS)':
 'CB4_A': CDS_PINID='CB4_A';
NET_NAME
'M_F_CPU1_SA_CB<5>'
 '@S9S_MB_2U_LIB.S9S_MB_2U(SCH_1):M_F_CPU1_SA_CB'<5>:
 C_SIGNAL='@s9s_mb_2u_lib.s9s_mb_2u(sch_1):m_f_cpu1_sa_cb(5)';
NODE_NAME     U1 EE56
 '@S9S_MB_2U_LIB.S9S_MB_2U(SCH_1):PAGE56_I168@PURE_QUANTA.SOCKET4677_AZIF0045P001C01CS(CHIPS)':
 'DDR5_SA_ECC5': CDS_PINID='DDR5_SA_ECC5';
NODE_NAME     J27 60
 '@S9S_MB_2U_LIB.S9S_MB_2U(SCH_1):PAGE108_I179@PURE_QUANTA.SCONN288_ADR50017P130CC(CHIPS)':
 'CB5_A': CDS_PINID='CB5_A';
NODE_NAME     J28 60
 '@S9S_MB_2U_LIB.S9S_MB_2U(SCH_1):PAGE109_I47@PURE_QUANTA.SCONN288_ADR50017P087CC(CHIPS)':
 'CB5_A': CDS_PINID='CB5_A';
NET_NAME
'M_F_CPU1_SA_CB<6>'
 '@S9S_MB_2U_LIB.S9S_MB_2U(SCH_1):M_F_CPU1_SA_CB'<6>:
 C_SIGNAL='@s9s_mb_2u_lib.s9s_mb_2u(sch_1):m_f_cpu1_sa_cb(6)';
NODE_NAME     U1 EH57
 '@S9S_MB_2U_LIB.S9S_MB_2U(SCH_1):PAGE56_I168@PURE_QUANTA.SOCKET4677_AZIF0045P001C01CS(CHIPS)':
 'DDR5_SA_ECC6': CDS_PINID='DDR5_SA_ECC6';
NODE_NAME     J27 203
 '@S9S_MB_2U_LIB.S9S_MB_2U(SCH_1):PAGE108_I179@PURE_QUANTA.SCONN288_ADR50017P130CC(CHIPS)':
 'CB6_A': CDS_PINID='CB6_A';
NODE_NAME     J28 203
 '@S9S_MB_2U_LIB.S9S_MB_2U(SCH_1):PAGE109_I47@PURE_QUANTA.SCONN288_ADR50017P087CC(CHIPS)':
 'CB6_A': CDS_PINID='CB6_A';
NET_NAME
'M_F_CPU1_SA_CB<7>'
 '@S9S_MB_2U_LIB.S9S_MB_2U(SCH_1):M_F_CPU1_SA_CB'<7>:
 C_SIGNAL='@s9s_mb_2u_lib.s9s_mb_2u(sch_1):m_f_cpu1_sa_cb(7)';
NODE_NAME     U1 EG56
 '@S9S_MB_2U_LIB.S9S_MB_2U(SCH_1):PAGE56_I168@PURE_QUANTA.SOCKET4677_AZIF0045P001C01CS(CHIPS)':
 'DDR5_SA_ECC7': CDS_PINID='DDR5_SA_ECC7';
NODE_NAME     J27 205
 '@S9S_MB_2U_LIB.S9S_MB_2U(SCH_1):PAGE108_I179@PURE_QUANTA.SCONN288_ADR50017P130CC(CHIPS)':
 'CB7_A': CDS_PINID='CB7_A';
NODE_NAME     J28 205
 '@S9S_MB_2U_LIB.S9S_MB_2U(SCH_1):PAGE109_I47@PURE_QUANTA.SCONN288_ADR50017P087CC(CHIPS)':
 'CB7_A': CDS_PINID='CB7_A';
NET_NAME
'M_F_CPU1_SA_CS_N<0>'
 '@S9S_MB_2U_LIB.S9S_MB_2U(SCH_1):M_F_CPU1_SA_CS_N'<0>:
 C_SIGNAL='@s9s_mb_2u_lib.s9s_mb_2u(sch_1):m_f_cpu1_sa_cs_n(0)';
NODE_NAME     U1 EG54
 '@S9S_MB_2U_LIB.S9S_MB_2U(SCH_1):PAGE56_I168@PURE_QUANTA.SOCKET4677_AZIF0045P001C01CS(CHIPS)':
 'DDR5_SA_CS_N0': CDS_PINID='DDR5_SA_CS_N0';
NODE_NAME     J27 64
 '@S9S_MB_2U_LIB.S9S_MB_2U(SCH_1):PAGE108_I179@PURE_QUANTA.SCONN288_ADR50017P130CC(CHIPS)':
 'CS0_A_N': CDS_PINID='CS0_A_N';
NET_NAME
'M_F_CPU1_SA_CS_N<1>'
 '@S9S_MB_2U_LIB.S9S_MB_2U(SCH_1):M_F_CPU1_SA_CS_N'<1>:
 C_SIGNAL='@s9s_mb_2u_lib.s9s_mb_2u(sch_1):m_f_cpu1_sa_cs_n(1)';
NODE_NAME     U1 EH53
 '@S9S_MB_2U_LIB.S9S_MB_2U(SCH_1):PAGE56_I168@PURE_QUANTA.SOCKET4677_AZIF0045P001C01CS(CHIPS)':
 'DDR5_SA_CS_N1': CDS_PINID='DDR5_SA_CS_N1';
NODE_NAME     J27 209
 '@S9S_MB_2U_LIB.S9S_MB_2U(SCH_1):PAGE108_I179@PURE_QUANTA.SCONN288_ADR50017P130CC(CHIPS)':
 'CS1_A_N': CDS_PINID='CS1_A_N';
NET_NAME
'M_F_CPU1_SA_CS_N<2>'
 '@S9S_MB_2U_LIB.S9S_MB_2U(SCH_1):M_F_CPU1_SA_CS_N'<2>:
 C_SIGNAL='@s9s_mb_2u_lib.s9s_mb_2u(sch_1):m_f_cpu1_sa_cs_n(2)';
NODE_NAME     U1 EE54
 '@S9S_MB_2U_LIB.S9S_MB_2U(SCH_1):PAGE56_I168@PURE_QUANTA.SOCKET4677_AZIF0045P001C01CS(CHIPS)':
 'DDR5_SA_CS_N2': CDS_PINID='DDR5_SA_CS_N2';
NODE_NAME     J28 64
 '@S9S_MB_2U_LIB.S9S_MB_2U(SCH_1):PAGE109_I47@PURE_QUANTA.SCONN288_ADR50017P087CC(CHIPS)':
 'CS0_A_N': CDS_PINID='CS0_A_N';
NET_NAME
'M_F_CPU1_SA_CS_N<3>'
 '@S9S_MB_2U_LIB.S9S_MB_2U(SCH_1):M_F_CPU1_SA_CS_N'<3>:
 C_SIGNAL='@s9s_mb_2u_lib.s9s_mb_2u(sch_1):m_f_cpu1_sa_cs_n(3)';
NODE_NAME     U1 ED53
 '@S9S_MB_2U_LIB.S9S_MB_2U(SCH_1):PAGE56_I168@PURE_QUANTA.SOCKET4677_AZIF0045P001C01CS(CHIPS)':
 'DDR5_SA_CS_N3': CDS_PINID='DDR5_SA_CS_N3';
NODE_NAME     J28 209
 '@S9S_MB_2U_LIB.S9S_MB_2U(SCH_1):PAGE109_I47@PURE_QUANTA.SCONN288_ADR50017P087CC(CHIPS)':
 'CS1_A_N': CDS_PINID='CS1_A_N';
NET_NAME
'M_F_CPU1_SA_DQ<0>'
 '@S9S_MB_2U_LIB.S9S_MB_2U(SCH_1):M_F_CPU1_SA_DQ'<0>:
 C_SIGNAL='@s9s_mb_2u_lib.s9s_mb_2u(sch_1):m_f_cpu1_sa_dq(0)';
NODE_NAME     U1 EB77
 '@S9S_MB_2U_LIB.S9S_MB_2U(SCH_1):PAGE56_I168@PURE_QUANTA.SOCKET4677_AZIF0045P001C01CS(CHIPS)':
 'DDR5_SA_DQ0': CDS_PINID='DDR5_SA_DQ0';
NODE_NAME     J27 7
 '@S9S_MB_2U_LIB.S9S_MB_2U(SCH_1):PAGE108_I179@PURE_QUANTA.SCONN288_ADR50017P130CC(CHIPS)':
 'DQ0_A': CDS_PINID='DQ0_A';
NODE_NAME     J28 7
 '@S9S_MB_2U_LIB.S9S_MB_2U(SCH_1):PAGE109_I47@PURE_QUANTA.SCONN288_ADR50017P087CC(CHIPS)':
 'DQ0_A': CDS_PINID='DQ0_A';
NET_NAME
'M_F_CPU1_SA_DQ<10>'
 '@S9S_MB_2U_LIB.S9S_MB_2U(SCH_1):M_F_CPU1_SA_DQ'<10>:
 C_SIGNAL='@s9s_mb_2u_lib.s9s_mb_2u(sch_1):m_f_cpu1_sa_dq(10)';
NODE_NAME     U1 DY69
 '@S9S_MB_2U_LIB.S9S_MB_2U(SCH_1):PAGE56_I168@PURE_QUANTA.SOCKET4677_AZIF0045P001C01CS(CHIPS)':
 'DDR5_SA_DQ10': CDS_PINID='DDR5_SA_DQ10';
NODE_NAME     J27 163
 '@S9S_MB_2U_LIB.S9S_MB_2U(SCH_1):PAGE108_I179@PURE_QUANTA.SCONN288_ADR50017P130CC(CHIPS)':
 'DQ10_A': CDS_PINID='DQ10_A';
NODE_NAME     J28 163
 '@S9S_MB_2U_LIB.S9S_MB_2U(SCH_1):PAGE109_I47@PURE_QUANTA.SCONN288_ADR50017P087CC(CHIPS)':
 'DQ10_A': CDS_PINID='DQ10_A';
NET_NAME
'M_F_CPU1_SA_DQ<11>'
 '@S9S_MB_2U_LIB.S9S_MB_2U(SCH_1):M_F_CPU1_SA_DQ'<11>:
 C_SIGNAL='@s9s_mb_2u_lib.s9s_mb_2u(sch_1):m_f_cpu1_sa_dq(11)';
NODE_NAME     U1 EA68
 '@S9S_MB_2U_LIB.S9S_MB_2U(SCH_1):PAGE56_I168@PURE_QUANTA.SOCKET4677_AZIF0045P001C01CS(CHIPS)':
 'DDR5_SA_DQ11': CDS_PINID='DDR5_SA_DQ11';
NODE_NAME     J27 165
 '@S9S_MB_2U_LIB.S9S_MB_2U(SCH_1):PAGE108_I179@PURE_QUANTA.SCONN288_ADR50017P130CC(CHIPS)':
 'DQ11_A': CDS_PINID='DQ11_A';
NODE_NAME     J28 165
 '@S9S_MB_2U_LIB.S9S_MB_2U(SCH_1):PAGE109_I47@PURE_QUANTA.SCONN288_ADR50017P087CC(CHIPS)':
 'DQ11_A': CDS_PINID='DQ11_A';
NET_NAME
'M_F_CPU1_SA_DQ<12>'
 '@S9S_MB_2U_LIB.S9S_MB_2U(SCH_1):M_F_CPU1_SA_DQ'<12>:
 C_SIGNAL='@s9s_mb_2u_lib.s9s_mb_2u(sch_1):m_f_cpu1_sa_dq(12)';
NODE_NAME     U1 DU66
 '@S9S_MB_2U_LIB.S9S_MB_2U(SCH_1):PAGE56_I168@PURE_QUANTA.SOCKET4677_AZIF0045P001C01CS(CHIPS)':
 'DDR5_SA_DQ12': CDS_PINID='DDR5_SA_DQ12';
NODE_NAME     J27 25
 '@S9S_MB_2U_LIB.S9S_MB_2U(SCH_1):PAGE108_I179@PURE_QUANTA.SCONN288_ADR50017P130CC(CHIPS)':
 'DQ12_A': CDS_PINID='DQ12_A';
NODE_NAME     J28 25
 '@S9S_MB_2U_LIB.S9S_MB_2U(SCH_1):PAGE109_I47@PURE_QUANTA.SCONN288_ADR50017P087CC(CHIPS)':
 'DQ12_A': CDS_PINID='DQ12_A';
NET_NAME
'M_F_CPU1_SA_DQ<13>'
 '@S9S_MB_2U_LIB.S9S_MB_2U(SCH_1):M_F_CPU1_SA_DQ'<13>:
 C_SIGNAL='@s9s_mb_2u_lib.s9s_mb_2u(sch_1):m_f_cpu1_sa_dq(13)';
NODE_NAME     U1 DV65
 '@S9S_MB_2U_LIB.S9S_MB_2U(SCH_1):PAGE56_I168@PURE_QUANTA.SOCKET4677_AZIF0045P001C01CS(CHIPS)':
 'DDR5_SA_DQ13': CDS_PINID='DDR5_SA_DQ13';
NODE_NAME     J27 27
 '@S9S_MB_2U_LIB.S9S_MB_2U(SCH_1):PAGE108_I179@PURE_QUANTA.SCONN288_ADR50017P130CC(CHIPS)':
 'DQ13_A': CDS_PINID='DQ13_A';
NODE_NAME     J28 27
 '@S9S_MB_2U_LIB.S9S_MB_2U(SCH_1):PAGE109_I47@PURE_QUANTA.SCONN288_ADR50017P087CC(CHIPS)':
 'DQ13_A': CDS_PINID='DQ13_A';
NET_NAME
'M_F_CPU1_SA_DQ<14>'
 '@S9S_MB_2U_LIB.S9S_MB_2U(SCH_1):M_F_CPU1_SA_DQ'<14>:
 C_SIGNAL='@s9s_mb_2u_lib.s9s_mb_2u(sch_1):m_f_cpu1_sa_dq(14)';
NODE_NAME     U1 EA66
 '@S9S_MB_2U_LIB.S9S_MB_2U(SCH_1):PAGE56_I168@PURE_QUANTA.SOCKET4677_AZIF0045P001C01CS(CHIPS)':
 'DDR5_SA_DQ14': CDS_PINID='DDR5_SA_DQ14';
NODE_NAME     J27 170
 '@S9S_MB_2U_LIB.S9S_MB_2U(SCH_1):PAGE108_I179@PURE_QUANTA.SCONN288_ADR50017P130CC(CHIPS)':
 'DQ14_A': CDS_PINID='DQ14_A';
NODE_NAME     J28 170
 '@S9S_MB_2U_LIB.S9S_MB_2U(SCH_1):PAGE109_I47@PURE_QUANTA.SCONN288_ADR50017P087CC(CHIPS)':
 'DQ14_A': CDS_PINID='DQ14_A';
NET_NAME
'M_F_CPU1_SA_DQ<15>'
 '@S9S_MB_2U_LIB.S9S_MB_2U(SCH_1):M_F_CPU1_SA_DQ'<15>:
 C_SIGNAL='@s9s_mb_2u_lib.s9s_mb_2u(sch_1):m_f_cpu1_sa_dq(15)';
NODE_NAME     U1 DY65
 '@S9S_MB_2U_LIB.S9S_MB_2U(SCH_1):PAGE56_I168@PURE_QUANTA.SOCKET4677_AZIF0045P001C01CS(CHIPS)':
 'DDR5_SA_DQ15': CDS_PINID='DDR5_SA_DQ15';
NODE_NAME     J27 172
 '@S9S_MB_2U_LIB.S9S_MB_2U(SCH_1):PAGE108_I179@PURE_QUANTA.SCONN288_ADR50017P130CC(CHIPS)':
 'DQ15_A': CDS_PINID='DQ15_A';
NODE_NAME     J28 172
 '@S9S_MB_2U_LIB.S9S_MB_2U(SCH_1):PAGE109_I47@PURE_QUANTA.SCONN288_ADR50017P087CC(CHIPS)':
 'DQ15_A': CDS_PINID='DQ15_A';
NET_NAME
'M_F_CPU1_SA_DQ<16>'
 '@S9S_MB_2U_LIB.S9S_MB_2U(SCH_1):M_F_CPU1_SA_DQ'<16>:
 C_SIGNAL='@s9s_mb_2u_lib.s9s_mb_2u(sch_1):m_f_cpu1_sa_dq(16)';
NODE_NAME     U1 EE66
 '@S9S_MB_2U_LIB.S9S_MB_2U(SCH_1):PAGE56_I168@PURE_QUANTA.SOCKET4677_AZIF0045P001C01CS(CHIPS)':
 'DDR5_SA_DQ16': CDS_PINID='DDR5_SA_DQ16';
NODE_NAME     J27 29
 '@S9S_MB_2U_LIB.S9S_MB_2U(SCH_1):PAGE108_I179@PURE_QUANTA.SCONN288_ADR50017P130CC(CHIPS)':
 'DQ16_A': CDS_PINID='DQ16_A';
NODE_NAME     J28 29
 '@S9S_MB_2U_LIB.S9S_MB_2U(SCH_1):PAGE109_I47@PURE_QUANTA.SCONN288_ADR50017P087CC(CHIPS)':
 'DQ16_A': CDS_PINID='DQ16_A';
NET_NAME
'M_F_CPU1_SA_DQ<17>'
 '@S9S_MB_2U_LIB.S9S_MB_2U(SCH_1):M_F_CPU1_SA_DQ'<17>:
 C_SIGNAL='@s9s_mb_2u_lib.s9s_mb_2u(sch_1):m_f_cpu1_sa_dq(17)';
NODE_NAME     U1 ED65
 '@S9S_MB_2U_LIB.S9S_MB_2U(SCH_1):PAGE56_I168@PURE_QUANTA.SOCKET4677_AZIF0045P001C01CS(CHIPS)':
 'DDR5_SA_DQ17': CDS_PINID='DDR5_SA_DQ17';
NODE_NAME     J27 31
 '@S9S_MB_2U_LIB.S9S_MB_2U(SCH_1):PAGE108_I179@PURE_QUANTA.SCONN288_ADR50017P130CC(CHIPS)':
 'DQ17_A': CDS_PINID='DQ17_A';
NODE_NAME     J28 31
 '@S9S_MB_2U_LIB.S9S_MB_2U(SCH_1):PAGE109_I47@PURE_QUANTA.SCONN288_ADR50017P087CC(CHIPS)':
 'DQ17_A': CDS_PINID='DQ17_A';
NET_NAME
'M_F_CPU1_SA_DQ<18>'
 '@S9S_MB_2U_LIB.S9S_MB_2U(SCH_1):M_F_CPU1_SA_DQ'<18>:
 C_SIGNAL='@s9s_mb_2u_lib.s9s_mb_2u(sch_1):m_f_cpu1_sa_dq(18)';
NODE_NAME     U1 EG66
 '@S9S_MB_2U_LIB.S9S_MB_2U(SCH_1):PAGE56_I168@PURE_QUANTA.SOCKET4677_AZIF0045P001C01CS(CHIPS)':
 'DDR5_SA_DQ18': CDS_PINID='DDR5_SA_DQ18';
NODE_NAME     J27 174
 '@S9S_MB_2U_LIB.S9S_MB_2U(SCH_1):PAGE108_I179@PURE_QUANTA.SCONN288_ADR50017P130CC(CHIPS)':
 'DQ18_A': CDS_PINID='DQ18_A';
NODE_NAME     J28 174
 '@S9S_MB_2U_LIB.S9S_MB_2U(SCH_1):PAGE109_I47@PURE_QUANTA.SCONN288_ADR50017P087CC(CHIPS)':
 'DQ18_A': CDS_PINID='DQ18_A';
NET_NAME
'M_F_CPU1_SA_DQ<19>'
 '@S9S_MB_2U_LIB.S9S_MB_2U(SCH_1):M_F_CPU1_SA_DQ'<19>:
 C_SIGNAL='@s9s_mb_2u_lib.s9s_mb_2u(sch_1):m_f_cpu1_sa_dq(19)';
NODE_NAME     U1 EH65
 '@S9S_MB_2U_LIB.S9S_MB_2U(SCH_1):PAGE56_I168@PURE_QUANTA.SOCKET4677_AZIF0045P001C01CS(CHIPS)':
 'DDR5_SA_DQ19': CDS_PINID='DDR5_SA_DQ19';
NODE_NAME     J27 176
 '@S9S_MB_2U_LIB.S9S_MB_2U(SCH_1):PAGE108_I179@PURE_QUANTA.SCONN288_ADR50017P130CC(CHIPS)':
 'DQ19_A': CDS_PINID='DQ19_A';
NODE_NAME     J28 176
 '@S9S_MB_2U_LIB.S9S_MB_2U(SCH_1):PAGE109_I47@PURE_QUANTA.SCONN288_ADR50017P087CC(CHIPS)':
 'DQ19_A': CDS_PINID='DQ19_A';
NET_NAME
'M_F_CPU1_SA_DQ<1>'
 '@S9S_MB_2U_LIB.S9S_MB_2U(SCH_1):M_F_CPU1_SA_DQ'<1>:
 C_SIGNAL='@s9s_mb_2u_lib.s9s_mb_2u(sch_1):m_f_cpu1_sa_dq(1)';
NODE_NAME     U1 EH77
 '@S9S_MB_2U_LIB.S9S_MB_2U(SCH_1):PAGE56_I168@PURE_QUANTA.SOCKET4677_AZIF0045P001C01CS(CHIPS)':
 'DDR5_SA_DQ1': CDS_PINID='DDR5_SA_DQ1';
NODE_NAME     J27 9
 '@S9S_MB_2U_LIB.S9S_MB_2U(SCH_1):PAGE108_I179@PURE_QUANTA.SCONN288_ADR50017P130CC(CHIPS)':
 'DQ1_A': CDS_PINID='DQ1_A';
NODE_NAME     J28 9
 '@S9S_MB_2U_LIB.S9S_MB_2U(SCH_1):PAGE109_I47@PURE_QUANTA.SCONN288_ADR50017P087CC(CHIPS)':
 'DQ1_A': CDS_PINID='DQ1_A';
NET_NAME
'M_F_CPU1_SA_DQ<20>'
 '@S9S_MB_2U_LIB.S9S_MB_2U(SCH_1):M_F_CPU1_SA_DQ'<20>:
 C_SIGNAL='@s9s_mb_2u_lib.s9s_mb_2u(sch_1):m_f_cpu1_sa_dq(20)';
NODE_NAME     U1 ED63
 '@S9S_MB_2U_LIB.S9S_MB_2U(SCH_1):PAGE56_I168@PURE_QUANTA.SOCKET4677_AZIF0045P001C01CS(CHIPS)':
 'DDR5_SA_DQ20': CDS_PINID='DDR5_SA_DQ20';
NODE_NAME     J27 36
 '@S9S_MB_2U_LIB.S9S_MB_2U(SCH_1):PAGE108_I179@PURE_QUANTA.SCONN288_ADR50017P130CC(CHIPS)':
 'DQ20_A': CDS_PINID='DQ20_A';
NODE_NAME     J28 36
 '@S9S_MB_2U_LIB.S9S_MB_2U(SCH_1):PAGE109_I47@PURE_QUANTA.SCONN288_ADR50017P087CC(CHIPS)':
 'DQ20_A': CDS_PINID='DQ20_A';
NET_NAME
'M_F_CPU1_SA_DQ<21>'
 '@S9S_MB_2U_LIB.S9S_MB_2U(SCH_1):M_F_CPU1_SA_DQ'<21>:
 C_SIGNAL='@s9s_mb_2u_lib.s9s_mb_2u(sch_1):m_f_cpu1_sa_dq(21)';
NODE_NAME     U1 EE62
 '@S9S_MB_2U_LIB.S9S_MB_2U(SCH_1):PAGE56_I168@PURE_QUANTA.SOCKET4677_AZIF0045P001C01CS(CHIPS)':
 'DDR5_SA_DQ21': CDS_PINID='DDR5_SA_DQ21';
NODE_NAME     J27 38
 '@S9S_MB_2U_LIB.S9S_MB_2U(SCH_1):PAGE108_I179@PURE_QUANTA.SCONN288_ADR50017P130CC(CHIPS)':
 'DQ21_A': CDS_PINID='DQ21_A';
NODE_NAME     J28 38
 '@S9S_MB_2U_LIB.S9S_MB_2U(SCH_1):PAGE109_I47@PURE_QUANTA.SCONN288_ADR50017P087CC(CHIPS)':
 'DQ21_A': CDS_PINID='DQ21_A';
NET_NAME
'M_F_CPU1_SA_DQ<22>'
 '@S9S_MB_2U_LIB.S9S_MB_2U(SCH_1):M_F_CPU1_SA_DQ'<22>:
 C_SIGNAL='@s9s_mb_2u_lib.s9s_mb_2u(sch_1):m_f_cpu1_sa_dq(22)';
NODE_NAME     U1 EH63
 '@S9S_MB_2U_LIB.S9S_MB_2U(SCH_1):PAGE56_I168@PURE_QUANTA.SOCKET4677_AZIF0045P001C01CS(CHIPS)':
 'DDR5_SA_DQ22': CDS_PINID='DDR5_SA_DQ22';
NODE_NAME     J27 181
 '@S9S_MB_2U_LIB.S9S_MB_2U(SCH_1):PAGE108_I179@PURE_QUANTA.SCONN288_ADR50017P130CC(CHIPS)':
 'DQ22_A': CDS_PINID='DQ22_A';
NODE_NAME     J28 181
 '@S9S_MB_2U_LIB.S9S_MB_2U(SCH_1):PAGE109_I47@PURE_QUANTA.SCONN288_ADR50017P087CC(CHIPS)':
 'DQ22_A': CDS_PINID='DQ22_A';
NET_NAME
'M_F_CPU1_SA_DQ<23>'
 '@S9S_MB_2U_LIB.S9S_MB_2U(SCH_1):M_F_CPU1_SA_DQ'<23>:
 C_SIGNAL='@s9s_mb_2u_lib.s9s_mb_2u(sch_1):m_f_cpu1_sa_dq(23)';
NODE_NAME     U1 EG62
 '@S9S_MB_2U_LIB.S9S_MB_2U(SCH_1):PAGE56_I168@PURE_QUANTA.SOCKET4677_AZIF0045P001C01CS(CHIPS)':
 'DDR5_SA_DQ23': CDS_PINID='DDR5_SA_DQ23';
NODE_NAME     J27 183
 '@S9S_MB_2U_LIB.S9S_MB_2U(SCH_1):PAGE108_I179@PURE_QUANTA.SCONN288_ADR50017P130CC(CHIPS)':
 'DQ23_A': CDS_PINID='DQ23_A';
NODE_NAME     J28 183
 '@S9S_MB_2U_LIB.S9S_MB_2U(SCH_1):PAGE109_I47@PURE_QUANTA.SCONN288_ADR50017P087CC(CHIPS)':
 'DQ23_A': CDS_PINID='DQ23_A';
NET_NAME
'M_F_CPU1_SA_DQ<24>'
 '@S9S_MB_2U_LIB.S9S_MB_2U(SCH_1):M_F_CPU1_SA_DQ'<24>:
 C_SIGNAL='@s9s_mb_2u_lib.s9s_mb_2u(sch_1):m_f_cpu1_sa_dq(24)';
NODE_NAME     U1 DV57
 '@S9S_MB_2U_LIB.S9S_MB_2U(SCH_1):PAGE56_I168@PURE_QUANTA.SOCKET4677_AZIF0045P001C01CS(CHIPS)':
 'DDR5_SA_DQ24': CDS_PINID='DDR5_SA_DQ24';
NODE_NAME     J27 40
 '@S9S_MB_2U_LIB.S9S_MB_2U(SCH_1):PAGE108_I179@PURE_QUANTA.SCONN288_ADR50017P130CC(CHIPS)':
 'DQ24_A': CDS_PINID='DQ24_A';
NODE_NAME     J28 40
 '@S9S_MB_2U_LIB.S9S_MB_2U(SCH_1):PAGE109_I47@PURE_QUANTA.SCONN288_ADR50017P087CC(CHIPS)':
 'DQ24_A': CDS_PINID='DQ24_A';
NET_NAME
'M_F_CPU1_SA_DQ<25>'
 '@S9S_MB_2U_LIB.S9S_MB_2U(SCH_1):M_F_CPU1_SA_DQ'<25>:
 C_SIGNAL='@s9s_mb_2u_lib.s9s_mb_2u(sch_1):m_f_cpu1_sa_dq(25)';
NODE_NAME     U1 DU56
 '@S9S_MB_2U_LIB.S9S_MB_2U(SCH_1):PAGE56_I168@PURE_QUANTA.SOCKET4677_AZIF0045P001C01CS(CHIPS)':
 'DDR5_SA_DQ25': CDS_PINID='DDR5_SA_DQ25';
NODE_NAME     J27 42
 '@S9S_MB_2U_LIB.S9S_MB_2U(SCH_1):PAGE108_I179@PURE_QUANTA.SCONN288_ADR50017P130CC(CHIPS)':
 'DQ25_A': CDS_PINID='DQ25_A';
NODE_NAME     J28 42
 '@S9S_MB_2U_LIB.S9S_MB_2U(SCH_1):PAGE109_I47@PURE_QUANTA.SCONN288_ADR50017P087CC(CHIPS)':
 'DQ25_A': CDS_PINID='DQ25_A';
NET_NAME
'M_F_CPU1_SA_DQ<26>'
 '@S9S_MB_2U_LIB.S9S_MB_2U(SCH_1):M_F_CPU1_SA_DQ'<26>:
 C_SIGNAL='@s9s_mb_2u_lib.s9s_mb_2u(sch_1):m_f_cpu1_sa_dq(26)';
NODE_NAME     U1 DY57
 '@S9S_MB_2U_LIB.S9S_MB_2U(SCH_1):PAGE56_I168@PURE_QUANTA.SOCKET4677_AZIF0045P001C01CS(CHIPS)':
 'DDR5_SA_DQ26': CDS_PINID='DDR5_SA_DQ26';
NODE_NAME     J27 185
 '@S9S_MB_2U_LIB.S9S_MB_2U(SCH_1):PAGE108_I179@PURE_QUANTA.SCONN288_ADR50017P130CC(CHIPS)':
 'DQ26_A': CDS_PINID='DQ26_A';
NODE_NAME     J28 185
 '@S9S_MB_2U_LIB.S9S_MB_2U(SCH_1):PAGE109_I47@PURE_QUANTA.SCONN288_ADR50017P087CC(CHIPS)':
 'DQ26_A': CDS_PINID='DQ26_A';
NET_NAME
'M_F_CPU1_SA_DQ<27>'
 '@S9S_MB_2U_LIB.S9S_MB_2U(SCH_1):M_F_CPU1_SA_DQ'<27>:
 C_SIGNAL='@s9s_mb_2u_lib.s9s_mb_2u(sch_1):m_f_cpu1_sa_dq(27)';
NODE_NAME     U1 EA56
 '@S9S_MB_2U_LIB.S9S_MB_2U(SCH_1):PAGE56_I168@PURE_QUANTA.SOCKET4677_AZIF0045P001C01CS(CHIPS)':
 'DDR5_SA_DQ27': CDS_PINID='DDR5_SA_DQ27';
NODE_NAME     J27 187
 '@S9S_MB_2U_LIB.S9S_MB_2U(SCH_1):PAGE108_I179@PURE_QUANTA.SCONN288_ADR50017P130CC(CHIPS)':
 'DQ27_A': CDS_PINID='DQ27_A';
NODE_NAME     J28 187
 '@S9S_MB_2U_LIB.S9S_MB_2U(SCH_1):PAGE109_I47@PURE_QUANTA.SCONN288_ADR50017P087CC(CHIPS)':
 'DQ27_A': CDS_PINID='DQ27_A';
NET_NAME
'M_F_CPU1_SA_DQ<28>'
 '@S9S_MB_2U_LIB.S9S_MB_2U(SCH_1):M_F_CPU1_SA_DQ'<28>:
 C_SIGNAL='@s9s_mb_2u_lib.s9s_mb_2u(sch_1):m_f_cpu1_sa_dq(28)';
NODE_NAME     U1 DU54
 '@S9S_MB_2U_LIB.S9S_MB_2U(SCH_1):PAGE56_I168@PURE_QUANTA.SOCKET4677_AZIF0045P001C01CS(CHIPS)':
 'DDR5_SA_DQ28': CDS_PINID='DDR5_SA_DQ28';
NODE_NAME     J27 47
 '@S9S_MB_2U_LIB.S9S_MB_2U(SCH_1):PAGE108_I179@PURE_QUANTA.SCONN288_ADR50017P130CC(CHIPS)':
 'DQ28_A': CDS_PINID='DQ28_A';
NODE_NAME     J28 47
 '@S9S_MB_2U_LIB.S9S_MB_2U(SCH_1):PAGE109_I47@PURE_QUANTA.SCONN288_ADR50017P087CC(CHIPS)':
 'DQ28_A': CDS_PINID='DQ28_A';
NET_NAME
'M_F_CPU1_SA_DQ<29>'
 '@S9S_MB_2U_LIB.S9S_MB_2U(SCH_1):M_F_CPU1_SA_DQ'<29>:
 C_SIGNAL='@s9s_mb_2u_lib.s9s_mb_2u(sch_1):m_f_cpu1_sa_dq(29)';
NODE_NAME     U1 DV53
 '@S9S_MB_2U_LIB.S9S_MB_2U(SCH_1):PAGE56_I168@PURE_QUANTA.SOCKET4677_AZIF0045P001C01CS(CHIPS)':
 'DDR5_SA_DQ29': CDS_PINID='DDR5_SA_DQ29';
NODE_NAME     J27 49
 '@S9S_MB_2U_LIB.S9S_MB_2U(SCH_1):PAGE108_I179@PURE_QUANTA.SCONN288_ADR50017P130CC(CHIPS)':
 'DQ29_A': CDS_PINID='DQ29_A';
NODE_NAME     J28 49
 '@S9S_MB_2U_LIB.S9S_MB_2U(SCH_1):PAGE109_I47@PURE_QUANTA.SCONN288_ADR50017P087CC(CHIPS)':
 'DQ29_A': CDS_PINID='DQ29_A';
NET_NAME
'M_F_CPU1_SA_DQ<2>'
 '@S9S_MB_2U_LIB.S9S_MB_2U(SCH_1):M_F_CPU1_SA_DQ'<2>:
 C_SIGNAL='@s9s_mb_2u_lib.s9s_mb_2u(sch_1):m_f_cpu1_sa_dq(2)';
NODE_NAME     U1 ED77
 '@S9S_MB_2U_LIB.S9S_MB_2U(SCH_1):PAGE56_I168@PURE_QUANTA.SOCKET4677_AZIF0045P001C01CS(CHIPS)':
 'DDR5_SA_DQ2': CDS_PINID='DDR5_SA_DQ2';
NODE_NAME     J27 152
 '@S9S_MB_2U_LIB.S9S_MB_2U(SCH_1):PAGE108_I179@PURE_QUANTA.SCONN288_ADR50017P130CC(CHIPS)':
 'DQ2_A': CDS_PINID='DQ2_A';
NODE_NAME     J28 152
 '@S9S_MB_2U_LIB.S9S_MB_2U(SCH_1):PAGE109_I47@PURE_QUANTA.SCONN288_ADR50017P087CC(CHIPS)':
 'DQ2_A': CDS_PINID='DQ2_A';
NET_NAME
'M_F_CPU1_SA_DQ<30>'
 '@S9S_MB_2U_LIB.S9S_MB_2U(SCH_1):M_F_CPU1_SA_DQ'<30>:
 C_SIGNAL='@s9s_mb_2u_lib.s9s_mb_2u(sch_1):m_f_cpu1_sa_dq(30)';
NODE_NAME     U1 EA54
 '@S9S_MB_2U_LIB.S9S_MB_2U(SCH_1):PAGE56_I168@PURE_QUANTA.SOCKET4677_AZIF0045P001C01CS(CHIPS)':
 'DDR5_SA_DQ30': CDS_PINID='DDR5_SA_DQ30';
NODE_NAME     J27 192
 '@S9S_MB_2U_LIB.S9S_MB_2U(SCH_1):PAGE108_I179@PURE_QUANTA.SCONN288_ADR50017P130CC(CHIPS)':
 'DQ30_A': CDS_PINID='DQ30_A';
NODE_NAME     J28 192
 '@S9S_MB_2U_LIB.S9S_MB_2U(SCH_1):PAGE109_I47@PURE_QUANTA.SCONN288_ADR50017P087CC(CHIPS)':
 'DQ30_A': CDS_PINID='DQ30_A';
NET_NAME
'M_F_CPU1_SA_DQ<31>'
 '@S9S_MB_2U_LIB.S9S_MB_2U(SCH_1):M_F_CPU1_SA_DQ'<31>:
 C_SIGNAL='@s9s_mb_2u_lib.s9s_mb_2u(sch_1):m_f_cpu1_sa_dq(31)';
NODE_NAME     U1 DY53
 '@S9S_MB_2U_LIB.S9S_MB_2U(SCH_1):PAGE56_I168@PURE_QUANTA.SOCKET4677_AZIF0045P001C01CS(CHIPS)':
 'DDR5_SA_DQ31': CDS_PINID='DDR5_SA_DQ31';
NODE_NAME     J27 194
 '@S9S_MB_2U_LIB.S9S_MB_2U(SCH_1):PAGE108_I179@PURE_QUANTA.SCONN288_ADR50017P130CC(CHIPS)':
 'DQ31_A': CDS_PINID='DQ31_A';
NODE_NAME     J28 194
 '@S9S_MB_2U_LIB.S9S_MB_2U(SCH_1):PAGE109_I47@PURE_QUANTA.SCONN288_ADR50017P087CC(CHIPS)':
 'DQ31_A': CDS_PINID='DQ31_A';
NET_NAME
'M_F_CPU1_SA_DQ<3>'
 '@S9S_MB_2U_LIB.S9S_MB_2U(SCH_1):M_F_CPU1_SA_DQ'<3>:
 C_SIGNAL='@s9s_mb_2u_lib.s9s_mb_2u(sch_1):m_f_cpu1_sa_dq(3)';
NODE_NAME     U1 EG78
 '@S9S_MB_2U_LIB.S9S_MB_2U(SCH_1):PAGE56_I168@PURE_QUANTA.SOCKET4677_AZIF0045P001C01CS(CHIPS)':
 'DDR5_SA_DQ3': CDS_PINID='DDR5_SA_DQ3';
NODE_NAME     J27 154
 '@S9S_MB_2U_LIB.S9S_MB_2U(SCH_1):PAGE108_I179@PURE_QUANTA.SCONN288_ADR50017P130CC(CHIPS)':
 'DQ3_A': CDS_PINID='DQ3_A';
NODE_NAME     J28 154
 '@S9S_MB_2U_LIB.S9S_MB_2U(SCH_1):PAGE109_I47@PURE_QUANTA.SCONN288_ADR50017P087CC(CHIPS)':
 'DQ3_A': CDS_PINID='DQ3_A';
NET_NAME
'M_F_CPU1_SA_DQ<4>'
 '@S9S_MB_2U_LIB.S9S_MB_2U(SCH_1):M_F_CPU1_SA_DQ'<4>:
 C_SIGNAL='@s9s_mb_2u_lib.s9s_mb_2u(sch_1):m_f_cpu1_sa_dq(4)';
NODE_NAME     U1 ED75
 '@S9S_MB_2U_LIB.S9S_MB_2U(SCH_1):PAGE56_I168@PURE_QUANTA.SOCKET4677_AZIF0045P001C01CS(CHIPS)':
 'DDR5_SA_DQ4': CDS_PINID='DDR5_SA_DQ4';
NODE_NAME     J27 14
 '@S9S_MB_2U_LIB.S9S_MB_2U(SCH_1):PAGE108_I179@PURE_QUANTA.SCONN288_ADR50017P130CC(CHIPS)':
 'DQ4_A': CDS_PINID='DQ4_A';
NODE_NAME     J28 14
 '@S9S_MB_2U_LIB.S9S_MB_2U(SCH_1):PAGE109_I47@PURE_QUANTA.SCONN288_ADR50017P087CC(CHIPS)':
 'DQ4_A': CDS_PINID='DQ4_A';
NET_NAME
'M_F_CPU1_SA_DQ<5>'
 '@S9S_MB_2U_LIB.S9S_MB_2U(SCH_1):M_F_CPU1_SA_DQ'<5>:
 C_SIGNAL='@s9s_mb_2u_lib.s9s_mb_2u(sch_1):m_f_cpu1_sa_dq(5)';
NODE_NAME     U1 EE74
 '@S9S_MB_2U_LIB.S9S_MB_2U(SCH_1):PAGE56_I168@PURE_QUANTA.SOCKET4677_AZIF0045P001C01CS(CHIPS)':
 'DDR5_SA_DQ5': CDS_PINID='DDR5_SA_DQ5';
NODE_NAME     J27 16
 '@S9S_MB_2U_LIB.S9S_MB_2U(SCH_1):PAGE108_I179@PURE_QUANTA.SCONN288_ADR50017P130CC(CHIPS)':
 'DQ5_A': CDS_PINID='DQ5_A';
NODE_NAME     J28 16
 '@S9S_MB_2U_LIB.S9S_MB_2U(SCH_1):PAGE109_I47@PURE_QUANTA.SCONN288_ADR50017P087CC(CHIPS)':
 'DQ5_A': CDS_PINID='DQ5_A';
NET_NAME
'M_F_CPU1_SA_DQ<6>'
 '@S9S_MB_2U_LIB.S9S_MB_2U(SCH_1):M_F_CPU1_SA_DQ'<6>:
 C_SIGNAL='@s9s_mb_2u_lib.s9s_mb_2u(sch_1):m_f_cpu1_sa_dq(6)';
NODE_NAME     U1 EH75
 '@S9S_MB_2U_LIB.S9S_MB_2U(SCH_1):PAGE56_I168@PURE_QUANTA.SOCKET4677_AZIF0045P001C01CS(CHIPS)':
 'DDR5_SA_DQ6': CDS_PINID='DDR5_SA_DQ6';
NODE_NAME     J27 159
 '@S9S_MB_2U_LIB.S9S_MB_2U(SCH_1):PAGE108_I179@PURE_QUANTA.SCONN288_ADR50017P130CC(CHIPS)':
 'DQ6_A': CDS_PINID='DQ6_A';
NODE_NAME     J28 159
 '@S9S_MB_2U_LIB.S9S_MB_2U(SCH_1):PAGE109_I47@PURE_QUANTA.SCONN288_ADR50017P087CC(CHIPS)':
 'DQ6_A': CDS_PINID='DQ6_A';
NET_NAME
'M_F_CPU1_SA_DQ<7>'
 '@S9S_MB_2U_LIB.S9S_MB_2U(SCH_1):M_F_CPU1_SA_DQ'<7>:
 C_SIGNAL='@s9s_mb_2u_lib.s9s_mb_2u(sch_1):m_f_cpu1_sa_dq(7)';
NODE_NAME     U1 EG74
 '@S9S_MB_2U_LIB.S9S_MB_2U(SCH_1):PAGE56_I168@PURE_QUANTA.SOCKET4677_AZIF0045P001C01CS(CHIPS)':
 'DDR5_SA_DQ7': CDS_PINID='DDR5_SA_DQ7';
NODE_NAME     J27 161
 '@S9S_MB_2U_LIB.S9S_MB_2U(SCH_1):PAGE108_I179@PURE_QUANTA.SCONN288_ADR50017P130CC(CHIPS)':
 'DQ7_A': CDS_PINID='DQ7_A';
NODE_NAME     J28 161
 '@S9S_MB_2U_LIB.S9S_MB_2U(SCH_1):PAGE109_I47@PURE_QUANTA.SCONN288_ADR50017P087CC(CHIPS)':
 'DQ7_A': CDS_PINID='DQ7_A';
NET_NAME
'M_F_CPU1_SA_DQ<8>'
 '@S9S_MB_2U_LIB.S9S_MB_2U(SCH_1):M_F_CPU1_SA_DQ'<8>:
 C_SIGNAL='@s9s_mb_2u_lib.s9s_mb_2u(sch_1):m_f_cpu1_sa_dq(8)';
NODE_NAME     U1 DV69
 '@S9S_MB_2U_LIB.S9S_MB_2U(SCH_1):PAGE56_I168@PURE_QUANTA.SOCKET4677_AZIF0045P001C01CS(CHIPS)':
 'DDR5_SA_DQ8': CDS_PINID='DDR5_SA_DQ8';
NODE_NAME     J27 18
 '@S9S_MB_2U_LIB.S9S_MB_2U(SCH_1):PAGE108_I179@PURE_QUANTA.SCONN288_ADR50017P130CC(CHIPS)':
 'DQ8_A': CDS_PINID='DQ8_A';
NODE_NAME     J28 18
 '@S9S_MB_2U_LIB.S9S_MB_2U(SCH_1):PAGE109_I47@PURE_QUANTA.SCONN288_ADR50017P087CC(CHIPS)':
 'DQ8_A': CDS_PINID='DQ8_A';
NET_NAME
'M_F_CPU1_SA_DQ<9>'
 '@S9S_MB_2U_LIB.S9S_MB_2U(SCH_1):M_F_CPU1_SA_DQ'<9>:
 C_SIGNAL='@s9s_mb_2u_lib.s9s_mb_2u(sch_1):m_f_cpu1_sa_dq(9)';
NODE_NAME     U1 DU68
 '@S9S_MB_2U_LIB.S9S_MB_2U(SCH_1):PAGE56_I168@PURE_QUANTA.SOCKET4677_AZIF0045P001C01CS(CHIPS)':
 'DDR5_SA_DQ9': CDS_PINID='DDR5_SA_DQ9';
NODE_NAME     J27 20
 '@S9S_MB_2U_LIB.S9S_MB_2U(SCH_1):PAGE108_I179@PURE_QUANTA.SCONN288_ADR50017P130CC(CHIPS)':
 'DQ9_A': CDS_PINID='DQ9_A';
NODE_NAME     J28 20
 '@S9S_MB_2U_LIB.S9S_MB_2U(SCH_1):PAGE109_I47@PURE_QUANTA.SCONN288_ADR50017P087CC(CHIPS)':
 'DQ9_A': CDS_PINID='DQ9_A';
NET_NAME
'M_F_CPU1_SA_DQS_DN<0>'
 '@S9S_MB_2U_LIB.S9S_MB_2U(SCH_1):M_F_CPU1_SA_DQS_DN'<0>:
 C_SIGNAL='@s9s_mb_2u_lib.s9s_mb_2u(sch_1):m_f_cpu1_sa_dqs_dn(0)';
NODE_NAME     U1 EE76
 '@S9S_MB_2U_LIB.S9S_MB_2U(SCH_1):PAGE56_I168@PURE_QUANTA.SOCKET4677_AZIF0045P001C01CS(CHIPS)':
 'DDR5_SA_DQS_DN0': CDS_PINID='DDR5_SA_DQS_DN0';
NODE_NAME     J27 12
 '@S9S_MB_2U_LIB.S9S_MB_2U(SCH_1):PAGE108_I180@PURE_QUANTA.SCONN288_ADR50017P130CC(CHIPS)':
 'DQS0_A_C': CDS_PINID='DQS0_A_C';
NODE_NAME     J28 12
 '@S9S_MB_2U_LIB.S9S_MB_2U(SCH_1):PAGE109_I178@PURE_QUANTA.SCONN288_ADR50017P087CC(CHIPS)':
 'DQS0_A_C': CDS_PINID='DQS0_A_C';
NET_NAME
'M_F_CPU1_SA_DQS_DN<1>'
 '@S9S_MB_2U_LIB.S9S_MB_2U(SCH_1):M_F_CPU1_SA_DQS_DN'<1>:
 C_SIGNAL='@s9s_mb_2u_lib.s9s_mb_2u(sch_1):m_f_cpu1_sa_dqs_dn(1)';
NODE_NAME     U1 DT67
 '@S9S_MB_2U_LIB.S9S_MB_2U(SCH_1):PAGE56_I168@PURE_QUANTA.SOCKET4677_AZIF0045P001C01CS(CHIPS)':
 'DDR5_SA_DQS_DN1': CDS_PINID='DDR5_SA_DQS_DN1';
NODE_NAME     J27 23
 '@S9S_MB_2U_LIB.S9S_MB_2U(SCH_1):PAGE108_I180@PURE_QUANTA.SCONN288_ADR50017P130CC(CHIPS)':
 'DQS1_A_C': CDS_PINID='DQS1_A_C';
NODE_NAME     J28 23
 '@S9S_MB_2U_LIB.S9S_MB_2U(SCH_1):PAGE109_I178@PURE_QUANTA.SCONN288_ADR50017P087CC(CHIPS)':
 'DQS1_A_C': CDS_PINID='DQS1_A_C';
NET_NAME
'M_F_CPU1_SA_DQS_DN<2>'
 '@S9S_MB_2U_LIB.S9S_MB_2U(SCH_1):M_F_CPU1_SA_DQS_DN'<2>:
 C_SIGNAL='@s9s_mb_2u_lib.s9s_mb_2u(sch_1):m_f_cpu1_sa_dqs_dn(2)';
NODE_NAME     U1 EC64
 '@S9S_MB_2U_LIB.S9S_MB_2U(SCH_1):PAGE56_I168@PURE_QUANTA.SOCKET4677_AZIF0045P001C01CS(CHIPS)':
 'DDR5_SA_DQS_DN2': CDS_PINID='DDR5_SA_DQS_DN2';
NODE_NAME     J27 34
 '@S9S_MB_2U_LIB.S9S_MB_2U(SCH_1):PAGE108_I180@PURE_QUANTA.SCONN288_ADR50017P130CC(CHIPS)':
 'DQS2_A_C': CDS_PINID='DQS2_A_C';
NODE_NAME     J28 34
 '@S9S_MB_2U_LIB.S9S_MB_2U(SCH_1):PAGE109_I178@PURE_QUANTA.SCONN288_ADR50017P087CC(CHIPS)':
 'DQS2_A_C': CDS_PINID='DQS2_A_C';
NET_NAME
'M_F_CPU1_SA_DQS_DN<3>'
 '@S9S_MB_2U_LIB.S9S_MB_2U(SCH_1):M_F_CPU1_SA_DQS_DN'<3>:
 C_SIGNAL='@s9s_mb_2u_lib.s9s_mb_2u(sch_1):m_f_cpu1_sa_dqs_dn(3)';
NODE_NAME     U1 DV55
 '@S9S_MB_2U_LIB.S9S_MB_2U(SCH_1):PAGE56_I168@PURE_QUANTA.SOCKET4677_AZIF0045P001C01CS(CHIPS)':
 'DDR5_SA_DQS_DN3': CDS_PINID='DDR5_SA_DQS_DN3';
NODE_NAME     J27 45
 '@S9S_MB_2U_LIB.S9S_MB_2U(SCH_1):PAGE108_I180@PURE_QUANTA.SCONN288_ADR50017P130CC(CHIPS)':
 'DQS3_A_C': CDS_PINID='DQS3_A_C';
NODE_NAME     J28 45
 '@S9S_MB_2U_LIB.S9S_MB_2U(SCH_1):PAGE109_I178@PURE_QUANTA.SCONN288_ADR50017P087CC(CHIPS)':
 'DQS3_A_C': CDS_PINID='DQS3_A_C';
NET_NAME
'M_F_CPU1_SA_DQS_DN<4>'
 '@S9S_MB_2U_LIB.S9S_MB_2U(SCH_1):M_F_CPU1_SA_DQS_DN'<4>:
 C_SIGNAL='@s9s_mb_2u_lib.s9s_mb_2u(sch_1):m_f_cpu1_sa_dqs_dn(4)';
NODE_NAME     U1 EE58
 '@S9S_MB_2U_LIB.S9S_MB_2U(SCH_1):PAGE56_I168@PURE_QUANTA.SOCKET4677_AZIF0045P001C01CS(CHIPS)':
 'DDR5_SA_DQS_DN4': CDS_PINID='DDR5_SA_DQS_DN4';
NODE_NAME     J27 56
 '@S9S_MB_2U_LIB.S9S_MB_2U(SCH_1):PAGE108_I180@PURE_QUANTA.SCONN288_ADR50017P130CC(CHIPS)':
 'DQS4_A_C': CDS_PINID='DQS4_A_C';
NODE_NAME     J28 56
 '@S9S_MB_2U_LIB.S9S_MB_2U(SCH_1):PAGE109_I178@PURE_QUANTA.SCONN288_ADR50017P087CC(CHIPS)':
 'DQS4_A_C': CDS_PINID='DQS4_A_C';
NET_NAME
'M_F_CPU1_SA_DQS_DN<5>'
 '@S9S_MB_2U_LIB.S9S_MB_2U(SCH_1):M_F_CPU1_SA_DQS_DN'<5>:
 C_SIGNAL='@s9s_mb_2u_lib.s9s_mb_2u(sch_1):m_f_cpu1_sa_dqs_dn(5)';
NODE_NAME     U1 EJ76
 '@S9S_MB_2U_LIB.S9S_MB_2U(SCH_1):PAGE56_I168@PURE_QUANTA.SOCKET4677_AZIF0045P001C01CS(CHIPS)':
 'DDR5_SA_DQS_DN5': CDS_PINID='DDR5_SA_DQS_DN5';
NODE_NAME     J27 156
 '@S9S_MB_2U_LIB.S9S_MB_2U(SCH_1):PAGE108_I180@PURE_QUANTA.SCONN288_ADR50017P130CC(CHIPS)':
 'DQS5_A_C||TDQS5_A_C||DQS5_A_T||TDQS5_A_T': CDS_PINID='\dqs5_a_c||tdqs5_a_c||dqs5_a_t||tdqs5_a_t\';
NODE_NAME     J28 156
 '@S9S_MB_2U_LIB.S9S_MB_2U(SCH_1):PAGE109_I178@PURE_QUANTA.SCONN288_ADR50017P087CC(CHIPS)':
 'DQS5_A_C||TDQS5_A_C||DQS5_A_T||TDQS5_A_T': CDS_PINID='\dqs5_a_c||tdqs5_a_c||dqs5_a_t||tdqs5_a_t\';
NET_NAME
'M_F_CPU1_SA_DQS_DN<6>'
 '@S9S_MB_2U_LIB.S9S_MB_2U(SCH_1):M_F_CPU1_SA_DQS_DN'<6>:
 C_SIGNAL='@s9s_mb_2u_lib.s9s_mb_2u(sch_1):m_f_cpu1_sa_dqs_dn(6)';
NODE_NAME     U1 EB67
 '@S9S_MB_2U_LIB.S9S_MB_2U(SCH_1):PAGE56_I168@PURE_QUANTA.SOCKET4677_AZIF0045P001C01CS(CHIPS)':
 'DDR5_SA_DQS_DN6': CDS_PINID='DDR5_SA_DQS_DN6';
NODE_NAME     J27 167
 '@S9S_MB_2U_LIB.S9S_MB_2U(SCH_1):PAGE108_I180@PURE_QUANTA.SCONN288_ADR50017P130CC(CHIPS)':
 'DQS6_A_C||TDQS6_A_C||DQS6_A_T||TDQS6_A_T': CDS_PINID='\dqs6_a_c||tdqs6_a_c||dqs6_a_t||tdqs6_a_t\';
NODE_NAME     J28 167
 '@S9S_MB_2U_LIB.S9S_MB_2U(SCH_1):PAGE109_I178@PURE_QUANTA.SCONN288_ADR50017P087CC(CHIPS)':
 'DQS6_A_C||TDQS6_A_C||DQS6_A_T||TDQS6_A_T': CDS_PINID='\dqs6_a_c||tdqs6_a_c||dqs6_a_t||tdqs6_a_t\';
NET_NAME
'M_F_CPU1_SA_DQS_DN<7>'
 '@S9S_MB_2U_LIB.S9S_MB_2U(SCH_1):M_F_CPU1_SA_DQS_DN'<7>:
 C_SIGNAL='@s9s_mb_2u_lib.s9s_mb_2u(sch_1):m_f_cpu1_sa_dqs_dn(7)';
NODE_NAME     U1 EJ64
 '@S9S_MB_2U_LIB.S9S_MB_2U(SCH_1):PAGE56_I168@PURE_QUANTA.SOCKET4677_AZIF0045P001C01CS(CHIPS)':
 'DDR5_SA_DQS_DN7': CDS_PINID='DDR5_SA_DQS_DN7';
NODE_NAME     J27 178
 '@S9S_MB_2U_LIB.S9S_MB_2U(SCH_1):PAGE108_I180@PURE_QUANTA.SCONN288_ADR50017P130CC(CHIPS)':
 'DQS7_A_C||TDQS7_A_C': CDS_PINID='\dqs7_a_c||tdqs7_a_c\';
NODE_NAME     J28 178
 '@S9S_MB_2U_LIB.S9S_MB_2U(SCH_1):PAGE109_I178@PURE_QUANTA.SCONN288_ADR50017P087CC(CHIPS)':
 'DQS7_A_C||TDQS7_A_C': CDS_PINID='\dqs7_a_c||tdqs7_a_c\';
NET_NAME
'M_F_CPU1_SA_DQS_DN<8>'
 '@S9S_MB_2U_LIB.S9S_MB_2U(SCH_1):M_F_CPU1_SA_DQS_DN'<8>:
 C_SIGNAL='@s9s_mb_2u_lib.s9s_mb_2u(sch_1):m_f_cpu1_sa_dqs_dn(8)';
NODE_NAME     U1 EB55
 '@S9S_MB_2U_LIB.S9S_MB_2U(SCH_1):PAGE56_I168@PURE_QUANTA.SOCKET4677_AZIF0045P001C01CS(CHIPS)':
 'DDR5_SA_DQS_DN8': CDS_PINID='DDR5_SA_DQS_DN8';
NODE_NAME     J27 189
 '@S9S_MB_2U_LIB.S9S_MB_2U(SCH_1):PAGE108_I180@PURE_QUANTA.SCONN288_ADR50017P130CC(CHIPS)':
 'DQS8_A_C||TDQS8_A_C': CDS_PINID='\dqs8_a_c||tdqs8_a_c\';
NODE_NAME     J28 189
 '@S9S_MB_2U_LIB.S9S_MB_2U(SCH_1):PAGE109_I178@PURE_QUANTA.SCONN288_ADR50017P087CC(CHIPS)':
 'DQS8_A_C||TDQS8_A_C': CDS_PINID='\dqs8_a_c||tdqs8_a_c\';
NET_NAME
'M_F_CPU1_SA_DQS_DN<9>'
 '@S9S_MB_2U_LIB.S9S_MB_2U(SCH_1):M_F_CPU1_SA_DQS_DN'<9>:
 C_SIGNAL='@s9s_mb_2u_lib.s9s_mb_2u(sch_1):m_f_cpu1_sa_dqs_dn(9)';
NODE_NAME     U1 EJ58
 '@S9S_MB_2U_LIB.S9S_MB_2U(SCH_1):PAGE56_I168@PURE_QUANTA.SOCKET4677_AZIF0045P001C01CS(CHIPS)':
 'DDR5_SA_DQS_DN9': CDS_PINID='DDR5_SA_DQS_DN9';
NODE_NAME     J27 200
 '@S9S_MB_2U_LIB.S9S_MB_2U(SCH_1):PAGE108_I180@PURE_QUANTA.SCONN288_ADR50017P130CC(CHIPS)':
 'DQS9_A_C||TDQS9_A_C': CDS_PINID='\dqs9_a_c||tdqs9_a_c\';
NODE_NAME     J28 200
 '@S9S_MB_2U_LIB.S9S_MB_2U(SCH_1):PAGE109_I178@PURE_QUANTA.SCONN288_ADR50017P087CC(CHIPS)':
 'DQS9_A_C||TDQS9_A_C': CDS_PINID='\dqs9_a_c||tdqs9_a_c\';
NET_NAME
'M_F_CPU1_SA_DQS_DP<0>'
 '@S9S_MB_2U_LIB.S9S_MB_2U(SCH_1):M_F_CPU1_SA_DQS_DP'<0>:
 C_SIGNAL='@s9s_mb_2u_lib.s9s_mb_2u(sch_1):m_f_cpu1_sa_dqs_dp(0)';
NODE_NAME     U1 EC76
 '@S9S_MB_2U_LIB.S9S_MB_2U(SCH_1):PAGE56_I168@PURE_QUANTA.SOCKET4677_AZIF0045P001C01CS(CHIPS)':
 'DDR5_SA_DQS_DP0': CDS_PINID='DDR5_SA_DQS_DP0';
NODE_NAME     J27 11
 '@S9S_MB_2U_LIB.S9S_MB_2U(SCH_1):PAGE108_I180@PURE_QUANTA.SCONN288_ADR50017P130CC(CHIPS)':
 'DQS0_A_T': CDS_PINID='DQS0_A_T';
NODE_NAME     J28 11
 '@S9S_MB_2U_LIB.S9S_MB_2U(SCH_1):PAGE109_I178@PURE_QUANTA.SCONN288_ADR50017P087CC(CHIPS)':
 'DQS0_A_T': CDS_PINID='DQS0_A_T';
NET_NAME
'M_F_CPU1_SA_DQS_DP<1>'
 '@S9S_MB_2U_LIB.S9S_MB_2U(SCH_1):M_F_CPU1_SA_DQS_DP'<1>:
 C_SIGNAL='@s9s_mb_2u_lib.s9s_mb_2u(sch_1):m_f_cpu1_sa_dqs_dp(1)';
NODE_NAME     U1 DV67
 '@S9S_MB_2U_LIB.S9S_MB_2U(SCH_1):PAGE56_I168@PURE_QUANTA.SOCKET4677_AZIF0045P001C01CS(CHIPS)':
 'DDR5_SA_DQS_DP1': CDS_PINID='DDR5_SA_DQS_DP1';
NODE_NAME     J27 22
 '@S9S_MB_2U_LIB.S9S_MB_2U(SCH_1):PAGE108_I180@PURE_QUANTA.SCONN288_ADR50017P130CC(CHIPS)':
 'DQS1_A_T': CDS_PINID='DQS1_A_T';
NODE_NAME     J28 22
 '@S9S_MB_2U_LIB.S9S_MB_2U(SCH_1):PAGE109_I178@PURE_QUANTA.SCONN288_ADR50017P087CC(CHIPS)':
 'DQS1_A_T': CDS_PINID='DQS1_A_T';
NET_NAME
'M_F_CPU1_SA_DQS_DP<2>'
 '@S9S_MB_2U_LIB.S9S_MB_2U(SCH_1):M_F_CPU1_SA_DQS_DP'<2>:
 C_SIGNAL='@s9s_mb_2u_lib.s9s_mb_2u(sch_1):m_f_cpu1_sa_dqs_dp(2)';
NODE_NAME     U1 EE64
 '@S9S_MB_2U_LIB.S9S_MB_2U(SCH_1):PAGE56_I168@PURE_QUANTA.SOCKET4677_AZIF0045P001C01CS(CHIPS)':
 'DDR5_SA_DQS_DP2': CDS_PINID='DDR5_SA_DQS_DP2';
NODE_NAME     J27 33
 '@S9S_MB_2U_LIB.S9S_MB_2U(SCH_1):PAGE108_I180@PURE_QUANTA.SCONN288_ADR50017P130CC(CHIPS)':
 'DQS2_A_T': CDS_PINID='DQS2_A_T';
NODE_NAME     J28 33
 '@S9S_MB_2U_LIB.S9S_MB_2U(SCH_1):PAGE109_I178@PURE_QUANTA.SCONN288_ADR50017P087CC(CHIPS)':
 'DQS2_A_T': CDS_PINID='DQS2_A_T';
NET_NAME
'M_F_CPU1_SA_DQS_DP<3>'
 '@S9S_MB_2U_LIB.S9S_MB_2U(SCH_1):M_F_CPU1_SA_DQS_DP'<3>:
 C_SIGNAL='@s9s_mb_2u_lib.s9s_mb_2u(sch_1):m_f_cpu1_sa_dqs_dp(3)';
NODE_NAME     U1 DT55
 '@S9S_MB_2U_LIB.S9S_MB_2U(SCH_1):PAGE56_I168@PURE_QUANTA.SOCKET4677_AZIF0045P001C01CS(CHIPS)':
 'DDR5_SA_DQS_DP3': CDS_PINID='DDR5_SA_DQS_DP3';
NODE_NAME     J27 44
 '@S9S_MB_2U_LIB.S9S_MB_2U(SCH_1):PAGE108_I180@PURE_QUANTA.SCONN288_ADR50017P130CC(CHIPS)':
 'DQS3_A_T': CDS_PINID='DQS3_A_T';
NODE_NAME     J28 44
 '@S9S_MB_2U_LIB.S9S_MB_2U(SCH_1):PAGE109_I178@PURE_QUANTA.SCONN288_ADR50017P087CC(CHIPS)':
 'DQS3_A_T': CDS_PINID='DQS3_A_T';
NET_NAME
'M_F_CPU1_SA_DQS_DP<4>'
 '@S9S_MB_2U_LIB.S9S_MB_2U(SCH_1):M_F_CPU1_SA_DQS_DP'<4>:
 C_SIGNAL='@s9s_mb_2u_lib.s9s_mb_2u(sch_1):m_f_cpu1_sa_dqs_dp(4)';
NODE_NAME     U1 EC58
 '@S9S_MB_2U_LIB.S9S_MB_2U(SCH_1):PAGE56_I168@PURE_QUANTA.SOCKET4677_AZIF0045P001C01CS(CHIPS)':
 'DDR5_SA_DQS_DP4': CDS_PINID='DDR5_SA_DQS_DP4';
NODE_NAME     J27 55
 '@S9S_MB_2U_LIB.S9S_MB_2U(SCH_1):PAGE108_I180@PURE_QUANTA.SCONN288_ADR50017P130CC(CHIPS)':
 'DQS4_A_T': CDS_PINID='DQS4_A_T';
NODE_NAME     J28 55
 '@S9S_MB_2U_LIB.S9S_MB_2U(SCH_1):PAGE109_I178@PURE_QUANTA.SCONN288_ADR50017P087CC(CHIPS)':
 'DQS4_A_T': CDS_PINID='DQS4_A_T';
NET_NAME
'M_F_CPU1_SA_DQS_DP<5>'
 '@S9S_MB_2U_LIB.S9S_MB_2U(SCH_1):M_F_CPU1_SA_DQS_DP'<5>:
 C_SIGNAL='@s9s_mb_2u_lib.s9s_mb_2u(sch_1):m_f_cpu1_sa_dqs_dp(5)';
NODE_NAME     U1 EG76
 '@S9S_MB_2U_LIB.S9S_MB_2U(SCH_1):PAGE56_I168@PURE_QUANTA.SOCKET4677_AZIF0045P001C01CS(CHIPS)':
 'DDR5_SA_DQS_DP5': CDS_PINID='DDR5_SA_DQS_DP5';
NODE_NAME     J27 157
 '@S9S_MB_2U_LIB.S9S_MB_2U(SCH_1):PAGE108_I180@PURE_QUANTA.SCONN288_ADR50017P130CC(CHIPS)':
 'DQS5_A_T||TDQS5_A_T': CDS_PINID='\dqs5_a_t||tdqs5_a_t\';
NODE_NAME     J28 157
 '@S9S_MB_2U_LIB.S9S_MB_2U(SCH_1):PAGE109_I178@PURE_QUANTA.SCONN288_ADR50017P087CC(CHIPS)':
 'DQS5_A_T||TDQS5_A_T': CDS_PINID='\dqs5_a_t||tdqs5_a_t\';
NET_NAME
'M_F_CPU1_SA_DQS_DP<6>'
 '@S9S_MB_2U_LIB.S9S_MB_2U(SCH_1):M_F_CPU1_SA_DQS_DP'<6>:
 C_SIGNAL='@s9s_mb_2u_lib.s9s_mb_2u(sch_1):m_f_cpu1_sa_dqs_dp(6)';
NODE_NAME     U1 DY67
 '@S9S_MB_2U_LIB.S9S_MB_2U(SCH_1):PAGE56_I168@PURE_QUANTA.SOCKET4677_AZIF0045P001C01CS(CHIPS)':
 'DDR5_SA_DQS_DP6': CDS_PINID='DDR5_SA_DQS_DP6';
NODE_NAME     J27 168
 '@S9S_MB_2U_LIB.S9S_MB_2U(SCH_1):PAGE108_I180@PURE_QUANTA.SCONN288_ADR50017P130CC(CHIPS)':
 'DQS6_A_T||TDQS6_A_T': CDS_PINID='\dqs6_a_t||tdqs6_a_t\';
NODE_NAME     J28 168
 '@S9S_MB_2U_LIB.S9S_MB_2U(SCH_1):PAGE109_I178@PURE_QUANTA.SCONN288_ADR50017P087CC(CHIPS)':
 'DQS6_A_T||TDQS6_A_T': CDS_PINID='\dqs6_a_t||tdqs6_a_t\';
NET_NAME
'M_F_CPU1_SA_DQS_DP<7>'
 '@S9S_MB_2U_LIB.S9S_MB_2U(SCH_1):M_F_CPU1_SA_DQS_DP'<7>:
 C_SIGNAL='@s9s_mb_2u_lib.s9s_mb_2u(sch_1):m_f_cpu1_sa_dqs_dp(7)';
NODE_NAME     U1 EG64
 '@S9S_MB_2U_LIB.S9S_MB_2U(SCH_1):PAGE56_I168@PURE_QUANTA.SOCKET4677_AZIF0045P001C01CS(CHIPS)':
 'DDR5_SA_DQS_DP7': CDS_PINID='DDR5_SA_DQS_DP7';
NODE_NAME     J27 179
 '@S9S_MB_2U_LIB.S9S_MB_2U(SCH_1):PAGE108_I180@PURE_QUANTA.SCONN288_ADR50017P130CC(CHIPS)':
 'DQS7_A_T||TDQS7_A_T': CDS_PINID='\dqs7_a_t||tdqs7_a_t\';
NODE_NAME     J28 179
 '@S9S_MB_2U_LIB.S9S_MB_2U(SCH_1):PAGE109_I178@PURE_QUANTA.SCONN288_ADR50017P087CC(CHIPS)':
 'DQS7_A_T||TDQS7_A_T': CDS_PINID='\dqs7_a_t||tdqs7_a_t\';
NET_NAME
'M_F_CPU1_SA_DQS_DP<8>'
 '@S9S_MB_2U_LIB.S9S_MB_2U(SCH_1):M_F_CPU1_SA_DQS_DP'<8>:
 C_SIGNAL='@s9s_mb_2u_lib.s9s_mb_2u(sch_1):m_f_cpu1_sa_dqs_dp(8)';
NODE_NAME     U1 DY55
 '@S9S_MB_2U_LIB.S9S_MB_2U(SCH_1):PAGE56_I168@PURE_QUANTA.SOCKET4677_AZIF0045P001C01CS(CHIPS)':
 'DDR5_SA_DQS_DP8': CDS_PINID='DDR5_SA_DQS_DP8';
NODE_NAME     J27 190
 '@S9S_MB_2U_LIB.S9S_MB_2U(SCH_1):PAGE108_I180@PURE_QUANTA.SCONN288_ADR50017P130CC(CHIPS)':
 'DQS8_A_T||TDQS8_A_T': CDS_PINID='\dqs8_a_t||tdqs8_a_t\';
NODE_NAME     J28 190
 '@S9S_MB_2U_LIB.S9S_MB_2U(SCH_1):PAGE109_I178@PURE_QUANTA.SCONN288_ADR50017P087CC(CHIPS)':
 'DQS8_A_T||TDQS8_A_T': CDS_PINID='\dqs8_a_t||tdqs8_a_t\';
NET_NAME
'M_F_CPU1_SA_DQS_DP<9>'
 '@S9S_MB_2U_LIB.S9S_MB_2U(SCH_1):M_F_CPU1_SA_DQS_DP'<9>:
 C_SIGNAL='@s9s_mb_2u_lib.s9s_mb_2u(sch_1):m_f_cpu1_sa_dqs_dp(9)';
NODE_NAME     U1 EG58
 '@S9S_MB_2U_LIB.S9S_MB_2U(SCH_1):PAGE56_I168@PURE_QUANTA.SOCKET4677_AZIF0045P001C01CS(CHIPS)':
 'DDR5_SA_DQS_DP9': CDS_PINID='DDR5_SA_DQS_DP9';
NODE_NAME     J27 201
 '@S9S_MB_2U_LIB.S9S_MB_2U(SCH_1):PAGE108_I180@PURE_QUANTA.SCONN288_ADR50017P130CC(CHIPS)':
 'DQS9_A_T||TDQS9_A_T': CDS_PINID='\dqs9_a_t||tdqs9_a_t\';
NODE_NAME     J28 201
 '@S9S_MB_2U_LIB.S9S_MB_2U(SCH_1):PAGE109_I178@PURE_QUANTA.SCONN288_ADR50017P087CC(CHIPS)':
 'DQS9_A_T||TDQS9_A_T': CDS_PINID='\dqs9_a_t||tdqs9_a_t\';
NET_NAME
'M_F_CPU1_SA_PAR'
 '@S9S_MB_2U_LIB.S9S_MB_2U(SCH_1):M_F_CPU1_SA_PAR':
 C_SIGNAL='@s9s_mb_2u_lib.s9s_mb_2u(sch_1):m_f_cpu1_sa_par';
NODE_NAME     U1 EA50
 '@S9S_MB_2U_LIB.S9S_MB_2U(SCH_1):PAGE56_I168@PURE_QUANTA.SOCKET4677_AZIF0045P001C01CS(CHIPS)':
 'DDR5_SA_PAR': CDS_PINID='DDR5_SA_PAR';
NODE_NAME     J27 74
 '@S9S_MB_2U_LIB.S9S_MB_2U(SCH_1):PAGE108_I179@PURE_QUANTA.SCONN288_ADR50017P130CC(CHIPS)':
 'PAR_A': CDS_PINID='PAR_A';
NODE_NAME     J28 74
 '@S9S_MB_2U_LIB.S9S_MB_2U(SCH_1):PAGE109_I47@PURE_QUANTA.SCONN288_ADR50017P087CC(CHIPS)':
 'PAR_A': CDS_PINID='PAR_A';
NET_NAME
'M_F_CPU1_SA_RSP<0>'
 '@S9S_MB_2U_LIB.S9S_MB_2U(SCH_1):M_F_CPU1_SA_RSP'<0>:
 C_SIGNAL='@s9s_mb_2u_lib.s9s_mb_2u(sch_1):m_f_cpu1_sa_rsp(0)';
NODE_NAME     U1 DN48
 '@S9S_MB_2U_LIB.S9S_MB_2U(SCH_1):PAGE56_I168@PURE_QUANTA.SOCKET4677_AZIF0045P001C01CS(CHIPS)':
 'DDR5_A_RSP0': CDS_PINID='DDR5_A_RSP0';
NODE_NAME     J27 86
 '@S9S_MB_2U_LIB.S9S_MB_2U(SCH_1):PAGE108_I179@PURE_QUANTA.SCONN288_ADR50017P130CC(CHIPS)':
 'LBD||RSP_A_N': CDS_PINID='\lbd||rsp_a_n\';
NET_NAME
'M_F_CPU1_SA_RSP<1>'
 '@S9S_MB_2U_LIB.S9S_MB_2U(SCH_1):M_F_CPU1_SA_RSP'<1>:
 C_SIGNAL='@s9s_mb_2u_lib.s9s_mb_2u(sch_1):m_f_cpu1_sa_rsp(1)';
NODE_NAME     U1 DP47
 '@S9S_MB_2U_LIB.S9S_MB_2U(SCH_1):PAGE56_I168@PURE_QUANTA.SOCKET4677_AZIF0045P001C01CS(CHIPS)':
 'DDR5_A_RSP1': CDS_PINID='DDR5_A_RSP1';
NODE_NAME     J28 86
 '@S9S_MB_2U_LIB.S9S_MB_2U(SCH_1):PAGE109_I47@PURE_QUANTA.SCONN288_ADR50017P087CC(CHIPS)':
 'LBD||RSP_A_N': CDS_PINID='\lbd||rsp_a_n\';
NET_NAME
'M_F_CPU1_SB_CA<0>'
 '@S9S_MB_2U_LIB.S9S_MB_2U(SCH_1):M_F_CPU1_SB_CA'<0>:
 C_SIGNAL='@s9s_mb_2u_lib.s9s_mb_2u(sch_1):m_f_cpu1_sb_ca(0)';
NODE_NAME     U1 DV51
 '@S9S_MB_2U_LIB.S9S_MB_2U(SCH_1):PAGE56_I168@PURE_QUANTA.SOCKET4677_AZIF0045P001C01CS(CHIPS)':
 'DDR5_SB_CA0': CDS_PINID='DDR5_SB_CA0';
NODE_NAME     J27 76
 '@S9S_MB_2U_LIB.S9S_MB_2U(SCH_1):PAGE108_I179@PURE_QUANTA.SCONN288_ADR50017P130CC(CHIPS)':
 'CA0_B': CDS_PINID='CA0_B';
NODE_NAME     J28 76
 '@S9S_MB_2U_LIB.S9S_MB_2U(SCH_1):PAGE109_I47@PURE_QUANTA.SCONN288_ADR50017P087CC(CHIPS)':
 'CA0_B': CDS_PINID='CA0_B';
NET_NAME
'M_F_CPU1_SB_CA<1>'
 '@S9S_MB_2U_LIB.S9S_MB_2U(SCH_1):M_F_CPU1_SB_CA'<1>:
 C_SIGNAL='@s9s_mb_2u_lib.s9s_mb_2u(sch_1):m_f_cpu1_sb_ca(1)';
NODE_NAME     U1 DU50
 '@S9S_MB_2U_LIB.S9S_MB_2U(SCH_1):PAGE56_I168@PURE_QUANTA.SOCKET4677_AZIF0045P001C01CS(CHIPS)':
 'DDR5_SB_CA1': CDS_PINID='DDR5_SB_CA1';
NODE_NAME     J27 221
 '@S9S_MB_2U_LIB.S9S_MB_2U(SCH_1):PAGE108_I179@PURE_QUANTA.SCONN288_ADR50017P130CC(CHIPS)':
 'CA1_B': CDS_PINID='CA1_B';
NODE_NAME     J28 221
 '@S9S_MB_2U_LIB.S9S_MB_2U(SCH_1):PAGE109_I47@PURE_QUANTA.SCONN288_ADR50017P087CC(CHIPS)':
 'CA1_B': CDS_PINID='CA1_B';
NET_NAME
'M_F_CPU1_SB_CA<2>'
 '@S9S_MB_2U_LIB.S9S_MB_2U(SCH_1):M_F_CPU1_SB_CA'<2>:
 C_SIGNAL='@s9s_mb_2u_lib.s9s_mb_2u(sch_1):m_f_cpu1_sb_ca(2)';
NODE_NAME     U1 EE41
 '@S9S_MB_2U_LIB.S9S_MB_2U(SCH_1):PAGE56_I168@PURE_QUANTA.SOCKET4677_AZIF0045P001C01CS(CHIPS)':
 'DDR5_SB_CA2': CDS_PINID='DDR5_SB_CA2';
NODE_NAME     J27 78
 '@S9S_MB_2U_LIB.S9S_MB_2U(SCH_1):PAGE108_I179@PURE_QUANTA.SCONN288_ADR50017P130CC(CHIPS)':
 'CA2_B': CDS_PINID='CA2_B';
NODE_NAME     J28 78
 '@S9S_MB_2U_LIB.S9S_MB_2U(SCH_1):PAGE109_I47@PURE_QUANTA.SCONN288_ADR50017P087CC(CHIPS)':
 'CA2_B': CDS_PINID='CA2_B';
NET_NAME
'M_F_CPU1_SB_CA<3>'
 '@S9S_MB_2U_LIB.S9S_MB_2U(SCH_1):M_F_CPU1_SB_CA'<3>:
 C_SIGNAL='@s9s_mb_2u_lib.s9s_mb_2u(sch_1):m_f_cpu1_sb_ca(3)';
NODE_NAME     U1 EG41
 '@S9S_MB_2U_LIB.S9S_MB_2U(SCH_1):PAGE56_I168@PURE_QUANTA.SOCKET4677_AZIF0045P001C01CS(CHIPS)':
 'DDR5_SB_CA3': CDS_PINID='DDR5_SB_CA3';
NODE_NAME     J27 223
 '@S9S_MB_2U_LIB.S9S_MB_2U(SCH_1):PAGE108_I179@PURE_QUANTA.SCONN288_ADR50017P130CC(CHIPS)':
 'CA3_B': CDS_PINID='CA3_B';
NODE_NAME     J28 223
 '@S9S_MB_2U_LIB.S9S_MB_2U(SCH_1):PAGE109_I47@PURE_QUANTA.SCONN288_ADR50017P087CC(CHIPS)':
 'CA3_B': CDS_PINID='CA3_B';
NET_NAME
'M_F_CPU1_SB_CA<4>'
 '@S9S_MB_2U_LIB.S9S_MB_2U(SCH_1):M_F_CPU1_SB_CA'<4>:
 C_SIGNAL='@s9s_mb_2u_lib.s9s_mb_2u(sch_1):m_f_cpu1_sb_ca(4)';
NODE_NAME     U1 ED40
 '@S9S_MB_2U_LIB.S9S_MB_2U(SCH_1):PAGE56_I168@PURE_QUANTA.SOCKET4677_AZIF0045P001C01CS(CHIPS)':
 'DDR5_SB_CA4': CDS_PINID='DDR5_SB_CA4';
NODE_NAME     J27 80
 '@S9S_MB_2U_LIB.S9S_MB_2U(SCH_1):PAGE108_I179@PURE_QUANTA.SCONN288_ADR50017P130CC(CHIPS)':
 'CA4_B': CDS_PINID='CA4_B';
NODE_NAME     J28 80
 '@S9S_MB_2U_LIB.S9S_MB_2U(SCH_1):PAGE109_I47@PURE_QUANTA.SCONN288_ADR50017P087CC(CHIPS)':
 'CA4_B': CDS_PINID='CA4_B';
NET_NAME
'M_F_CPU1_SB_CA<5>'
 '@S9S_MB_2U_LIB.S9S_MB_2U(SCH_1):M_F_CPU1_SB_CA'<5>:
 C_SIGNAL='@s9s_mb_2u_lib.s9s_mb_2u(sch_1):m_f_cpu1_sb_ca(5)';
NODE_NAME     U1 EH40
 '@S9S_MB_2U_LIB.S9S_MB_2U(SCH_1):PAGE56_I168@PURE_QUANTA.SOCKET4677_AZIF0045P001C01CS(CHIPS)':
 'DDR5_SB_CA5': CDS_PINID='DDR5_SB_CA5';
NODE_NAME     J27 225
 '@S9S_MB_2U_LIB.S9S_MB_2U(SCH_1):PAGE108_I179@PURE_QUANTA.SCONN288_ADR50017P130CC(CHIPS)':
 'CA5_B': CDS_PINID='CA5_B';
NODE_NAME     J28 225
 '@S9S_MB_2U_LIB.S9S_MB_2U(SCH_1):PAGE109_I47@PURE_QUANTA.SCONN288_ADR50017P087CC(CHIPS)':
 'CA5_B': CDS_PINID='CA5_B';
NET_NAME
'M_F_CPU1_SB_CA<6>'
 '@S9S_MB_2U_LIB.S9S_MB_2U(SCH_1):M_F_CPU1_SB_CA'<6>:
 C_SIGNAL='@s9s_mb_2u_lib.s9s_mb_2u(sch_1):m_f_cpu1_sb_ca(6)';
NODE_NAME     U1 EC39
 '@S9S_MB_2U_LIB.S9S_MB_2U(SCH_1):PAGE56_I168@PURE_QUANTA.SOCKET4677_AZIF0045P001C01CS(CHIPS)':
 'DDR5_SB_CA6': CDS_PINID='DDR5_SB_CA6';
NODE_NAME     J27 82
 '@S9S_MB_2U_LIB.S9S_MB_2U(SCH_1):PAGE108_I179@PURE_QUANTA.SCONN288_ADR50017P130CC(CHIPS)':
 'CA6_B': CDS_PINID='CA6_B';
NODE_NAME     J28 82
 '@S9S_MB_2U_LIB.S9S_MB_2U(SCH_1):PAGE109_I47@PURE_QUANTA.SCONN288_ADR50017P087CC(CHIPS)':
 'CA6_B': CDS_PINID='CA6_B';
NET_NAME
'M_F_CPU1_SB_CB<0>'
 '@S9S_MB_2U_LIB.S9S_MB_2U(SCH_1):M_F_CPU1_SB_CB'<0>:
 C_SIGNAL='@s9s_mb_2u_lib.s9s_mb_2u(sch_1):m_f_cpu1_sb_cb(0)';
NODE_NAME     U1 ED32
 '@S9S_MB_2U_LIB.S9S_MB_2U(SCH_1):PAGE56_I168@PURE_QUANTA.SOCKET4677_AZIF0045P001C01CS(CHIPS)':
 'DDR5_SB_ECC0': CDS_PINID='DDR5_SB_ECC0';
NODE_NAME     J27 96
 '@S9S_MB_2U_LIB.S9S_MB_2U(SCH_1):PAGE108_I179@PURE_QUANTA.SCONN288_ADR50017P130CC(CHIPS)':
 'CB0_B': CDS_PINID='CB0_B';
NODE_NAME     J28 96
 '@S9S_MB_2U_LIB.S9S_MB_2U(SCH_1):PAGE109_I47@PURE_QUANTA.SCONN288_ADR50017P087CC(CHIPS)':
 'CB0_B': CDS_PINID='CB0_B';
NET_NAME
'M_F_CPU1_SB_CB<1>'
 '@S9S_MB_2U_LIB.S9S_MB_2U(SCH_1):M_F_CPU1_SB_CB'<1>:
 C_SIGNAL='@s9s_mb_2u_lib.s9s_mb_2u(sch_1):m_f_cpu1_sb_cb(1)';
NODE_NAME     U1 EE31
 '@S9S_MB_2U_LIB.S9S_MB_2U(SCH_1):PAGE56_I168@PURE_QUANTA.SOCKET4677_AZIF0045P001C01CS(CHIPS)':
 'DDR5_SB_ECC1': CDS_PINID='DDR5_SB_ECC1';
NODE_NAME     J27 98
 '@S9S_MB_2U_LIB.S9S_MB_2U(SCH_1):PAGE108_I179@PURE_QUANTA.SCONN288_ADR50017P130CC(CHIPS)':
 'CB1_B': CDS_PINID='CB1_B';
NODE_NAME     J28 98
 '@S9S_MB_2U_LIB.S9S_MB_2U(SCH_1):PAGE109_I47@PURE_QUANTA.SCONN288_ADR50017P087CC(CHIPS)':
 'CB1_B': CDS_PINID='CB1_B';
NET_NAME
'M_F_CPU1_SB_CB<2>'
 '@S9S_MB_2U_LIB.S9S_MB_2U(SCH_1):M_F_CPU1_SB_CB'<2>:
 C_SIGNAL='@s9s_mb_2u_lib.s9s_mb_2u(sch_1):m_f_cpu1_sb_cb(2)';
NODE_NAME     U1 EH32
 '@S9S_MB_2U_LIB.S9S_MB_2U(SCH_1):PAGE56_I168@PURE_QUANTA.SOCKET4677_AZIF0045P001C01CS(CHIPS)':
 'DDR5_SB_ECC2': CDS_PINID='DDR5_SB_ECC2';
NODE_NAME     J27 241
 '@S9S_MB_2U_LIB.S9S_MB_2U(SCH_1):PAGE108_I179@PURE_QUANTA.SCONN288_ADR50017P130CC(CHIPS)':
 'CB2_B': CDS_PINID='CB2_B';
NODE_NAME     J28 241
 '@S9S_MB_2U_LIB.S9S_MB_2U(SCH_1):PAGE109_I47@PURE_QUANTA.SCONN288_ADR50017P087CC(CHIPS)':
 'CB2_B': CDS_PINID='CB2_B';
NET_NAME
'M_F_CPU1_SB_CB<3>'
 '@S9S_MB_2U_LIB.S9S_MB_2U(SCH_1):M_F_CPU1_SB_CB'<3>:
 C_SIGNAL='@s9s_mb_2u_lib.s9s_mb_2u(sch_1):m_f_cpu1_sb_cb(3)';
NODE_NAME     U1 EG31
 '@S9S_MB_2U_LIB.S9S_MB_2U(SCH_1):PAGE56_I168@PURE_QUANTA.SOCKET4677_AZIF0045P001C01CS(CHIPS)':
 'DDR5_SB_ECC3': CDS_PINID='DDR5_SB_ECC3';
NODE_NAME     J27 243
 '@S9S_MB_2U_LIB.S9S_MB_2U(SCH_1):PAGE108_I179@PURE_QUANTA.SCONN288_ADR50017P130CC(CHIPS)':
 'CB3_B': CDS_PINID='CB3_B';
NODE_NAME     J28 243
 '@S9S_MB_2U_LIB.S9S_MB_2U(SCH_1):PAGE109_I47@PURE_QUANTA.SCONN288_ADR50017P087CC(CHIPS)':
 'CB3_B': CDS_PINID='CB3_B';
NET_NAME
'M_F_CPU1_SB_CB<4>'
 '@S9S_MB_2U_LIB.S9S_MB_2U(SCH_1):M_F_CPU1_SB_CB'<4>:
 C_SIGNAL='@s9s_mb_2u_lib.s9s_mb_2u(sch_1):m_f_cpu1_sb_cb(4)';
NODE_NAME     U1 EE35
 '@S9S_MB_2U_LIB.S9S_MB_2U(SCH_1):PAGE56_I168@PURE_QUANTA.SOCKET4677_AZIF0045P001C01CS(CHIPS)':
 'DDR5_SB_ECC4': CDS_PINID='DDR5_SB_ECC4';
NODE_NAME     J27 89
 '@S9S_MB_2U_LIB.S9S_MB_2U(SCH_1):PAGE108_I179@PURE_QUANTA.SCONN288_ADR50017P130CC(CHIPS)':
 'CB4_B': CDS_PINID='CB4_B';
NODE_NAME     J28 89
 '@S9S_MB_2U_LIB.S9S_MB_2U(SCH_1):PAGE109_I47@PURE_QUANTA.SCONN288_ADR50017P087CC(CHIPS)':
 'CB4_B': CDS_PINID='CB4_B';
NET_NAME
'M_F_CPU1_SB_CB<5>'
 '@S9S_MB_2U_LIB.S9S_MB_2U(SCH_1):M_F_CPU1_SB_CB'<5>:
 C_SIGNAL='@s9s_mb_2u_lib.s9s_mb_2u(sch_1):m_f_cpu1_sb_cb(5)';
NODE_NAME     U1 ED34
 '@S9S_MB_2U_LIB.S9S_MB_2U(SCH_1):PAGE56_I168@PURE_QUANTA.SOCKET4677_AZIF0045P001C01CS(CHIPS)':
 'DDR5_SB_ECC5': CDS_PINID='DDR5_SB_ECC5';
NODE_NAME     J27 91
 '@S9S_MB_2U_LIB.S9S_MB_2U(SCH_1):PAGE108_I179@PURE_QUANTA.SCONN288_ADR50017P130CC(CHIPS)':
 'CB5_B': CDS_PINID='CB5_B';
NODE_NAME     J28 91
 '@S9S_MB_2U_LIB.S9S_MB_2U(SCH_1):PAGE109_I47@PURE_QUANTA.SCONN288_ADR50017P087CC(CHIPS)':
 'CB5_B': CDS_PINID='CB5_B';
NET_NAME
'M_F_CPU1_SB_CB<6>'
 '@S9S_MB_2U_LIB.S9S_MB_2U(SCH_1):M_F_CPU1_SB_CB'<6>:
 C_SIGNAL='@s9s_mb_2u_lib.s9s_mb_2u(sch_1):m_f_cpu1_sb_cb(6)';
NODE_NAME     U1 EG35
 '@S9S_MB_2U_LIB.S9S_MB_2U(SCH_1):PAGE56_I168@PURE_QUANTA.SOCKET4677_AZIF0045P001C01CS(CHIPS)':
 'DDR5_SB_ECC6': CDS_PINID='DDR5_SB_ECC6';
NODE_NAME     J27 234
 '@S9S_MB_2U_LIB.S9S_MB_2U(SCH_1):PAGE108_I179@PURE_QUANTA.SCONN288_ADR50017P130CC(CHIPS)':
 'CB6_B': CDS_PINID='CB6_B';
NODE_NAME     J28 234
 '@S9S_MB_2U_LIB.S9S_MB_2U(SCH_1):PAGE109_I47@PURE_QUANTA.SCONN288_ADR50017P087CC(CHIPS)':
 'CB6_B': CDS_PINID='CB6_B';
NET_NAME
'M_F_CPU1_SB_CB<7>'
 '@S9S_MB_2U_LIB.S9S_MB_2U(SCH_1):M_F_CPU1_SB_CB'<7>:
 C_SIGNAL='@s9s_mb_2u_lib.s9s_mb_2u(sch_1):m_f_cpu1_sb_cb(7)';
NODE_NAME     U1 EH34
 '@S9S_MB_2U_LIB.S9S_MB_2U(SCH_1):PAGE56_I168@PURE_QUANTA.SOCKET4677_AZIF0045P001C01CS(CHIPS)':
 'DDR5_SB_ECC7': CDS_PINID='DDR5_SB_ECC7';
NODE_NAME     J27 236
 '@S9S_MB_2U_LIB.S9S_MB_2U(SCH_1):PAGE108_I179@PURE_QUANTA.SCONN288_ADR50017P130CC(CHIPS)':
 'CB7_B': CDS_PINID='CB7_B';
NODE_NAME     J28 236
 '@S9S_MB_2U_LIB.S9S_MB_2U(SCH_1):PAGE109_I47@PURE_QUANTA.SCONN288_ADR50017P087CC(CHIPS)':
 'CB7_B': CDS_PINID='CB7_B';
NET_NAME
'M_F_CPU1_SB_CS_N<0>'
 '@S9S_MB_2U_LIB.S9S_MB_2U(SCH_1):M_F_CPU1_SB_CS_N'<0>:
 C_SIGNAL='@s9s_mb_2u_lib.s9s_mb_2u(sch_1):m_f_cpu1_sb_cs_n(0)';
NODE_NAME     U1 EH38
 '@S9S_MB_2U_LIB.S9S_MB_2U(SCH_1):PAGE56_I168@PURE_QUANTA.SOCKET4677_AZIF0045P001C01CS(CHIPS)':
 'DDR5_SB_CS_N0': CDS_PINID='DDR5_SB_CS_N0';
NODE_NAME     J27 84
 '@S9S_MB_2U_LIB.S9S_MB_2U(SCH_1):PAGE108_I179@PURE_QUANTA.SCONN288_ADR50017P130CC(CHIPS)':
 'CS0_B_N': CDS_PINID='CS0_B_N';
NET_NAME
'M_F_CPU1_SB_CS_N<1>'
 '@S9S_MB_2U_LIB.S9S_MB_2U(SCH_1):M_F_CPU1_SB_CS_N'<1>:
 C_SIGNAL='@s9s_mb_2u_lib.s9s_mb_2u(sch_1):m_f_cpu1_sb_cs_n(1)';
NODE_NAME     U1 EG37
 '@S9S_MB_2U_LIB.S9S_MB_2U(SCH_1):PAGE56_I168@PURE_QUANTA.SOCKET4677_AZIF0045P001C01CS(CHIPS)':
 'DDR5_SB_CS_N1': CDS_PINID='DDR5_SB_CS_N1';
NODE_NAME     J27 229
 '@S9S_MB_2U_LIB.S9S_MB_2U(SCH_1):PAGE108_I179@PURE_QUANTA.SCONN288_ADR50017P130CC(CHIPS)':
 'CS1_B_N': CDS_PINID='CS1_B_N';
NET_NAME
'M_F_CPU1_SB_CS_N<2>'
 '@S9S_MB_2U_LIB.S9S_MB_2U(SCH_1):M_F_CPU1_SB_CS_N'<2>:
 C_SIGNAL='@s9s_mb_2u_lib.s9s_mb_2u(sch_1):m_f_cpu1_sb_cs_n(2)';
NODE_NAME     U1 ED38
 '@S9S_MB_2U_LIB.S9S_MB_2U(SCH_1):PAGE56_I168@PURE_QUANTA.SOCKET4677_AZIF0045P001C01CS(CHIPS)':
 'DDR5_SB_CS_N2': CDS_PINID='DDR5_SB_CS_N2';
NODE_NAME     J28 84
 '@S9S_MB_2U_LIB.S9S_MB_2U(SCH_1):PAGE109_I47@PURE_QUANTA.SCONN288_ADR50017P087CC(CHIPS)':
 'CS0_B_N': CDS_PINID='CS0_B_N';
NET_NAME
'M_F_CPU1_SB_CS_N<3>'
 '@S9S_MB_2U_LIB.S9S_MB_2U(SCH_1):M_F_CPU1_SB_CS_N'<3>:
 C_SIGNAL='@s9s_mb_2u_lib.s9s_mb_2u(sch_1):m_f_cpu1_sb_cs_n(3)';
NODE_NAME     U1 EE37
 '@S9S_MB_2U_LIB.S9S_MB_2U(SCH_1):PAGE56_I168@PURE_QUANTA.SOCKET4677_AZIF0045P001C01CS(CHIPS)':
 'DDR5_SB_CS_N3': CDS_PINID='DDR5_SB_CS_N3';
NODE_NAME     J28 229
 '@S9S_MB_2U_LIB.S9S_MB_2U(SCH_1):PAGE109_I47@PURE_QUANTA.SCONN288_ADR50017P087CC(CHIPS)':
 'CS1_B_N': CDS_PINID='CS1_B_N';
NET_NAME
'M_F_CPU1_SB_DQ<0>'
 '@S9S_MB_2U_LIB.S9S_MB_2U(SCH_1):M_F_CPU1_SB_DQ'<0>:
 C_SIGNAL='@s9s_mb_2u_lib.s9s_mb_2u(sch_1):m_f_cpu1_sb_dq(0)';
NODE_NAME     U1 DV32
 '@S9S_MB_2U_LIB.S9S_MB_2U(SCH_1):PAGE56_I168@PURE_QUANTA.SOCKET4677_AZIF0045P001C01CS(CHIPS)':
 'DDR5_SB_DQ0': CDS_PINID='DDR5_SB_DQ0';
NODE_NAME     J27 100
 '@S9S_MB_2U_LIB.S9S_MB_2U(SCH_1):PAGE108_I179@PURE_QUANTA.SCONN288_ADR50017P130CC(CHIPS)':
 'DQ0_B': CDS_PINID='DQ0_B';
NODE_NAME     J28 100
 '@S9S_MB_2U_LIB.S9S_MB_2U(SCH_1):PAGE109_I47@PURE_QUANTA.SCONN288_ADR50017P087CC(CHIPS)':
 'DQ0_B': CDS_PINID='DQ0_B';
NET_NAME
'M_F_CPU1_SB_DQ<10>'
 '@S9S_MB_2U_LIB.S9S_MB_2U(SCH_1):M_F_CPU1_SB_DQ'<10>:
 C_SIGNAL='@s9s_mb_2u_lib.s9s_mb_2u(sch_1):m_f_cpu1_sb_dq(10)';
NODE_NAME     U1 EG23
 '@S9S_MB_2U_LIB.S9S_MB_2U(SCH_1):PAGE56_I168@PURE_QUANTA.SOCKET4677_AZIF0045P001C01CS(CHIPS)':
 'DDR5_SB_DQ10': CDS_PINID='DDR5_SB_DQ10';
NODE_NAME     J27 256
 '@S9S_MB_2U_LIB.S9S_MB_2U(SCH_1):PAGE108_I179@PURE_QUANTA.SCONN288_ADR50017P130CC(CHIPS)':
 'DQ10_B': CDS_PINID='DQ10_B';
NODE_NAME     J28 256
 '@S9S_MB_2U_LIB.S9S_MB_2U(SCH_1):PAGE109_I47@PURE_QUANTA.SCONN288_ADR50017P087CC(CHIPS)':
 'DQ10_B': CDS_PINID='DQ10_B';
NET_NAME
'M_F_CPU1_SB_DQ<11>'
 '@S9S_MB_2U_LIB.S9S_MB_2U(SCH_1):M_F_CPU1_SB_DQ'<11>:
 C_SIGNAL='@s9s_mb_2u_lib.s9s_mb_2u(sch_1):m_f_cpu1_sb_dq(11)';
NODE_NAME     U1 EH22
 '@S9S_MB_2U_LIB.S9S_MB_2U(SCH_1):PAGE56_I168@PURE_QUANTA.SOCKET4677_AZIF0045P001C01CS(CHIPS)':
 'DDR5_SB_DQ11': CDS_PINID='DDR5_SB_DQ11';
NODE_NAME     J27 258
 '@S9S_MB_2U_LIB.S9S_MB_2U(SCH_1):PAGE108_I179@PURE_QUANTA.SCONN288_ADR50017P130CC(CHIPS)':
 'DQ11_B': CDS_PINID='DQ11_B';
NODE_NAME     J28 258
 '@S9S_MB_2U_LIB.S9S_MB_2U(SCH_1):PAGE109_I47@PURE_QUANTA.SCONN288_ADR50017P087CC(CHIPS)':
 'DQ11_B': CDS_PINID='DQ11_B';
NET_NAME
'M_F_CPU1_SB_DQ<12>'
 '@S9S_MB_2U_LIB.S9S_MB_2U(SCH_1):M_F_CPU1_SB_DQ'<12>:
 C_SIGNAL='@s9s_mb_2u_lib.s9s_mb_2u(sch_1):m_f_cpu1_sb_dq(12)';
NODE_NAME     U1 ED20
 '@S9S_MB_2U_LIB.S9S_MB_2U(SCH_1):PAGE56_I168@PURE_QUANTA.SOCKET4677_AZIF0045P001C01CS(CHIPS)':
 'DDR5_SB_DQ12': CDS_PINID='DDR5_SB_DQ12';
NODE_NAME     J27 118
 '@S9S_MB_2U_LIB.S9S_MB_2U(SCH_1):PAGE108_I179@PURE_QUANTA.SCONN288_ADR50017P130CC(CHIPS)':
 'DQ12_B': CDS_PINID='DQ12_B';
NODE_NAME     J28 118
 '@S9S_MB_2U_LIB.S9S_MB_2U(SCH_1):PAGE109_I47@PURE_QUANTA.SCONN288_ADR50017P087CC(CHIPS)':
 'DQ12_B': CDS_PINID='DQ12_B';
NET_NAME
'M_F_CPU1_SB_DQ<13>'
 '@S9S_MB_2U_LIB.S9S_MB_2U(SCH_1):M_F_CPU1_SB_DQ'<13>:
 C_SIGNAL='@s9s_mb_2u_lib.s9s_mb_2u(sch_1):m_f_cpu1_sb_dq(13)';
NODE_NAME     U1 EE19
 '@S9S_MB_2U_LIB.S9S_MB_2U(SCH_1):PAGE56_I168@PURE_QUANTA.SOCKET4677_AZIF0045P001C01CS(CHIPS)':
 'DDR5_SB_DQ13': CDS_PINID='DDR5_SB_DQ13';
NODE_NAME     J27 120
 '@S9S_MB_2U_LIB.S9S_MB_2U(SCH_1):PAGE108_I179@PURE_QUANTA.SCONN288_ADR50017P130CC(CHIPS)':
 'DQ13_B': CDS_PINID='DQ13_B';
NODE_NAME     J28 120
 '@S9S_MB_2U_LIB.S9S_MB_2U(SCH_1):PAGE109_I47@PURE_QUANTA.SCONN288_ADR50017P087CC(CHIPS)':
 'DQ13_B': CDS_PINID='DQ13_B';
NET_NAME
'M_F_CPU1_SB_DQ<14>'
 '@S9S_MB_2U_LIB.S9S_MB_2U(SCH_1):M_F_CPU1_SB_DQ'<14>:
 C_SIGNAL='@s9s_mb_2u_lib.s9s_mb_2u(sch_1):m_f_cpu1_sb_dq(14)';
NODE_NAME     U1 EH20
 '@S9S_MB_2U_LIB.S9S_MB_2U(SCH_1):PAGE56_I168@PURE_QUANTA.SOCKET4677_AZIF0045P001C01CS(CHIPS)':
 'DDR5_SB_DQ14': CDS_PINID='DDR5_SB_DQ14';
NODE_NAME     J27 263
 '@S9S_MB_2U_LIB.S9S_MB_2U(SCH_1):PAGE108_I179@PURE_QUANTA.SCONN288_ADR50017P130CC(CHIPS)':
 'DQ14_B': CDS_PINID='DQ14_B';
NODE_NAME     J28 263
 '@S9S_MB_2U_LIB.S9S_MB_2U(SCH_1):PAGE109_I47@PURE_QUANTA.SCONN288_ADR50017P087CC(CHIPS)':
 'DQ14_B': CDS_PINID='DQ14_B';
NET_NAME
'M_F_CPU1_SB_DQ<15>'
 '@S9S_MB_2U_LIB.S9S_MB_2U(SCH_1):M_F_CPU1_SB_DQ'<15>:
 C_SIGNAL='@s9s_mb_2u_lib.s9s_mb_2u(sch_1):m_f_cpu1_sb_dq(15)';
NODE_NAME     U1 EG19
 '@S9S_MB_2U_LIB.S9S_MB_2U(SCH_1):PAGE56_I168@PURE_QUANTA.SOCKET4677_AZIF0045P001C01CS(CHIPS)':
 'DDR5_SB_DQ15': CDS_PINID='DDR5_SB_DQ15';
NODE_NAME     J27 265
 '@S9S_MB_2U_LIB.S9S_MB_2U(SCH_1):PAGE108_I179@PURE_QUANTA.SCONN288_ADR50017P130CC(CHIPS)':
 'DQ15_B': CDS_PINID='DQ15_B';
NODE_NAME     J28 265
 '@S9S_MB_2U_LIB.S9S_MB_2U(SCH_1):PAGE109_I47@PURE_QUANTA.SCONN288_ADR50017P087CC(CHIPS)':
 'DQ15_B': CDS_PINID='DQ15_B';
NET_NAME
'M_F_CPU1_SB_DQ<16>'
 '@S9S_MB_2U_LIB.S9S_MB_2U(SCH_1):M_F_CPU1_SB_DQ'<16>:
 C_SIGNAL='@s9s_mb_2u_lib.s9s_mb_2u(sch_1):m_f_cpu1_sb_dq(16)';
NODE_NAME     U1 EM14
 '@S9S_MB_2U_LIB.S9S_MB_2U(SCH_1):PAGE56_I168@PURE_QUANTA.SOCKET4677_AZIF0045P001C01CS(CHIPS)':
 'DDR5_SB_DQ16': CDS_PINID='DDR5_SB_DQ16';
NODE_NAME     J27 122
 '@S9S_MB_2U_LIB.S9S_MB_2U(SCH_1):PAGE108_I179@PURE_QUANTA.SCONN288_ADR50017P130CC(CHIPS)':
 'DQ16_B': CDS_PINID='DQ16_B';
NODE_NAME     J28 122
 '@S9S_MB_2U_LIB.S9S_MB_2U(SCH_1):PAGE109_I47@PURE_QUANTA.SCONN288_ADR50017P087CC(CHIPS)':
 'DQ16_B': CDS_PINID='DQ16_B';
NET_NAME
'M_F_CPU1_SB_DQ<17>'
 '@S9S_MB_2U_LIB.S9S_MB_2U(SCH_1):M_F_CPU1_SB_DQ'<17>:
 C_SIGNAL='@s9s_mb_2u_lib.s9s_mb_2u(sch_1):m_f_cpu1_sb_dq(17)';
NODE_NAME     U1 EL13
 '@S9S_MB_2U_LIB.S9S_MB_2U(SCH_1):PAGE56_I168@PURE_QUANTA.SOCKET4677_AZIF0045P001C01CS(CHIPS)':
 'DDR5_SB_DQ17': CDS_PINID='DDR5_SB_DQ17';
NODE_NAME     J27 124
 '@S9S_MB_2U_LIB.S9S_MB_2U(SCH_1):PAGE108_I179@PURE_QUANTA.SCONN288_ADR50017P130CC(CHIPS)':
 'DQ17_B': CDS_PINID='DQ17_B';
NODE_NAME     J28 124
 '@S9S_MB_2U_LIB.S9S_MB_2U(SCH_1):PAGE109_I47@PURE_QUANTA.SCONN288_ADR50017P087CC(CHIPS)':
 'DQ17_B': CDS_PINID='DQ17_B';
NET_NAME
'M_F_CPU1_SB_DQ<18>'
 '@S9S_MB_2U_LIB.S9S_MB_2U(SCH_1):M_F_CPU1_SB_DQ'<18>:
 C_SIGNAL='@s9s_mb_2u_lib.s9s_mb_2u(sch_1):m_f_cpu1_sb_dq(18)';
NODE_NAME     U1 EP14
 '@S9S_MB_2U_LIB.S9S_MB_2U(SCH_1):PAGE56_I168@PURE_QUANTA.SOCKET4677_AZIF0045P001C01CS(CHIPS)':
 'DDR5_SB_DQ18': CDS_PINID='DDR5_SB_DQ18';
NODE_NAME     J27 267
 '@S9S_MB_2U_LIB.S9S_MB_2U(SCH_1):PAGE108_I179@PURE_QUANTA.SCONN288_ADR50017P130CC(CHIPS)':
 'DQ18_B': CDS_PINID='DQ18_B';
NODE_NAME     J28 267
 '@S9S_MB_2U_LIB.S9S_MB_2U(SCH_1):PAGE109_I47@PURE_QUANTA.SCONN288_ADR50017P087CC(CHIPS)':
 'DQ18_B': CDS_PINID='DQ18_B';
NET_NAME
'M_F_CPU1_SB_DQ<19>'
 '@S9S_MB_2U_LIB.S9S_MB_2U(SCH_1):M_F_CPU1_SB_DQ'<19>:
 C_SIGNAL='@s9s_mb_2u_lib.s9s_mb_2u(sch_1):m_f_cpu1_sb_dq(19)';
NODE_NAME     U1 ER13
 '@S9S_MB_2U_LIB.S9S_MB_2U(SCH_1):PAGE56_I168@PURE_QUANTA.SOCKET4677_AZIF0045P001C01CS(CHIPS)':
 'DDR5_SB_DQ19': CDS_PINID='DDR5_SB_DQ19';
NODE_NAME     J27 269
 '@S9S_MB_2U_LIB.S9S_MB_2U(SCH_1):PAGE108_I179@PURE_QUANTA.SCONN288_ADR50017P130CC(CHIPS)':
 'DQ19_B': CDS_PINID='DQ19_B';
NODE_NAME     J28 269
 '@S9S_MB_2U_LIB.S9S_MB_2U(SCH_1):PAGE109_I47@PURE_QUANTA.SCONN288_ADR50017P087CC(CHIPS)':
 'DQ19_B': CDS_PINID='DQ19_B';
NET_NAME
'M_F_CPU1_SB_DQ<1>'
 '@S9S_MB_2U_LIB.S9S_MB_2U(SCH_1):M_F_CPU1_SB_DQ'<1>:
 C_SIGNAL='@s9s_mb_2u_lib.s9s_mb_2u(sch_1):m_f_cpu1_sb_dq(1)';
NODE_NAME     U1 DU31
 '@S9S_MB_2U_LIB.S9S_MB_2U(SCH_1):PAGE56_I168@PURE_QUANTA.SOCKET4677_AZIF0045P001C01CS(CHIPS)':
 'DDR5_SB_DQ1': CDS_PINID='DDR5_SB_DQ1';
NODE_NAME     J27 102
 '@S9S_MB_2U_LIB.S9S_MB_2U(SCH_1):PAGE108_I179@PURE_QUANTA.SCONN288_ADR50017P130CC(CHIPS)':
 'DQ1_B': CDS_PINID='DQ1_B';
NODE_NAME     J28 102
 '@S9S_MB_2U_LIB.S9S_MB_2U(SCH_1):PAGE109_I47@PURE_QUANTA.SCONN288_ADR50017P087CC(CHIPS)':
 'DQ1_B': CDS_PINID='DQ1_B';
NET_NAME
'M_F_CPU1_SB_DQ<20>'
 '@S9S_MB_2U_LIB.S9S_MB_2U(SCH_1):M_F_CPU1_SB_DQ'<20>:
 C_SIGNAL='@s9s_mb_2u_lib.s9s_mb_2u(sch_1):m_f_cpu1_sb_dq(20)';
NODE_NAME     U1 EL11
 '@S9S_MB_2U_LIB.S9S_MB_2U(SCH_1):PAGE56_I168@PURE_QUANTA.SOCKET4677_AZIF0045P001C01CS(CHIPS)':
 'DDR5_SB_DQ20': CDS_PINID='DDR5_SB_DQ20';
NODE_NAME     J27 129
 '@S9S_MB_2U_LIB.S9S_MB_2U(SCH_1):PAGE108_I179@PURE_QUANTA.SCONN288_ADR50017P130CC(CHIPS)':
 'DQ20_B': CDS_PINID='DQ20_B';
NODE_NAME     J28 129
 '@S9S_MB_2U_LIB.S9S_MB_2U(SCH_1):PAGE109_I47@PURE_QUANTA.SCONN288_ADR50017P087CC(CHIPS)':
 'DQ20_B': CDS_PINID='DQ20_B';
NET_NAME
'M_F_CPU1_SB_DQ<21>'
 '@S9S_MB_2U_LIB.S9S_MB_2U(SCH_1):M_F_CPU1_SB_DQ'<21>:
 C_SIGNAL='@s9s_mb_2u_lib.s9s_mb_2u(sch_1):m_f_cpu1_sb_dq(21)';
NODE_NAME     U1 EM10
 '@S9S_MB_2U_LIB.S9S_MB_2U(SCH_1):PAGE56_I168@PURE_QUANTA.SOCKET4677_AZIF0045P001C01CS(CHIPS)':
 'DDR5_SB_DQ21': CDS_PINID='DDR5_SB_DQ21';
NODE_NAME     J27 131
 '@S9S_MB_2U_LIB.S9S_MB_2U(SCH_1):PAGE108_I179@PURE_QUANTA.SCONN288_ADR50017P130CC(CHIPS)':
 'DQ21_B': CDS_PINID='DQ21_B';
NODE_NAME     J28 131
 '@S9S_MB_2U_LIB.S9S_MB_2U(SCH_1):PAGE109_I47@PURE_QUANTA.SCONN288_ADR50017P087CC(CHIPS)':
 'DQ21_B': CDS_PINID='DQ21_B';
NET_NAME
'M_F_CPU1_SB_DQ<22>'
 '@S9S_MB_2U_LIB.S9S_MB_2U(SCH_1):M_F_CPU1_SB_DQ'<22>:
 C_SIGNAL='@s9s_mb_2u_lib.s9s_mb_2u(sch_1):m_f_cpu1_sb_dq(22)';
NODE_NAME     U1 ER11
 '@S9S_MB_2U_LIB.S9S_MB_2U(SCH_1):PAGE56_I168@PURE_QUANTA.SOCKET4677_AZIF0045P001C01CS(CHIPS)':
 'DDR5_SB_DQ22': CDS_PINID='DDR5_SB_DQ22';
NODE_NAME     J27 274
 '@S9S_MB_2U_LIB.S9S_MB_2U(SCH_1):PAGE108_I179@PURE_QUANTA.SCONN288_ADR50017P130CC(CHIPS)':
 'DQ22_B': CDS_PINID='DQ22_B';
NODE_NAME     J28 274
 '@S9S_MB_2U_LIB.S9S_MB_2U(SCH_1):PAGE109_I47@PURE_QUANTA.SCONN288_ADR50017P087CC(CHIPS)':
 'DQ22_B': CDS_PINID='DQ22_B';
NET_NAME
'M_F_CPU1_SB_DQ<23>'
 '@S9S_MB_2U_LIB.S9S_MB_2U(SCH_1):M_F_CPU1_SB_DQ'<23>:
 C_SIGNAL='@s9s_mb_2u_lib.s9s_mb_2u(sch_1):m_f_cpu1_sb_dq(23)';
NODE_NAME     U1 EP10
 '@S9S_MB_2U_LIB.S9S_MB_2U(SCH_1):PAGE56_I168@PURE_QUANTA.SOCKET4677_AZIF0045P001C01CS(CHIPS)':
 'DDR5_SB_DQ23': CDS_PINID='DDR5_SB_DQ23';
NODE_NAME     J27 276
 '@S9S_MB_2U_LIB.S9S_MB_2U(SCH_1):PAGE108_I179@PURE_QUANTA.SCONN288_ADR50017P130CC(CHIPS)':
 'DQ23_B': CDS_PINID='DQ23_B';
NODE_NAME     J28 276
 '@S9S_MB_2U_LIB.S9S_MB_2U(SCH_1):PAGE109_I47@PURE_QUANTA.SCONN288_ADR50017P087CC(CHIPS)':
 'DQ23_B': CDS_PINID='DQ23_B';
NET_NAME
'M_F_CPU1_SB_DQ<24>'
 '@S9S_MB_2U_LIB.S9S_MB_2U(SCH_1):M_F_CPU1_SB_DQ'<24>:
 C_SIGNAL='@s9s_mb_2u_lib.s9s_mb_2u(sch_1):m_f_cpu1_sb_dq(24)';
NODE_NAME     U1 DV20
 '@S9S_MB_2U_LIB.S9S_MB_2U(SCH_1):PAGE56_I168@PURE_QUANTA.SOCKET4677_AZIF0045P001C01CS(CHIPS)':
 'DDR5_SB_DQ24': CDS_PINID='DDR5_SB_DQ24';
NODE_NAME     J27 133
 '@S9S_MB_2U_LIB.S9S_MB_2U(SCH_1):PAGE108_I179@PURE_QUANTA.SCONN288_ADR50017P130CC(CHIPS)':
 'DQ24_B': CDS_PINID='DQ24_B';
NODE_NAME     J28 133
 '@S9S_MB_2U_LIB.S9S_MB_2U(SCH_1):PAGE109_I47@PURE_QUANTA.SCONN288_ADR50017P087CC(CHIPS)':
 'DQ24_B': CDS_PINID='DQ24_B';
NET_NAME
'M_F_CPU1_SB_DQ<25>'
 '@S9S_MB_2U_LIB.S9S_MB_2U(SCH_1):M_F_CPU1_SB_DQ'<25>:
 C_SIGNAL='@s9s_mb_2u_lib.s9s_mb_2u(sch_1):m_f_cpu1_sb_dq(25)';
NODE_NAME     U1 DU19
 '@S9S_MB_2U_LIB.S9S_MB_2U(SCH_1):PAGE56_I168@PURE_QUANTA.SOCKET4677_AZIF0045P001C01CS(CHIPS)':
 'DDR5_SB_DQ25': CDS_PINID='DDR5_SB_DQ25';
NODE_NAME     J27 135
 '@S9S_MB_2U_LIB.S9S_MB_2U(SCH_1):PAGE108_I179@PURE_QUANTA.SCONN288_ADR50017P130CC(CHIPS)':
 'DQ25_B': CDS_PINID='DQ25_B';
NODE_NAME     J28 135
 '@S9S_MB_2U_LIB.S9S_MB_2U(SCH_1):PAGE109_I47@PURE_QUANTA.SCONN288_ADR50017P087CC(CHIPS)':
 'DQ25_B': CDS_PINID='DQ25_B';
NET_NAME
'M_F_CPU1_SB_DQ<26>'
 '@S9S_MB_2U_LIB.S9S_MB_2U(SCH_1):M_F_CPU1_SB_DQ'<26>:
 C_SIGNAL='@s9s_mb_2u_lib.s9s_mb_2u(sch_1):m_f_cpu1_sb_dq(26)';
NODE_NAME     U1 DY20
 '@S9S_MB_2U_LIB.S9S_MB_2U(SCH_1):PAGE56_I168@PURE_QUANTA.SOCKET4677_AZIF0045P001C01CS(CHIPS)':
 'DDR5_SB_DQ26': CDS_PINID='DDR5_SB_DQ26';
NODE_NAME     J27 278
 '@S9S_MB_2U_LIB.S9S_MB_2U(SCH_1):PAGE108_I179@PURE_QUANTA.SCONN288_ADR50017P130CC(CHIPS)':
 'DQ26_B': CDS_PINID='DQ26_B';
NODE_NAME     J28 278
 '@S9S_MB_2U_LIB.S9S_MB_2U(SCH_1):PAGE109_I47@PURE_QUANTA.SCONN288_ADR50017P087CC(CHIPS)':
 'DQ26_B': CDS_PINID='DQ26_B';
NET_NAME
'M_F_CPU1_SB_DQ<27>'
 '@S9S_MB_2U_LIB.S9S_MB_2U(SCH_1):M_F_CPU1_SB_DQ'<27>:
 C_SIGNAL='@s9s_mb_2u_lib.s9s_mb_2u(sch_1):m_f_cpu1_sb_dq(27)';
NODE_NAME     U1 EA19
 '@S9S_MB_2U_LIB.S9S_MB_2U(SCH_1):PAGE56_I168@PURE_QUANTA.SOCKET4677_AZIF0045P001C01CS(CHIPS)':
 'DDR5_SB_DQ27': CDS_PINID='DDR5_SB_DQ27';
NODE_NAME     J27 280
 '@S9S_MB_2U_LIB.S9S_MB_2U(SCH_1):PAGE108_I179@PURE_QUANTA.SCONN288_ADR50017P130CC(CHIPS)':
 'DQ27_B': CDS_PINID='DQ27_B';
NODE_NAME     J28 280
 '@S9S_MB_2U_LIB.S9S_MB_2U(SCH_1):PAGE109_I47@PURE_QUANTA.SCONN288_ADR50017P087CC(CHIPS)':
 'DQ27_B': CDS_PINID='DQ27_B';
NET_NAME
'M_F_CPU1_SB_DQ<28>'
 '@S9S_MB_2U_LIB.S9S_MB_2U(SCH_1):M_F_CPU1_SB_DQ'<28>:
 C_SIGNAL='@s9s_mb_2u_lib.s9s_mb_2u(sch_1):m_f_cpu1_sb_dq(28)';
NODE_NAME     U1 EA17
 '@S9S_MB_2U_LIB.S9S_MB_2U(SCH_1):PAGE56_I168@PURE_QUANTA.SOCKET4677_AZIF0045P001C01CS(CHIPS)':
 'DDR5_SB_DQ28': CDS_PINID='DDR5_SB_DQ28';
NODE_NAME     J27 140
 '@S9S_MB_2U_LIB.S9S_MB_2U(SCH_1):PAGE108_I179@PURE_QUANTA.SCONN288_ADR50017P130CC(CHIPS)':
 'DQ28_B': CDS_PINID='DQ28_B';
NODE_NAME     J28 140
 '@S9S_MB_2U_LIB.S9S_MB_2U(SCH_1):PAGE109_I47@PURE_QUANTA.SCONN288_ADR50017P087CC(CHIPS)':
 'DQ28_B': CDS_PINID='DQ28_B';
NET_NAME
'M_F_CPU1_SB_DQ<29>'
 '@S9S_MB_2U_LIB.S9S_MB_2U(SCH_1):M_F_CPU1_SB_DQ'<29>:
 C_SIGNAL='@s9s_mb_2u_lib.s9s_mb_2u(sch_1):m_f_cpu1_sb_dq(29)';
NODE_NAME     U1 DU17
 '@S9S_MB_2U_LIB.S9S_MB_2U(SCH_1):PAGE56_I168@PURE_QUANTA.SOCKET4677_AZIF0045P001C01CS(CHIPS)':
 'DDR5_SB_DQ29': CDS_PINID='DDR5_SB_DQ29';
NODE_NAME     J27 142
 '@S9S_MB_2U_LIB.S9S_MB_2U(SCH_1):PAGE108_I179@PURE_QUANTA.SCONN288_ADR50017P130CC(CHIPS)':
 'DQ29_B': CDS_PINID='DQ29_B';
NODE_NAME     J28 142
 '@S9S_MB_2U_LIB.S9S_MB_2U(SCH_1):PAGE109_I47@PURE_QUANTA.SCONN288_ADR50017P087CC(CHIPS)':
 'DQ29_B': CDS_PINID='DQ29_B';
NET_NAME
'M_F_CPU1_SB_DQ<2>'
 '@S9S_MB_2U_LIB.S9S_MB_2U(SCH_1):M_F_CPU1_SB_DQ'<2>:
 C_SIGNAL='@s9s_mb_2u_lib.s9s_mb_2u(sch_1):m_f_cpu1_sb_dq(2)';
NODE_NAME     U1 DY32
 '@S9S_MB_2U_LIB.S9S_MB_2U(SCH_1):PAGE56_I168@PURE_QUANTA.SOCKET4677_AZIF0045P001C01CS(CHIPS)':
 'DDR5_SB_DQ2': CDS_PINID='DDR5_SB_DQ2';
NODE_NAME     J27 245
 '@S9S_MB_2U_LIB.S9S_MB_2U(SCH_1):PAGE108_I179@PURE_QUANTA.SCONN288_ADR50017P130CC(CHIPS)':
 'DQ2_B': CDS_PINID='DQ2_B';
NODE_NAME     J28 245
 '@S9S_MB_2U_LIB.S9S_MB_2U(SCH_1):PAGE109_I47@PURE_QUANTA.SCONN288_ADR50017P087CC(CHIPS)':
 'DQ2_B': CDS_PINID='DQ2_B';
NET_NAME
'M_F_CPU1_SB_DQ<30>'
 '@S9S_MB_2U_LIB.S9S_MB_2U(SCH_1):M_F_CPU1_SB_DQ'<30>:
 C_SIGNAL='@s9s_mb_2u_lib.s9s_mb_2u(sch_1):m_f_cpu1_sb_dq(30)';
NODE_NAME     U1 EC17
 '@S9S_MB_2U_LIB.S9S_MB_2U(SCH_1):PAGE56_I168@PURE_QUANTA.SOCKET4677_AZIF0045P001C01CS(CHIPS)':
 'DDR5_SB_DQ30': CDS_PINID='DDR5_SB_DQ30';
NODE_NAME     J27 285
 '@S9S_MB_2U_LIB.S9S_MB_2U(SCH_1):PAGE108_I179@PURE_QUANTA.SCONN288_ADR50017P130CC(CHIPS)':
 'DQ30_B': CDS_PINID='DQ30_B';
NODE_NAME     J28 285
 '@S9S_MB_2U_LIB.S9S_MB_2U(SCH_1):PAGE109_I47@PURE_QUANTA.SCONN288_ADR50017P087CC(CHIPS)':
 'DQ30_B': CDS_PINID='DQ30_B';
NET_NAME
'M_F_CPU1_SB_DQ<31>'
 '@S9S_MB_2U_LIB.S9S_MB_2U(SCH_1):M_F_CPU1_SB_DQ'<31>:
 C_SIGNAL='@s9s_mb_2u_lib.s9s_mb_2u(sch_1):m_f_cpu1_sb_dq(31)';
NODE_NAME     U1 DR17
 '@S9S_MB_2U_LIB.S9S_MB_2U(SCH_1):PAGE56_I168@PURE_QUANTA.SOCKET4677_AZIF0045P001C01CS(CHIPS)':
 'DDR5_SB_DQ31': CDS_PINID='DDR5_SB_DQ31';
NODE_NAME     J27 287
 '@S9S_MB_2U_LIB.S9S_MB_2U(SCH_1):PAGE108_I179@PURE_QUANTA.SCONN288_ADR50017P130CC(CHIPS)':
 'DQ31_B': CDS_PINID='DQ31_B';
NODE_NAME     J28 287
 '@S9S_MB_2U_LIB.S9S_MB_2U(SCH_1):PAGE109_I47@PURE_QUANTA.SCONN288_ADR50017P087CC(CHIPS)':
 'DQ31_B': CDS_PINID='DQ31_B';
NET_NAME
'M_F_CPU1_SB_DQ<3>'
 '@S9S_MB_2U_LIB.S9S_MB_2U(SCH_1):M_F_CPU1_SB_DQ'<3>:
 C_SIGNAL='@s9s_mb_2u_lib.s9s_mb_2u(sch_1):m_f_cpu1_sb_dq(3)';
NODE_NAME     U1 EA31
 '@S9S_MB_2U_LIB.S9S_MB_2U(SCH_1):PAGE56_I168@PURE_QUANTA.SOCKET4677_AZIF0045P001C01CS(CHIPS)':
 'DDR5_SB_DQ3': CDS_PINID='DDR5_SB_DQ3';
NODE_NAME     J27 247
 '@S9S_MB_2U_LIB.S9S_MB_2U(SCH_1):PAGE108_I179@PURE_QUANTA.SCONN288_ADR50017P130CC(CHIPS)':
 'DQ3_B': CDS_PINID='DQ3_B';
NODE_NAME     J28 247
 '@S9S_MB_2U_LIB.S9S_MB_2U(SCH_1):PAGE109_I47@PURE_QUANTA.SCONN288_ADR50017P087CC(CHIPS)':
 'DQ3_B': CDS_PINID='DQ3_B';
NET_NAME
'M_F_CPU1_SB_DQ<4>'
 '@S9S_MB_2U_LIB.S9S_MB_2U(SCH_1):M_F_CPU1_SB_DQ'<4>:
 C_SIGNAL='@s9s_mb_2u_lib.s9s_mb_2u(sch_1):m_f_cpu1_sb_dq(4)';
NODE_NAME     U1 DU29
 '@S9S_MB_2U_LIB.S9S_MB_2U(SCH_1):PAGE56_I168@PURE_QUANTA.SOCKET4677_AZIF0045P001C01CS(CHIPS)':
 'DDR5_SB_DQ4': CDS_PINID='DDR5_SB_DQ4';
NODE_NAME     J27 107
 '@S9S_MB_2U_LIB.S9S_MB_2U(SCH_1):PAGE108_I179@PURE_QUANTA.SCONN288_ADR50017P130CC(CHIPS)':
 'DQ4_B': CDS_PINID='DQ4_B';
NODE_NAME     J28 107
 '@S9S_MB_2U_LIB.S9S_MB_2U(SCH_1):PAGE109_I47@PURE_QUANTA.SCONN288_ADR50017P087CC(CHIPS)':
 'DQ4_B': CDS_PINID='DQ4_B';
NET_NAME
'M_F_CPU1_SB_DQ<5>'
 '@S9S_MB_2U_LIB.S9S_MB_2U(SCH_1):M_F_CPU1_SB_DQ'<5>:
 C_SIGNAL='@s9s_mb_2u_lib.s9s_mb_2u(sch_1):m_f_cpu1_sb_dq(5)';
NODE_NAME     U1 DV28
 '@S9S_MB_2U_LIB.S9S_MB_2U(SCH_1):PAGE56_I168@PURE_QUANTA.SOCKET4677_AZIF0045P001C01CS(CHIPS)':
 'DDR5_SB_DQ5': CDS_PINID='DDR5_SB_DQ5';
NODE_NAME     J27 109
 '@S9S_MB_2U_LIB.S9S_MB_2U(SCH_1):PAGE108_I179@PURE_QUANTA.SCONN288_ADR50017P130CC(CHIPS)':
 'DQ5_B': CDS_PINID='DQ5_B';
NODE_NAME     J28 109
 '@S9S_MB_2U_LIB.S9S_MB_2U(SCH_1):PAGE109_I47@PURE_QUANTA.SCONN288_ADR50017P087CC(CHIPS)':
 'DQ5_B': CDS_PINID='DQ5_B';
NET_NAME
'M_F_CPU1_SB_DQ<6>'
 '@S9S_MB_2U_LIB.S9S_MB_2U(SCH_1):M_F_CPU1_SB_DQ'<6>:
 C_SIGNAL='@s9s_mb_2u_lib.s9s_mb_2u(sch_1):m_f_cpu1_sb_dq(6)';
NODE_NAME     U1 EA29
 '@S9S_MB_2U_LIB.S9S_MB_2U(SCH_1):PAGE56_I168@PURE_QUANTA.SOCKET4677_AZIF0045P001C01CS(CHIPS)':
 'DDR5_SB_DQ6': CDS_PINID='DDR5_SB_DQ6';
NODE_NAME     J27 252
 '@S9S_MB_2U_LIB.S9S_MB_2U(SCH_1):PAGE108_I179@PURE_QUANTA.SCONN288_ADR50017P130CC(CHIPS)':
 'DQ6_B': CDS_PINID='DQ6_B';
NODE_NAME     J28 252
 '@S9S_MB_2U_LIB.S9S_MB_2U(SCH_1):PAGE109_I47@PURE_QUANTA.SCONN288_ADR50017P087CC(CHIPS)':
 'DQ6_B': CDS_PINID='DQ6_B';
NET_NAME
'M_F_CPU1_SB_DQ<7>'
 '@S9S_MB_2U_LIB.S9S_MB_2U(SCH_1):M_F_CPU1_SB_DQ'<7>:
 C_SIGNAL='@s9s_mb_2u_lib.s9s_mb_2u(sch_1):m_f_cpu1_sb_dq(7)';
NODE_NAME     U1 DY28
 '@S9S_MB_2U_LIB.S9S_MB_2U(SCH_1):PAGE56_I168@PURE_QUANTA.SOCKET4677_AZIF0045P001C01CS(CHIPS)':
 'DDR5_SB_DQ7': CDS_PINID='DDR5_SB_DQ7';
NODE_NAME     J27 254
 '@S9S_MB_2U_LIB.S9S_MB_2U(SCH_1):PAGE108_I179@PURE_QUANTA.SCONN288_ADR50017P130CC(CHIPS)':
 'DQ7_B': CDS_PINID='DQ7_B';
NODE_NAME     J28 254
 '@S9S_MB_2U_LIB.S9S_MB_2U(SCH_1):PAGE109_I47@PURE_QUANTA.SCONN288_ADR50017P087CC(CHIPS)':
 'DQ7_B': CDS_PINID='DQ7_B';
NET_NAME
'M_F_CPU1_SB_DQ<8>'
 '@S9S_MB_2U_LIB.S9S_MB_2U(SCH_1):M_F_CPU1_SB_DQ'<8>:
 C_SIGNAL='@s9s_mb_2u_lib.s9s_mb_2u(sch_1):m_f_cpu1_sb_dq(8)';
NODE_NAME     U1 EE23
 '@S9S_MB_2U_LIB.S9S_MB_2U(SCH_1):PAGE56_I168@PURE_QUANTA.SOCKET4677_AZIF0045P001C01CS(CHIPS)':
 'DDR5_SB_DQ8': CDS_PINID='DDR5_SB_DQ8';
NODE_NAME     J27 111
 '@S9S_MB_2U_LIB.S9S_MB_2U(SCH_1):PAGE108_I179@PURE_QUANTA.SCONN288_ADR50017P130CC(CHIPS)':
 'DQ8_B': CDS_PINID='DQ8_B';
NODE_NAME     J28 111
 '@S9S_MB_2U_LIB.S9S_MB_2U(SCH_1):PAGE109_I47@PURE_QUANTA.SCONN288_ADR50017P087CC(CHIPS)':
 'DQ8_B': CDS_PINID='DQ8_B';
NET_NAME
'M_F_CPU1_SB_DQ<9>'
 '@S9S_MB_2U_LIB.S9S_MB_2U(SCH_1):M_F_CPU1_SB_DQ'<9>:
 C_SIGNAL='@s9s_mb_2u_lib.s9s_mb_2u(sch_1):m_f_cpu1_sb_dq(9)';
NODE_NAME     U1 ED22
 '@S9S_MB_2U_LIB.S9S_MB_2U(SCH_1):PAGE56_I168@PURE_QUANTA.SOCKET4677_AZIF0045P001C01CS(CHIPS)':
 'DDR5_SB_DQ9': CDS_PINID='DDR5_SB_DQ9';
NODE_NAME     J27 113
 '@S9S_MB_2U_LIB.S9S_MB_2U(SCH_1):PAGE108_I179@PURE_QUANTA.SCONN288_ADR50017P130CC(CHIPS)':
 'DQ9_B': CDS_PINID='DQ9_B';
NODE_NAME     J28 113
 '@S9S_MB_2U_LIB.S9S_MB_2U(SCH_1):PAGE109_I47@PURE_QUANTA.SCONN288_ADR50017P087CC(CHIPS)':
 'DQ9_B': CDS_PINID='DQ9_B';
NET_NAME
'M_F_CPU1_SB_DQS_DN<0>'
 '@S9S_MB_2U_LIB.S9S_MB_2U(SCH_1):M_F_CPU1_SB_DQS_DN'<0>:
 C_SIGNAL='@s9s_mb_2u_lib.s9s_mb_2u(sch_1):m_f_cpu1_sb_dqs_dn(0)';
NODE_NAME     U1 DV30
 '@S9S_MB_2U_LIB.S9S_MB_2U(SCH_1):PAGE56_I168@PURE_QUANTA.SOCKET4677_AZIF0045P001C01CS(CHIPS)':
 'DDR5_SB_DQS_DN0': CDS_PINID='DDR5_SB_DQS_DN0';
NODE_NAME     J27 105
 '@S9S_MB_2U_LIB.S9S_MB_2U(SCH_1):PAGE108_I180@PURE_QUANTA.SCONN288_ADR50017P130CC(CHIPS)':
 'DQS0_B_C': CDS_PINID='DQS0_B_C';
NODE_NAME     J28 105
 '@S9S_MB_2U_LIB.S9S_MB_2U(SCH_1):PAGE109_I178@PURE_QUANTA.SCONN288_ADR50017P087CC(CHIPS)':
 'DQS0_B_C': CDS_PINID='DQS0_B_C';
NET_NAME
'M_F_CPU1_SB_DQS_DN<1>'
 '@S9S_MB_2U_LIB.S9S_MB_2U(SCH_1):M_F_CPU1_SB_DQS_DN'<1>:
 C_SIGNAL='@s9s_mb_2u_lib.s9s_mb_2u(sch_1):m_f_cpu1_sb_dqs_dn(1)';
NODE_NAME     U1 EE21
 '@S9S_MB_2U_LIB.S9S_MB_2U(SCH_1):PAGE56_I168@PURE_QUANTA.SOCKET4677_AZIF0045P001C01CS(CHIPS)':
 'DDR5_SB_DQS_DN1': CDS_PINID='DDR5_SB_DQS_DN1';
NODE_NAME     J27 116
 '@S9S_MB_2U_LIB.S9S_MB_2U(SCH_1):PAGE108_I180@PURE_QUANTA.SCONN288_ADR50017P130CC(CHIPS)':
 'DQS1_B_C': CDS_PINID='DQS1_B_C';
NODE_NAME     J28 116
 '@S9S_MB_2U_LIB.S9S_MB_2U(SCH_1):PAGE109_I178@PURE_QUANTA.SCONN288_ADR50017P087CC(CHIPS)':
 'DQS1_B_C': CDS_PINID='DQS1_B_C';
NET_NAME
'M_F_CPU1_SB_DQS_DN<2>'
 '@S9S_MB_2U_LIB.S9S_MB_2U(SCH_1):M_F_CPU1_SB_DQS_DN'<2>:
 C_SIGNAL='@s9s_mb_2u_lib.s9s_mb_2u(sch_1):m_f_cpu1_sb_dqs_dn(2)';
NODE_NAME     U1 EM12
 '@S9S_MB_2U_LIB.S9S_MB_2U(SCH_1):PAGE56_I168@PURE_QUANTA.SOCKET4677_AZIF0045P001C01CS(CHIPS)':
 'DDR5_SB_DQS_DN2': CDS_PINID='DDR5_SB_DQS_DN2';
NODE_NAME     J27 127
 '@S9S_MB_2U_LIB.S9S_MB_2U(SCH_1):PAGE108_I180@PURE_QUANTA.SCONN288_ADR50017P130CC(CHIPS)':
 'DQS2_B_C': CDS_PINID='DQS2_B_C';
NODE_NAME     J28 127
 '@S9S_MB_2U_LIB.S9S_MB_2U(SCH_1):PAGE109_I178@PURE_QUANTA.SCONN288_ADR50017P087CC(CHIPS)':
 'DQS2_B_C': CDS_PINID='DQS2_B_C';
NET_NAME
'M_F_CPU1_SB_DQS_DN<3>'
 '@S9S_MB_2U_LIB.S9S_MB_2U(SCH_1):M_F_CPU1_SB_DQS_DN'<3>:
 C_SIGNAL='@s9s_mb_2u_lib.s9s_mb_2u(sch_1):m_f_cpu1_sb_dqs_dn(3)';
NODE_NAME     U1 DT18
 '@S9S_MB_2U_LIB.S9S_MB_2U(SCH_1):PAGE56_I168@PURE_QUANTA.SOCKET4677_AZIF0045P001C01CS(CHIPS)':
 'DDR5_SB_DQS_DN3': CDS_PINID='DDR5_SB_DQS_DN3';
NODE_NAME     J27 138
 '@S9S_MB_2U_LIB.S9S_MB_2U(SCH_1):PAGE108_I180@PURE_QUANTA.SCONN288_ADR50017P130CC(CHIPS)':
 'DQS3_B_C': CDS_PINID='DQS3_B_C';
NODE_NAME     J28 138
 '@S9S_MB_2U_LIB.S9S_MB_2U(SCH_1):PAGE109_I178@PURE_QUANTA.SCONN288_ADR50017P087CC(CHIPS)':
 'DQS3_B_C': CDS_PINID='DQS3_B_C';
NET_NAME
'M_F_CPU1_SB_DQS_DN<4>'
 '@S9S_MB_2U_LIB.S9S_MB_2U(SCH_1):M_F_CPU1_SB_DQS_DN'<4>:
 C_SIGNAL='@s9s_mb_2u_lib.s9s_mb_2u(sch_1):m_f_cpu1_sb_dqs_dn(4)';
NODE_NAME     U1 EJ33
 '@S9S_MB_2U_LIB.S9S_MB_2U(SCH_1):PAGE56_I168@PURE_QUANTA.SOCKET4677_AZIF0045P001C01CS(CHIPS)':
 'DDR5_SB_DQS_DN4': CDS_PINID='DDR5_SB_DQS_DN4';
NODE_NAME     J27 238
 '@S9S_MB_2U_LIB.S9S_MB_2U(SCH_1):PAGE108_I180@PURE_QUANTA.SCONN288_ADR50017P130CC(CHIPS)':
 'DQS4_B_C': CDS_PINID='DQS4_B_C';
NODE_NAME     J28 238
 '@S9S_MB_2U_LIB.S9S_MB_2U(SCH_1):PAGE109_I178@PURE_QUANTA.SCONN288_ADR50017P087CC(CHIPS)':
 'DQS4_B_C': CDS_PINID='DQS4_B_C';
NET_NAME
'M_F_CPU1_SB_DQS_DN<5>'
 '@S9S_MB_2U_LIB.S9S_MB_2U(SCH_1):M_F_CPU1_SB_DQS_DN'<5>:
 C_SIGNAL='@s9s_mb_2u_lib.s9s_mb_2u(sch_1):m_f_cpu1_sb_dqs_dn(5)';
NODE_NAME     U1 EB30
 '@S9S_MB_2U_LIB.S9S_MB_2U(SCH_1):PAGE56_I168@PURE_QUANTA.SOCKET4677_AZIF0045P001C01CS(CHIPS)':
 'DDR5_SB_DQS_DN5': CDS_PINID='DDR5_SB_DQS_DN5';
NODE_NAME     J27 249
 '@S9S_MB_2U_LIB.S9S_MB_2U(SCH_1):PAGE108_I180@PURE_QUANTA.SCONN288_ADR50017P130CC(CHIPS)':
 'DQS5_B_C||TDQS5_B_C': CDS_PINID='\dqs5_b_c||tdqs5_b_c\';
NODE_NAME     J28 249
 '@S9S_MB_2U_LIB.S9S_MB_2U(SCH_1):PAGE109_I178@PURE_QUANTA.SCONN288_ADR50017P087CC(CHIPS)':
 'DQS5_B_C||TDQS5_B_C': CDS_PINID='\dqs5_b_c||tdqs5_b_c\';
NET_NAME
'M_F_CPU1_SB_DQS_DN<6>'
 '@S9S_MB_2U_LIB.S9S_MB_2U(SCH_1):M_F_CPU1_SB_DQS_DN'<6>:
 C_SIGNAL='@s9s_mb_2u_lib.s9s_mb_2u(sch_1):m_f_cpu1_sb_dqs_dn(6)';
NODE_NAME     U1 EJ21
 '@S9S_MB_2U_LIB.S9S_MB_2U(SCH_1):PAGE56_I168@PURE_QUANTA.SOCKET4677_AZIF0045P001C01CS(CHIPS)':
 'DDR5_SB_DQS_DN6': CDS_PINID='DDR5_SB_DQS_DN6';
NODE_NAME     J27 260
 '@S9S_MB_2U_LIB.S9S_MB_2U(SCH_1):PAGE108_I180@PURE_QUANTA.SCONN288_ADR50017P130CC(CHIPS)':
 'DQS6_B_C||TDQS6_B_C': CDS_PINID='\dqs6_b_c||tdqs6_b_c\';
NODE_NAME     J28 260
 '@S9S_MB_2U_LIB.S9S_MB_2U(SCH_1):PAGE109_I178@PURE_QUANTA.SCONN288_ADR50017P087CC(CHIPS)':
 'DQS6_B_C||TDQS6_B_C': CDS_PINID='\dqs6_b_c||tdqs6_b_c\';
NET_NAME
'M_F_CPU1_SB_DQS_DN<7>'
 '@S9S_MB_2U_LIB.S9S_MB_2U(SCH_1):M_F_CPU1_SB_DQS_DN'<7>:
 C_SIGNAL='@s9s_mb_2u_lib.s9s_mb_2u(sch_1):m_f_cpu1_sb_dqs_dn(7)';
NODE_NAME     U1 ET12
 '@S9S_MB_2U_LIB.S9S_MB_2U(SCH_1):PAGE56_I168@PURE_QUANTA.SOCKET4677_AZIF0045P001C01CS(CHIPS)':
 'DDR5_SB_DQS_DN7': CDS_PINID='DDR5_SB_DQS_DN7';
NODE_NAME     J27 271
 '@S9S_MB_2U_LIB.S9S_MB_2U(SCH_1):PAGE108_I180@PURE_QUANTA.SCONN288_ADR50017P130CC(CHIPS)':
 'DQS7_B_C||TDQS7_B_C': CDS_PINID='\dqs7_b_c||tdqs7_b_c\';
NODE_NAME     J28 271
 '@S9S_MB_2U_LIB.S9S_MB_2U(SCH_1):PAGE109_I178@PURE_QUANTA.SCONN288_ADR50017P087CC(CHIPS)':
 'DQS7_B_C||TDQS7_B_C': CDS_PINID='\dqs7_b_c||tdqs7_b_c\';
NET_NAME
'M_F_CPU1_SB_DQS_DN<8>'
 '@S9S_MB_2U_LIB.S9S_MB_2U(SCH_1):M_F_CPU1_SB_DQS_DN'<8>:
 C_SIGNAL='@s9s_mb_2u_lib.s9s_mb_2u(sch_1):m_f_cpu1_sb_dqs_dn(8)';
NODE_NAME     U1 DY18
 '@S9S_MB_2U_LIB.S9S_MB_2U(SCH_1):PAGE56_I168@PURE_QUANTA.SOCKET4677_AZIF0045P001C01CS(CHIPS)':
 'DDR5_SB_DQS_DN8': CDS_PINID='DDR5_SB_DQS_DN8';
NODE_NAME     J27 282
 '@S9S_MB_2U_LIB.S9S_MB_2U(SCH_1):PAGE108_I180@PURE_QUANTA.SCONN288_ADR50017P130CC(CHIPS)':
 'DQS8_B_C||TDQS8_B_C': CDS_PINID='\dqs8_b_c||tdqs8_b_c\';
NODE_NAME     J28 282
 '@S9S_MB_2U_LIB.S9S_MB_2U(SCH_1):PAGE109_I178@PURE_QUANTA.SCONN288_ADR50017P087CC(CHIPS)':
 'DQS8_B_C||TDQS8_B_C': CDS_PINID='\dqs8_b_c||tdqs8_b_c\';
NET_NAME
'M_F_CPU1_SB_DQS_DN<9>'
 '@S9S_MB_2U_LIB.S9S_MB_2U(SCH_1):M_F_CPU1_SB_DQS_DN'<9>:
 C_SIGNAL='@s9s_mb_2u_lib.s9s_mb_2u(sch_1):m_f_cpu1_sb_dqs_dn(9)';
NODE_NAME     U1 EE33
 '@S9S_MB_2U_LIB.S9S_MB_2U(SCH_1):PAGE56_I168@PURE_QUANTA.SOCKET4677_AZIF0045P001C01CS(CHIPS)':
 'DDR5_SB_DQS_DN9': CDS_PINID='DDR5_SB_DQS_DN9';
NODE_NAME     J27 94
 '@S9S_MB_2U_LIB.S9S_MB_2U(SCH_1):PAGE108_I180@PURE_QUANTA.SCONN288_ADR50017P130CC(CHIPS)':
 'DQS9_B_C||TDQS9_B_C': CDS_PINID='\dqs9_b_c||tdqs9_b_c\';
NODE_NAME     J28 94
 '@S9S_MB_2U_LIB.S9S_MB_2U(SCH_1):PAGE109_I178@PURE_QUANTA.SCONN288_ADR50017P087CC(CHIPS)':
 'DQS9_B_C||TDQS9_B_C': CDS_PINID='\dqs9_b_c||tdqs9_b_c\';
NET_NAME
'M_F_CPU1_SB_DQS_DP<0>'
 '@S9S_MB_2U_LIB.S9S_MB_2U(SCH_1):M_F_CPU1_SB_DQS_DP'<0>:
 C_SIGNAL='@s9s_mb_2u_lib.s9s_mb_2u(sch_1):m_f_cpu1_sb_dqs_dp(0)';
NODE_NAME     U1 DT30
 '@S9S_MB_2U_LIB.S9S_MB_2U(SCH_1):PAGE56_I168@PURE_QUANTA.SOCKET4677_AZIF0045P001C01CS(CHIPS)':
 'DDR5_SB_DQS_DP0': CDS_PINID='DDR5_SB_DQS_DP0';
NODE_NAME     J27 104
 '@S9S_MB_2U_LIB.S9S_MB_2U(SCH_1):PAGE108_I180@PURE_QUANTA.SCONN288_ADR50017P130CC(CHIPS)':
 'DQS0_B_T': CDS_PINID='DQS0_B_T';
NODE_NAME     J28 104
 '@S9S_MB_2U_LIB.S9S_MB_2U(SCH_1):PAGE109_I178@PURE_QUANTA.SCONN288_ADR50017P087CC(CHIPS)':
 'DQS0_B_T': CDS_PINID='DQS0_B_T';
NET_NAME
'M_F_CPU1_SB_DQS_DP<1>'
 '@S9S_MB_2U_LIB.S9S_MB_2U(SCH_1):M_F_CPU1_SB_DQS_DP'<1>:
 C_SIGNAL='@s9s_mb_2u_lib.s9s_mb_2u(sch_1):m_f_cpu1_sb_dqs_dp(1)';
NODE_NAME     U1 EC21
 '@S9S_MB_2U_LIB.S9S_MB_2U(SCH_1):PAGE56_I168@PURE_QUANTA.SOCKET4677_AZIF0045P001C01CS(CHIPS)':
 'DDR5_SB_DQS_DP1': CDS_PINID='DDR5_SB_DQS_DP1';
NODE_NAME     J27 115
 '@S9S_MB_2U_LIB.S9S_MB_2U(SCH_1):PAGE108_I180@PURE_QUANTA.SCONN288_ADR50017P130CC(CHIPS)':
 'DQS1_B_T': CDS_PINID='DQS1_B_T';
NODE_NAME     J28 115
 '@S9S_MB_2U_LIB.S9S_MB_2U(SCH_1):PAGE109_I178@PURE_QUANTA.SCONN288_ADR50017P087CC(CHIPS)':
 'DQS1_B_T': CDS_PINID='DQS1_B_T';
NET_NAME
'M_F_CPU1_SB_DQS_DP<2>'
 '@S9S_MB_2U_LIB.S9S_MB_2U(SCH_1):M_F_CPU1_SB_DQS_DP'<2>:
 C_SIGNAL='@s9s_mb_2u_lib.s9s_mb_2u(sch_1):m_f_cpu1_sb_dqs_dp(2)';
NODE_NAME     U1 EK12
 '@S9S_MB_2U_LIB.S9S_MB_2U(SCH_1):PAGE56_I168@PURE_QUANTA.SOCKET4677_AZIF0045P001C01CS(CHIPS)':
 'DDR5_SB_DQS_DP2': CDS_PINID='DDR5_SB_DQS_DP2';
NODE_NAME     J27 126
 '@S9S_MB_2U_LIB.S9S_MB_2U(SCH_1):PAGE108_I180@PURE_QUANTA.SCONN288_ADR50017P130CC(CHIPS)':
 'DQS2_B_T': CDS_PINID='DQS2_B_T';
NODE_NAME     J28 126
 '@S9S_MB_2U_LIB.S9S_MB_2U(SCH_1):PAGE109_I178@PURE_QUANTA.SCONN288_ADR50017P087CC(CHIPS)':
 'DQS2_B_T': CDS_PINID='DQS2_B_T';
NET_NAME
'M_F_CPU1_SB_DQS_DP<3>'
 '@S9S_MB_2U_LIB.S9S_MB_2U(SCH_1):M_F_CPU1_SB_DQS_DP'<3>:
 C_SIGNAL='@s9s_mb_2u_lib.s9s_mb_2u(sch_1):m_f_cpu1_sb_dqs_dp(3)';
NODE_NAME     U1 DV18
 '@S9S_MB_2U_LIB.S9S_MB_2U(SCH_1):PAGE56_I168@PURE_QUANTA.SOCKET4677_AZIF0045P001C01CS(CHIPS)':
 'DDR5_SB_DQS_DP3': CDS_PINID='DDR5_SB_DQS_DP3';
NODE_NAME     J27 137
 '@S9S_MB_2U_LIB.S9S_MB_2U(SCH_1):PAGE108_I180@PURE_QUANTA.SCONN288_ADR50017P130CC(CHIPS)':
 'DQS3_B_T': CDS_PINID='DQS3_B_T';
NODE_NAME     J28 137
 '@S9S_MB_2U_LIB.S9S_MB_2U(SCH_1):PAGE109_I178@PURE_QUANTA.SCONN288_ADR50017P087CC(CHIPS)':
 'DQS3_B_T': CDS_PINID='DQS3_B_T';
NET_NAME
'M_F_CPU1_SB_DQS_DP<4>'
 '@S9S_MB_2U_LIB.S9S_MB_2U(SCH_1):M_F_CPU1_SB_DQS_DP'<4>:
 C_SIGNAL='@s9s_mb_2u_lib.s9s_mb_2u(sch_1):m_f_cpu1_sb_dqs_dp(4)';
NODE_NAME     U1 EG33
 '@S9S_MB_2U_LIB.S9S_MB_2U(SCH_1):PAGE56_I168@PURE_QUANTA.SOCKET4677_AZIF0045P001C01CS(CHIPS)':
 'DDR5_SB_DQS_DP4': CDS_PINID='DDR5_SB_DQS_DP4';
NODE_NAME     J27 239
 '@S9S_MB_2U_LIB.S9S_MB_2U(SCH_1):PAGE108_I180@PURE_QUANTA.SCONN288_ADR50017P130CC(CHIPS)':
 'DQS4_B_T': CDS_PINID='DQS4_B_T';
NODE_NAME     J28 239
 '@S9S_MB_2U_LIB.S9S_MB_2U(SCH_1):PAGE109_I178@PURE_QUANTA.SCONN288_ADR50017P087CC(CHIPS)':
 'DQS4_B_T': CDS_PINID='DQS4_B_T';
NET_NAME
'M_F_CPU1_SB_DQS_DP<5>'
 '@S9S_MB_2U_LIB.S9S_MB_2U(SCH_1):M_F_CPU1_SB_DQS_DP'<5>:
 C_SIGNAL='@s9s_mb_2u_lib.s9s_mb_2u(sch_1):m_f_cpu1_sb_dqs_dp(5)';
NODE_NAME     U1 DY30
 '@S9S_MB_2U_LIB.S9S_MB_2U(SCH_1):PAGE56_I168@PURE_QUANTA.SOCKET4677_AZIF0045P001C01CS(CHIPS)':
 'DDR5_SB_DQS_DP5': CDS_PINID='DDR5_SB_DQS_DP5';
NODE_NAME     J27 250
 '@S9S_MB_2U_LIB.S9S_MB_2U(SCH_1):PAGE108_I180@PURE_QUANTA.SCONN288_ADR50017P130CC(CHIPS)':
 'DQS5_B_T||TDQS5_B_T': CDS_PINID='\dqs5_b_t||tdqs5_b_t\';
NODE_NAME     J28 250
 '@S9S_MB_2U_LIB.S9S_MB_2U(SCH_1):PAGE109_I178@PURE_QUANTA.SCONN288_ADR50017P087CC(CHIPS)':
 'DQS5_B_T||TDQS5_B_T': CDS_PINID='\dqs5_b_t||tdqs5_b_t\';
NET_NAME
'M_F_CPU1_SB_DQS_DP<6>'
 '@S9S_MB_2U_LIB.S9S_MB_2U(SCH_1):M_F_CPU1_SB_DQS_DP'<6>:
 C_SIGNAL='@s9s_mb_2u_lib.s9s_mb_2u(sch_1):m_f_cpu1_sb_dqs_dp(6)';
NODE_NAME     U1 EG21
 '@S9S_MB_2U_LIB.S9S_MB_2U(SCH_1):PAGE56_I168@PURE_QUANTA.SOCKET4677_AZIF0045P001C01CS(CHIPS)':
 'DDR5_SB_DQS_DP6': CDS_PINID='DDR5_SB_DQS_DP6';
NODE_NAME     J27 261
 '@S9S_MB_2U_LIB.S9S_MB_2U(SCH_1):PAGE108_I180@PURE_QUANTA.SCONN288_ADR50017P130CC(CHIPS)':
 'DQS6_B_T||TDQS6_B_T': CDS_PINID='\dqs6_b_t||tdqs6_b_t\';
NODE_NAME     J28 261
 '@S9S_MB_2U_LIB.S9S_MB_2U(SCH_1):PAGE109_I178@PURE_QUANTA.SCONN288_ADR50017P087CC(CHIPS)':
 'DQS6_B_T||TDQS6_B_T': CDS_PINID='\dqs6_b_t||tdqs6_b_t\';
NET_NAME
'M_F_CPU1_SB_DQS_DP<7>'
 '@S9S_MB_2U_LIB.S9S_MB_2U(SCH_1):M_F_CPU1_SB_DQS_DP'<7>:
 C_SIGNAL='@s9s_mb_2u_lib.s9s_mb_2u(sch_1):m_f_cpu1_sb_dqs_dp(7)';
NODE_NAME     U1 EP12
 '@S9S_MB_2U_LIB.S9S_MB_2U(SCH_1):PAGE56_I168@PURE_QUANTA.SOCKET4677_AZIF0045P001C01CS(CHIPS)':
 'DDR5_SB_DQS_DP7': CDS_PINID='DDR5_SB_DQS_DP7';
NODE_NAME     J27 272
 '@S9S_MB_2U_LIB.S9S_MB_2U(SCH_1):PAGE108_I180@PURE_QUANTA.SCONN288_ADR50017P130CC(CHIPS)':
 'DQS7_B_T||TDQS7_B_T': CDS_PINID='\dqs7_b_t||tdqs7_b_t\';
NODE_NAME     J28 272
 '@S9S_MB_2U_LIB.S9S_MB_2U(SCH_1):PAGE109_I178@PURE_QUANTA.SCONN288_ADR50017P087CC(CHIPS)':
 'DQS7_B_T||TDQS7_B_T': CDS_PINID='\dqs7_b_t||tdqs7_b_t\';
NET_NAME
'M_F_CPU1_SB_DQS_DP<8>'
 '@S9S_MB_2U_LIB.S9S_MB_2U(SCH_1):M_F_CPU1_SB_DQS_DP'<8>:
 C_SIGNAL='@s9s_mb_2u_lib.s9s_mb_2u(sch_1):m_f_cpu1_sb_dqs_dp(8)';
NODE_NAME     U1 EB18
 '@S9S_MB_2U_LIB.S9S_MB_2U(SCH_1):PAGE56_I168@PURE_QUANTA.SOCKET4677_AZIF0045P001C01CS(CHIPS)':
 'DDR5_SB_DQS_DP8': CDS_PINID='DDR5_SB_DQS_DP8';
NODE_NAME     J27 283
 '@S9S_MB_2U_LIB.S9S_MB_2U(SCH_1):PAGE108_I180@PURE_QUANTA.SCONN288_ADR50017P130CC(CHIPS)':
 'DQS8_B_T||TDQS8_B_T': CDS_PINID='\dqs8_b_t||tdqs8_b_t\';
NODE_NAME     J28 283
 '@S9S_MB_2U_LIB.S9S_MB_2U(SCH_1):PAGE109_I178@PURE_QUANTA.SCONN288_ADR50017P087CC(CHIPS)':
 'DQS8_B_T||TDQS8_B_T': CDS_PINID='\dqs8_b_t||tdqs8_b_t\';
NET_NAME
'M_F_CPU1_SB_DQS_DP<9>'
 '@S9S_MB_2U_LIB.S9S_MB_2U(SCH_1):M_F_CPU1_SB_DQS_DP'<9>:
 C_SIGNAL='@s9s_mb_2u_lib.s9s_mb_2u(sch_1):m_f_cpu1_sb_dqs_dp(9)';
NODE_NAME     U1 EC33
 '@S9S_MB_2U_LIB.S9S_MB_2U(SCH_1):PAGE56_I168@PURE_QUANTA.SOCKET4677_AZIF0045P001C01CS(CHIPS)':
 'DDR5_SB_DQS_DP9': CDS_PINID='DDR5_SB_DQS_DP9';
NODE_NAME     J27 93
 '@S9S_MB_2U_LIB.S9S_MB_2U(SCH_1):PAGE108_I180@PURE_QUANTA.SCONN288_ADR50017P130CC(CHIPS)':
 'DQS9_B_T||TDQS9_B_T||DBI4_B_N': CDS_PINID='\dqs9_b_t||tdqs9_b_t||dbi4_b_n\';
NODE_NAME     J28 93
 '@S9S_MB_2U_LIB.S9S_MB_2U(SCH_1):PAGE109_I178@PURE_QUANTA.SCONN288_ADR50017P087CC(CHIPS)':
 'DQS9_B_T||TDQS9_B_T||DBI4_B_N': CDS_PINID='\dqs9_b_t||tdqs9_b_t||dbi4_b_n\';
NET_NAME
'M_F_CPU1_SB_PAR'
 '@S9S_MB_2U_LIB.S9S_MB_2U(SCH_1):M_F_CPU1_SB_PAR':
 C_SIGNAL='@s9s_mb_2u_lib.s9s_mb_2u(sch_1):m_f_cpu1_sb_par';
NODE_NAME     U1 EJ39
 '@S9S_MB_2U_LIB.S9S_MB_2U(SCH_1):PAGE56_I168@PURE_QUANTA.SOCKET4677_AZIF0045P001C01CS(CHIPS)':
 'DDR5_SB_PAR': CDS_PINID='DDR5_SB_PAR';
NODE_NAME     J27 227
 '@S9S_MB_2U_LIB.S9S_MB_2U(SCH_1):PAGE108_I179@PURE_QUANTA.SCONN288_ADR50017P130CC(CHIPS)':
 'PAR_B': CDS_PINID='PAR_B';
NODE_NAME     J28 227
 '@S9S_MB_2U_LIB.S9S_MB_2U(SCH_1):PAGE109_I47@PURE_QUANTA.SCONN288_ADR50017P087CC(CHIPS)':
 'PAR_B': CDS_PINID='PAR_B';
NET_NAME
'M_F_CPU1_SB_RSP<0>'
 '@S9S_MB_2U_LIB.S9S_MB_2U(SCH_1):M_F_CPU1_SB_RSP'<0>:
 C_SIGNAL='@s9s_mb_2u_lib.s9s_mb_2u(sch_1):m_f_cpu1_sb_rsp(0)';
NODE_NAME     U1 DL48
 '@S9S_MB_2U_LIB.S9S_MB_2U(SCH_1):PAGE56_I168@PURE_QUANTA.SOCKET4677_AZIF0045P001C01CS(CHIPS)':
 'DDR5_B_RSP0': CDS_PINID='DDR5_B_RSP0';
NODE_NAME     J27 87
 '@S9S_MB_2U_LIB.S9S_MB_2U(SCH_1):PAGE108_I179@PURE_QUANTA.SCONN288_ADR50017P130CC(CHIPS)':
 'LBS||RSP_B_N': CDS_PINID='\lbs||rsp_b_n\';
NET_NAME
'M_F_CPU1_SB_RSP<1>'
 '@S9S_MB_2U_LIB.S9S_MB_2U(SCH_1):M_F_CPU1_SB_RSP'<1>:
 C_SIGNAL='@s9s_mb_2u_lib.s9s_mb_2u(sch_1):m_f_cpu1_sb_rsp(1)';
NODE_NAME     U1 DK47
 '@S9S_MB_2U_LIB.S9S_MB_2U(SCH_1):PAGE56_I168@PURE_QUANTA.SOCKET4677_AZIF0045P001C01CS(CHIPS)':
 'DDR5_B_RSP1': CDS_PINID='DDR5_B_RSP1';
NODE_NAME     J28 87
 '@S9S_MB_2U_LIB.S9S_MB_2U(SCH_1):PAGE109_I47@PURE_QUANTA.SCONN288_ADR50017P087CC(CHIPS)':
 'LBS||RSP_B_N': CDS_PINID='\lbs||rsp_b_n\';
NET_NAME
'M_G_CPU0_ALERT_N'
 '@S9S_MB_2U_LIB.S9S_MB_2U(SCH_1):M_G_CPU0_ALERT_N':
 C_SIGNAL='@s9s_mb_2u_lib.s9s_mb_2u(sch_1):m_g_cpu0_alert_n';
NODE_NAME     U2 CW50
 '@S9S_MB_2U_LIB.S9S_MB_2U(SCH_1):PAGE26_I169@PURE_QUANTA.SOCKET4677_AZIF0045P001C01CS(CHIPS)':
 'DDR6_ALERT_N': CDS_PINID='DDR6_ALERT_N';
NODE_NAME     J13 62
 '@S9S_MB_2U_LIB.S9S_MB_2U(SCH_1):PAGE94_I11@PURE_QUANTA.SCONN288_ADR50017P130CC(CHIPS)':
 'ALERT_N': CDS_PINID='ALERT_N';
NODE_NAME     J14 62
 '@S9S_MB_2U_LIB.S9S_MB_2U(SCH_1):PAGE95_I47@PURE_QUANTA.SCONN288_ADR50017P087CC(CHIPS)':
 'ALERT_N': CDS_PINID='ALERT_N';
NET_NAME
'M_G_CPU0_CLK_DN<0>'
 '@S9S_MB_2U_LIB.S9S_MB_2U(SCH_1):M_G_CPU0_CLK_DN'<0>:
 C_SIGNAL='@s9s_mb_2u_lib.s9s_mb_2u(sch_1):m_g_cpu0_clk_dn(0)';
NODE_NAME     U2 DR45
 '@S9S_MB_2U_LIB.S9S_MB_2U(SCH_1):PAGE26_I169@PURE_QUANTA.SOCKET4677_AZIF0045P001C01CS(CHIPS)':
 'DDR6_CLK_DN0': CDS_PINID='DDR6_CLK_DN0';
NODE_NAME     J13 218
 '@S9S_MB_2U_LIB.S9S_MB_2U(SCH_1):PAGE94_I11@PURE_QUANTA.SCONN288_ADR50017P130CC(CHIPS)':
 'CK_C': CDS_PINID='CK_C';
NET_NAME
'M_G_CPU0_CLK_DN<1>'
 '@S9S_MB_2U_LIB.S9S_MB_2U(SCH_1):M_G_CPU0_CLK_DN'<1>:
 C_SIGNAL='@s9s_mb_2u_lib.s9s_mb_2u(sch_1):m_g_cpu0_clk_dn(1)';
NODE_NAME     U2 DL45
 '@S9S_MB_2U_LIB.S9S_MB_2U(SCH_1):PAGE26_I169@PURE_QUANTA.SOCKET4677_AZIF0045P001C01CS(CHIPS)':
 'DDR6_CLK_DN1': CDS_PINID='DDR6_CLK_DN1';
NODE_NAME     J14 218
 '@S9S_MB_2U_LIB.S9S_MB_2U(SCH_1):PAGE95_I47@PURE_QUANTA.SCONN288_ADR50017P087CC(CHIPS)':
 'CK_C': CDS_PINID='CK_C';
NET_NAME
'M_G_CPU0_CLK_DP<0>'
 '@S9S_MB_2U_LIB.S9S_MB_2U(SCH_1):M_G_CPU0_CLK_DP'<0>:
 C_SIGNAL='@s9s_mb_2u_lib.s9s_mb_2u(sch_1):m_g_cpu0_clk_dp(0)';
NODE_NAME     U2 DN45
 '@S9S_MB_2U_LIB.S9S_MB_2U(SCH_1):PAGE26_I169@PURE_QUANTA.SOCKET4677_AZIF0045P001C01CS(CHIPS)':
 'DDR6_CLK_DP0': CDS_PINID='DDR6_CLK_DP0';
NODE_NAME     J13 217
 '@S9S_MB_2U_LIB.S9S_MB_2U(SCH_1):PAGE94_I11@PURE_QUANTA.SCONN288_ADR50017P130CC(CHIPS)':
 'CK_T': CDS_PINID='CK_T';
NET_NAME
'M_G_CPU0_CLK_DP<1>'
 '@S9S_MB_2U_LIB.S9S_MB_2U(SCH_1):M_G_CPU0_CLK_DP'<1>:
 C_SIGNAL='@s9s_mb_2u_lib.s9s_mb_2u(sch_1):m_g_cpu0_clk_dp(1)';
NODE_NAME     U2 DJ45
 '@S9S_MB_2U_LIB.S9S_MB_2U(SCH_1):PAGE26_I169@PURE_QUANTA.SOCKET4677_AZIF0045P001C01CS(CHIPS)':
 'DDR6_CLK_DP1': CDS_PINID='DDR6_CLK_DP1';
NODE_NAME     J14 217
 '@S9S_MB_2U_LIB.S9S_MB_2U(SCH_1):PAGE95_I47@PURE_QUANTA.SCONN288_ADR50017P087CC(CHIPS)':
 'CK_T': CDS_PINID='CK_T';
NET_NAME
'M_G_CPU0_SA_CA<0>'
 '@S9S_MB_2U_LIB.S9S_MB_2U(SCH_1):M_G_CPU0_SA_CA'<0>:
 C_SIGNAL='@s9s_mb_2u_lib.s9s_mb_2u(sch_1):m_g_cpu0_sa_ca(0)';
NODE_NAME     U2 DJ52
 '@S9S_MB_2U_LIB.S9S_MB_2U(SCH_1):PAGE26_I169@PURE_QUANTA.SOCKET4677_AZIF0045P001C01CS(CHIPS)':
 'DDR6_SA_CA0': CDS_PINID='DDR6_SA_CA0';
NODE_NAME     J13 66
 '@S9S_MB_2U_LIB.S9S_MB_2U(SCH_1):PAGE94_I11@PURE_QUANTA.SCONN288_ADR50017P130CC(CHIPS)':
 'CA0_A': CDS_PINID='CA0_A';
NODE_NAME     J14 66
 '@S9S_MB_2U_LIB.S9S_MB_2U(SCH_1):PAGE95_I47@PURE_QUANTA.SCONN288_ADR50017P087CC(CHIPS)':
 'CA0_A': CDS_PINID='CA0_A';
NET_NAME
'M_G_CPU0_SA_CA<1>'
 '@S9S_MB_2U_LIB.S9S_MB_2U(SCH_1):M_G_CPU0_SA_CA'<1>:
 C_SIGNAL='@s9s_mb_2u_lib.s9s_mb_2u(sch_1):m_g_cpu0_sa_ca(1)';
NODE_NAME     U2 DR52
 '@S9S_MB_2U_LIB.S9S_MB_2U(SCH_1):PAGE26_I169@PURE_QUANTA.SOCKET4677_AZIF0045P001C01CS(CHIPS)':
 'DDR6_SA_CA1': CDS_PINID='DDR6_SA_CA1';
NODE_NAME     J13 211
 '@S9S_MB_2U_LIB.S9S_MB_2U(SCH_1):PAGE94_I11@PURE_QUANTA.SCONN288_ADR50017P130CC(CHIPS)':
 'CA1_A': CDS_PINID='CA1_A';
NODE_NAME     J14 211
 '@S9S_MB_2U_LIB.S9S_MB_2U(SCH_1):PAGE95_I47@PURE_QUANTA.SCONN288_ADR50017P087CC(CHIPS)':
 'CA1_A': CDS_PINID='CA1_A';
NET_NAME
'M_G_CPU0_SA_CA<2>'
 '@S9S_MB_2U_LIB.S9S_MB_2U(SCH_1):M_G_CPU0_SA_CA'<2>:
 C_SIGNAL='@s9s_mb_2u_lib.s9s_mb_2u(sch_1):m_g_cpu0_sa_ca(2)';
NODE_NAME     U2 DK51
 '@S9S_MB_2U_LIB.S9S_MB_2U(SCH_1):PAGE26_I169@PURE_QUANTA.SOCKET4677_AZIF0045P001C01CS(CHIPS)':
 'DDR6_SA_CA2': CDS_PINID='DDR6_SA_CA2';
NODE_NAME     J13 68
 '@S9S_MB_2U_LIB.S9S_MB_2U(SCH_1):PAGE94_I11@PURE_QUANTA.SCONN288_ADR50017P130CC(CHIPS)':
 'CA2_A': CDS_PINID='CA2_A';
NODE_NAME     J14 68
 '@S9S_MB_2U_LIB.S9S_MB_2U(SCH_1):PAGE95_I47@PURE_QUANTA.SCONN288_ADR50017P087CC(CHIPS)':
 'CA2_A': CDS_PINID='CA2_A';
NET_NAME
'M_G_CPU0_SA_CA<3>'
 '@S9S_MB_2U_LIB.S9S_MB_2U(SCH_1):M_G_CPU0_SA_CA'<3>:
 C_SIGNAL='@s9s_mb_2u_lib.s9s_mb_2u(sch_1):m_g_cpu0_sa_ca(3)';
NODE_NAME     U2 DP51
 '@S9S_MB_2U_LIB.S9S_MB_2U(SCH_1):PAGE26_I169@PURE_QUANTA.SOCKET4677_AZIF0045P001C01CS(CHIPS)':
 'DDR6_SA_CA3': CDS_PINID='DDR6_SA_CA3';
NODE_NAME     J13 213
 '@S9S_MB_2U_LIB.S9S_MB_2U(SCH_1):PAGE94_I11@PURE_QUANTA.SCONN288_ADR50017P130CC(CHIPS)':
 'CA3_A': CDS_PINID='CA3_A';
NODE_NAME     J14 213
 '@S9S_MB_2U_LIB.S9S_MB_2U(SCH_1):PAGE95_I47@PURE_QUANTA.SCONN288_ADR50017P087CC(CHIPS)':
 'CA3_A': CDS_PINID='CA3_A';
NET_NAME
'M_G_CPU0_SA_CA<4>'
 '@S9S_MB_2U_LIB.S9S_MB_2U(SCH_1):M_G_CPU0_SA_CA'<4>:
 C_SIGNAL='@s9s_mb_2u_lib.s9s_mb_2u(sch_1):m_g_cpu0_sa_ca(4)';
NODE_NAME     U2 DL50
 '@S9S_MB_2U_LIB.S9S_MB_2U(SCH_1):PAGE26_I169@PURE_QUANTA.SOCKET4677_AZIF0045P001C01CS(CHIPS)':
 'DDR6_SA_CA4': CDS_PINID='DDR6_SA_CA4';
NODE_NAME     J13 70
 '@S9S_MB_2U_LIB.S9S_MB_2U(SCH_1):PAGE94_I11@PURE_QUANTA.SCONN288_ADR50017P130CC(CHIPS)':
 'CA4_A': CDS_PINID='CA4_A';
NODE_NAME     J14 70
 '@S9S_MB_2U_LIB.S9S_MB_2U(SCH_1):PAGE95_I47@PURE_QUANTA.SCONN288_ADR50017P087CC(CHIPS)':
 'CA4_A': CDS_PINID='CA4_A';
NET_NAME
'M_G_CPU0_SA_CA<5>'
 '@S9S_MB_2U_LIB.S9S_MB_2U(SCH_1):M_G_CPU0_SA_CA'<5>:
 C_SIGNAL='@s9s_mb_2u_lib.s9s_mb_2u(sch_1):m_g_cpu0_sa_ca(5)';
NODE_NAME     U2 DN50
 '@S9S_MB_2U_LIB.S9S_MB_2U(SCH_1):PAGE26_I169@PURE_QUANTA.SOCKET4677_AZIF0045P001C01CS(CHIPS)':
 'DDR6_SA_CA5': CDS_PINID='DDR6_SA_CA5';
NODE_NAME     J13 215
 '@S9S_MB_2U_LIB.S9S_MB_2U(SCH_1):PAGE94_I11@PURE_QUANTA.SCONN288_ADR50017P130CC(CHIPS)':
 'CA5_A': CDS_PINID='CA5_A';
NODE_NAME     J14 215
 '@S9S_MB_2U_LIB.S9S_MB_2U(SCH_1):PAGE95_I47@PURE_QUANTA.SCONN288_ADR50017P087CC(CHIPS)':
 'CA5_A': CDS_PINID='CA5_A';
NET_NAME
'M_G_CPU0_SA_CA<6>'
 '@S9S_MB_2U_LIB.S9S_MB_2U(SCH_1):M_G_CPU0_SA_CA'<6>:
 C_SIGNAL='@s9s_mb_2u_lib.s9s_mb_2u(sch_1):m_g_cpu0_sa_ca(6)';
NODE_NAME     U2 DK44
 '@S9S_MB_2U_LIB.S9S_MB_2U(SCH_1):PAGE26_I169@PURE_QUANTA.SOCKET4677_AZIF0045P001C01CS(CHIPS)':
 'DDR6_SA_CA6': CDS_PINID='DDR6_SA_CA6';
NODE_NAME     J13 72
 '@S9S_MB_2U_LIB.S9S_MB_2U(SCH_1):PAGE94_I11@PURE_QUANTA.SCONN288_ADR50017P130CC(CHIPS)':
 'CA6_A': CDS_PINID='CA6_A';
NODE_NAME     J14 72
 '@S9S_MB_2U_LIB.S9S_MB_2U(SCH_1):PAGE95_I47@PURE_QUANTA.SCONN288_ADR50017P087CC(CHIPS)':
 'CA6_A': CDS_PINID='CA6_A';
NET_NAME
'M_G_CPU0_SA_CB<0>'
 '@S9S_MB_2U_LIB.S9S_MB_2U(SCH_1):M_G_CPU0_SA_CB'<0>:
 C_SIGNAL='@s9s_mb_2u_lib.s9s_mb_2u(sch_1):m_g_cpu0_sa_cb(0)';
NODE_NAME     U2 DL60
 '@S9S_MB_2U_LIB.S9S_MB_2U(SCH_1):PAGE26_I169@PURE_QUANTA.SOCKET4677_AZIF0045P001C01CS(CHIPS)':
 'DDR6_SA_ECC0': CDS_PINID='DDR6_SA_ECC0';
NODE_NAME     J13 51
 '@S9S_MB_2U_LIB.S9S_MB_2U(SCH_1):PAGE94_I11@PURE_QUANTA.SCONN288_ADR50017P130CC(CHIPS)':
 'CB0_A': CDS_PINID='CB0_A';
NODE_NAME     J14 51
 '@S9S_MB_2U_LIB.S9S_MB_2U(SCH_1):PAGE95_I47@PURE_QUANTA.SCONN288_ADR50017P087CC(CHIPS)':
 'CB0_A': CDS_PINID='CB0_A';
NET_NAME
'M_G_CPU0_SA_CB<1>'
 '@S9S_MB_2U_LIB.S9S_MB_2U(SCH_1):M_G_CPU0_SA_CB'<1>:
 C_SIGNAL='@s9s_mb_2u_lib.s9s_mb_2u(sch_1):m_g_cpu0_sa_cb(1)';
NODE_NAME     U2 DK59
 '@S9S_MB_2U_LIB.S9S_MB_2U(SCH_1):PAGE26_I169@PURE_QUANTA.SOCKET4677_AZIF0045P001C01CS(CHIPS)':
 'DDR6_SA_ECC1': CDS_PINID='DDR6_SA_ECC1';
NODE_NAME     J13 53
 '@S9S_MB_2U_LIB.S9S_MB_2U(SCH_1):PAGE94_I11@PURE_QUANTA.SCONN288_ADR50017P130CC(CHIPS)':
 'CB1_A': CDS_PINID='CB1_A';
NODE_NAME     J14 53
 '@S9S_MB_2U_LIB.S9S_MB_2U(SCH_1):PAGE95_I47@PURE_QUANTA.SCONN288_ADR50017P087CC(CHIPS)':
 'CB1_A': CDS_PINID='CB1_A';
NET_NAME
'M_G_CPU0_SA_CB<2>'
 '@S9S_MB_2U_LIB.S9S_MB_2U(SCH_1):M_G_CPU0_SA_CB'<2>:
 C_SIGNAL='@s9s_mb_2u_lib.s9s_mb_2u(sch_1):m_g_cpu0_sa_cb(2)';
NODE_NAME     U2 DN60
 '@S9S_MB_2U_LIB.S9S_MB_2U(SCH_1):PAGE26_I169@PURE_QUANTA.SOCKET4677_AZIF0045P001C01CS(CHIPS)':
 'DDR6_SA_ECC2': CDS_PINID='DDR6_SA_ECC2';
NODE_NAME     J13 196
 '@S9S_MB_2U_LIB.S9S_MB_2U(SCH_1):PAGE94_I11@PURE_QUANTA.SCONN288_ADR50017P130CC(CHIPS)':
 'CB2_A': CDS_PINID='CB2_A';
NODE_NAME     J14 196
 '@S9S_MB_2U_LIB.S9S_MB_2U(SCH_1):PAGE95_I47@PURE_QUANTA.SCONN288_ADR50017P087CC(CHIPS)':
 'CB2_A': CDS_PINID='CB2_A';
NET_NAME
'M_G_CPU0_SA_CB<3>'
 '@S9S_MB_2U_LIB.S9S_MB_2U(SCH_1):M_G_CPU0_SA_CB'<3>:
 C_SIGNAL='@s9s_mb_2u_lib.s9s_mb_2u(sch_1):m_g_cpu0_sa_cb(3)';
NODE_NAME     U2 DP59
 '@S9S_MB_2U_LIB.S9S_MB_2U(SCH_1):PAGE26_I169@PURE_QUANTA.SOCKET4677_AZIF0045P001C01CS(CHIPS)':
 'DDR6_SA_ECC3': CDS_PINID='DDR6_SA_ECC3';
NODE_NAME     J13 198
 '@S9S_MB_2U_LIB.S9S_MB_2U(SCH_1):PAGE94_I11@PURE_QUANTA.SCONN288_ADR50017P130CC(CHIPS)':
 'CB3_A': CDS_PINID='CB3_A';
NODE_NAME     J14 198
 '@S9S_MB_2U_LIB.S9S_MB_2U(SCH_1):PAGE95_I47@PURE_QUANTA.SCONN288_ADR50017P087CC(CHIPS)':
 'CB3_A': CDS_PINID='CB3_A';
NET_NAME
'M_G_CPU0_SA_CB<4>'
 '@S9S_MB_2U_LIB.S9S_MB_2U(SCH_1):M_G_CPU0_SA_CB'<4>:
 C_SIGNAL='@s9s_mb_2u_lib.s9s_mb_2u(sch_1):m_g_cpu0_sa_cb(4)';
NODE_NAME     U2 DK57
 '@S9S_MB_2U_LIB.S9S_MB_2U(SCH_1):PAGE26_I169@PURE_QUANTA.SOCKET4677_AZIF0045P001C01CS(CHIPS)':
 'DDR6_SA_ECC4': CDS_PINID='DDR6_SA_ECC4';
NODE_NAME     J13 58
 '@S9S_MB_2U_LIB.S9S_MB_2U(SCH_1):PAGE94_I11@PURE_QUANTA.SCONN288_ADR50017P130CC(CHIPS)':
 'CB4_A': CDS_PINID='CB4_A';
NODE_NAME     J14 58
 '@S9S_MB_2U_LIB.S9S_MB_2U(SCH_1):PAGE95_I47@PURE_QUANTA.SCONN288_ADR50017P087CC(CHIPS)':
 'CB4_A': CDS_PINID='CB4_A';
NET_NAME
'M_G_CPU0_SA_CB<5>'
 '@S9S_MB_2U_LIB.S9S_MB_2U(SCH_1):M_G_CPU0_SA_CB'<5>:
 C_SIGNAL='@s9s_mb_2u_lib.s9s_mb_2u(sch_1):m_g_cpu0_sa_cb(5)';
NODE_NAME     U2 DL56
 '@S9S_MB_2U_LIB.S9S_MB_2U(SCH_1):PAGE26_I169@PURE_QUANTA.SOCKET4677_AZIF0045P001C01CS(CHIPS)':
 'DDR6_SA_ECC5': CDS_PINID='DDR6_SA_ECC5';
NODE_NAME     J13 60
 '@S9S_MB_2U_LIB.S9S_MB_2U(SCH_1):PAGE94_I11@PURE_QUANTA.SCONN288_ADR50017P130CC(CHIPS)':
 'CB5_A': CDS_PINID='CB5_A';
NODE_NAME     J14 60
 '@S9S_MB_2U_LIB.S9S_MB_2U(SCH_1):PAGE95_I47@PURE_QUANTA.SCONN288_ADR50017P087CC(CHIPS)':
 'CB5_A': CDS_PINID='CB5_A';
NET_NAME
'M_G_CPU0_SA_CB<6>'
 '@S9S_MB_2U_LIB.S9S_MB_2U(SCH_1):M_G_CPU0_SA_CB'<6>:
 C_SIGNAL='@s9s_mb_2u_lib.s9s_mb_2u(sch_1):m_g_cpu0_sa_cb(6)';
NODE_NAME     U2 DP57
 '@S9S_MB_2U_LIB.S9S_MB_2U(SCH_1):PAGE26_I169@PURE_QUANTA.SOCKET4677_AZIF0045P001C01CS(CHIPS)':
 'DDR6_SA_ECC6': CDS_PINID='DDR6_SA_ECC6';
NODE_NAME     J13 203
 '@S9S_MB_2U_LIB.S9S_MB_2U(SCH_1):PAGE94_I11@PURE_QUANTA.SCONN288_ADR50017P130CC(CHIPS)':
 'CB6_A': CDS_PINID='CB6_A';
NODE_NAME     J14 203
 '@S9S_MB_2U_LIB.S9S_MB_2U(SCH_1):PAGE95_I47@PURE_QUANTA.SCONN288_ADR50017P087CC(CHIPS)':
 'CB6_A': CDS_PINID='CB6_A';
NET_NAME
'M_G_CPU0_SA_CB<7>'
 '@S9S_MB_2U_LIB.S9S_MB_2U(SCH_1):M_G_CPU0_SA_CB'<7>:
 C_SIGNAL='@s9s_mb_2u_lib.s9s_mb_2u(sch_1):m_g_cpu0_sa_cb(7)';
NODE_NAME     U2 DN56
 '@S9S_MB_2U_LIB.S9S_MB_2U(SCH_1):PAGE26_I169@PURE_QUANTA.SOCKET4677_AZIF0045P001C01CS(CHIPS)':
 'DDR6_SA_ECC7': CDS_PINID='DDR6_SA_ECC7';
NODE_NAME     J13 205
 '@S9S_MB_2U_LIB.S9S_MB_2U(SCH_1):PAGE94_I11@PURE_QUANTA.SCONN288_ADR50017P130CC(CHIPS)':
 'CB7_A': CDS_PINID='CB7_A';
NODE_NAME     J14 205
 '@S9S_MB_2U_LIB.S9S_MB_2U(SCH_1):PAGE95_I47@PURE_QUANTA.SCONN288_ADR50017P087CC(CHIPS)':
 'CB7_A': CDS_PINID='CB7_A';
NET_NAME
'M_G_CPU0_SA_CS_N<0>'
 '@S9S_MB_2U_LIB.S9S_MB_2U(SCH_1):M_G_CPU0_SA_CS_N'<0>:
 C_SIGNAL='@s9s_mb_2u_lib.s9s_mb_2u(sch_1):m_g_cpu0_sa_cs_n(0)';
NODE_NAME     U2 DN54
 '@S9S_MB_2U_LIB.S9S_MB_2U(SCH_1):PAGE26_I169@PURE_QUANTA.SOCKET4677_AZIF0045P001C01CS(CHIPS)':
 'DDR6_SA_CS_N0': CDS_PINID='DDR6_SA_CS_N0';
NODE_NAME     J13 64
 '@S9S_MB_2U_LIB.S9S_MB_2U(SCH_1):PAGE94_I11@PURE_QUANTA.SCONN288_ADR50017P130CC(CHIPS)':
 'CS0_A_N': CDS_PINID='CS0_A_N';
NET_NAME
'M_G_CPU0_SA_CS_N<1>'
 '@S9S_MB_2U_LIB.S9S_MB_2U(SCH_1):M_G_CPU0_SA_CS_N'<1>:
 C_SIGNAL='@s9s_mb_2u_lib.s9s_mb_2u(sch_1):m_g_cpu0_sa_cs_n(1)';
NODE_NAME     U2 DP53
 '@S9S_MB_2U_LIB.S9S_MB_2U(SCH_1):PAGE26_I169@PURE_QUANTA.SOCKET4677_AZIF0045P001C01CS(CHIPS)':
 'DDR6_SA_CS_N1': CDS_PINID='DDR6_SA_CS_N1';
NODE_NAME     J13 209
 '@S9S_MB_2U_LIB.S9S_MB_2U(SCH_1):PAGE94_I11@PURE_QUANTA.SCONN288_ADR50017P130CC(CHIPS)':
 'CS1_A_N': CDS_PINID='CS1_A_N';
NET_NAME
'M_G_CPU0_SA_CS_N<2>'
 '@S9S_MB_2U_LIB.S9S_MB_2U(SCH_1):M_G_CPU0_SA_CS_N'<2>:
 C_SIGNAL='@s9s_mb_2u_lib.s9s_mb_2u(sch_1):m_g_cpu0_sa_cs_n(2)';
NODE_NAME     U2 DL54
 '@S9S_MB_2U_LIB.S9S_MB_2U(SCH_1):PAGE26_I169@PURE_QUANTA.SOCKET4677_AZIF0045P001C01CS(CHIPS)':
 'DDR6_SA_CS_N2': CDS_PINID='DDR6_SA_CS_N2';
NODE_NAME     J14 64
 '@S9S_MB_2U_LIB.S9S_MB_2U(SCH_1):PAGE95_I47@PURE_QUANTA.SCONN288_ADR50017P087CC(CHIPS)':
 'CS0_A_N': CDS_PINID='CS0_A_N';
NET_NAME
'M_G_CPU0_SA_CS_N<3>'
 '@S9S_MB_2U_LIB.S9S_MB_2U(SCH_1):M_G_CPU0_SA_CS_N'<3>:
 C_SIGNAL='@s9s_mb_2u_lib.s9s_mb_2u(sch_1):m_g_cpu0_sa_cs_n(3)';
NODE_NAME     U2 DK53
 '@S9S_MB_2U_LIB.S9S_MB_2U(SCH_1):PAGE26_I169@PURE_QUANTA.SOCKET4677_AZIF0045P001C01CS(CHIPS)':
 'DDR6_SA_CS_N3': CDS_PINID='DDR6_SA_CS_N3';
NODE_NAME     J14 209
 '@S9S_MB_2U_LIB.S9S_MB_2U(SCH_1):PAGE95_I47@PURE_QUANTA.SCONN288_ADR50017P087CC(CHIPS)':
 'CS1_A_N': CDS_PINID='CS1_A_N';
NET_NAME
'M_G_CPU0_SA_DQ<0>'
 '@S9S_MB_2U_LIB.S9S_MB_2U(SCH_1):M_G_CPU0_SA_DQ'<0>:
 C_SIGNAL='@s9s_mb_2u_lib.s9s_mb_2u(sch_1):m_g_cpu0_sa_dq(0)';
NODE_NAME     U2 DV75
 '@S9S_MB_2U_LIB.S9S_MB_2U(SCH_1):PAGE26_I169@PURE_QUANTA.SOCKET4677_AZIF0045P001C01CS(CHIPS)':
 'DDR6_SA_DQ0': CDS_PINID='DDR6_SA_DQ0';
NODE_NAME     J13 7
 '@S9S_MB_2U_LIB.S9S_MB_2U(SCH_1):PAGE94_I11@PURE_QUANTA.SCONN288_ADR50017P130CC(CHIPS)':
 'DQ0_A': CDS_PINID='DQ0_A';
NODE_NAME     J14 7
 '@S9S_MB_2U_LIB.S9S_MB_2U(SCH_1):PAGE95_I47@PURE_QUANTA.SCONN288_ADR50017P087CC(CHIPS)':
 'DQ0_A': CDS_PINID='DQ0_A';
NET_NAME
'M_G_CPU0_SA_DQ<10>'
 '@S9S_MB_2U_LIB.S9S_MB_2U(SCH_1):M_G_CPU0_SA_DQ'<10>:
 C_SIGNAL='@s9s_mb_2u_lib.s9s_mb_2u(sch_1):m_g_cpu0_sa_dq(10)';
NODE_NAME     U2 DN72
 '@S9S_MB_2U_LIB.S9S_MB_2U(SCH_1):PAGE26_I169@PURE_QUANTA.SOCKET4677_AZIF0045P001C01CS(CHIPS)':
 'DDR6_SA_DQ10': CDS_PINID='DDR6_SA_DQ10';
NODE_NAME     J13 163
 '@S9S_MB_2U_LIB.S9S_MB_2U(SCH_1):PAGE94_I11@PURE_QUANTA.SCONN288_ADR50017P130CC(CHIPS)':
 'DQ10_A': CDS_PINID='DQ10_A';
NODE_NAME     J14 163
 '@S9S_MB_2U_LIB.S9S_MB_2U(SCH_1):PAGE95_I47@PURE_QUANTA.SCONN288_ADR50017P087CC(CHIPS)':
 'DQ10_A': CDS_PINID='DQ10_A';
NET_NAME
'M_G_CPU0_SA_DQ<11>'
 '@S9S_MB_2U_LIB.S9S_MB_2U(SCH_1):M_G_CPU0_SA_DQ'<11>:
 C_SIGNAL='@s9s_mb_2u_lib.s9s_mb_2u(sch_1):m_g_cpu0_sa_dq(11)';
NODE_NAME     U2 DP71
 '@S9S_MB_2U_LIB.S9S_MB_2U(SCH_1):PAGE26_I169@PURE_QUANTA.SOCKET4677_AZIF0045P001C01CS(CHIPS)':
 'DDR6_SA_DQ11': CDS_PINID='DDR6_SA_DQ11';
NODE_NAME     J13 165
 '@S9S_MB_2U_LIB.S9S_MB_2U(SCH_1):PAGE94_I11@PURE_QUANTA.SCONN288_ADR50017P130CC(CHIPS)':
 'DQ11_A': CDS_PINID='DQ11_A';
NODE_NAME     J14 165
 '@S9S_MB_2U_LIB.S9S_MB_2U(SCH_1):PAGE95_I47@PURE_QUANTA.SCONN288_ADR50017P087CC(CHIPS)':
 'DQ11_A': CDS_PINID='DQ11_A';
NET_NAME
'M_G_CPU0_SA_DQ<12>'
 '@S9S_MB_2U_LIB.S9S_MB_2U(SCH_1):M_G_CPU0_SA_DQ'<12>:
 C_SIGNAL='@s9s_mb_2u_lib.s9s_mb_2u(sch_1):m_g_cpu0_sa_dq(12)';
NODE_NAME     U2 DK69
 '@S9S_MB_2U_LIB.S9S_MB_2U(SCH_1):PAGE26_I169@PURE_QUANTA.SOCKET4677_AZIF0045P001C01CS(CHIPS)':
 'DDR6_SA_DQ12': CDS_PINID='DDR6_SA_DQ12';
NODE_NAME     J13 25
 '@S9S_MB_2U_LIB.S9S_MB_2U(SCH_1):PAGE94_I11@PURE_QUANTA.SCONN288_ADR50017P130CC(CHIPS)':
 'DQ12_A': CDS_PINID='DQ12_A';
NODE_NAME     J14 25
 '@S9S_MB_2U_LIB.S9S_MB_2U(SCH_1):PAGE95_I47@PURE_QUANTA.SCONN288_ADR50017P087CC(CHIPS)':
 'DQ12_A': CDS_PINID='DQ12_A';
NET_NAME
'M_G_CPU0_SA_DQ<13>'
 '@S9S_MB_2U_LIB.S9S_MB_2U(SCH_1):M_G_CPU0_SA_DQ'<13>:
 C_SIGNAL='@s9s_mb_2u_lib.s9s_mb_2u(sch_1):m_g_cpu0_sa_dq(13)';
NODE_NAME     U2 DL68
 '@S9S_MB_2U_LIB.S9S_MB_2U(SCH_1):PAGE26_I169@PURE_QUANTA.SOCKET4677_AZIF0045P001C01CS(CHIPS)':
 'DDR6_SA_DQ13': CDS_PINID='DDR6_SA_DQ13';
NODE_NAME     J13 27
 '@S9S_MB_2U_LIB.S9S_MB_2U(SCH_1):PAGE94_I11@PURE_QUANTA.SCONN288_ADR50017P130CC(CHIPS)':
 'DQ13_A': CDS_PINID='DQ13_A';
NODE_NAME     J14 27
 '@S9S_MB_2U_LIB.S9S_MB_2U(SCH_1):PAGE95_I47@PURE_QUANTA.SCONN288_ADR50017P087CC(CHIPS)':
 'DQ13_A': CDS_PINID='DQ13_A';
NET_NAME
'M_G_CPU0_SA_DQ<14>'
 '@S9S_MB_2U_LIB.S9S_MB_2U(SCH_1):M_G_CPU0_SA_DQ'<14>:
 C_SIGNAL='@s9s_mb_2u_lib.s9s_mb_2u(sch_1):m_g_cpu0_sa_dq(14)';
NODE_NAME     U2 DP69
 '@S9S_MB_2U_LIB.S9S_MB_2U(SCH_1):PAGE26_I169@PURE_QUANTA.SOCKET4677_AZIF0045P001C01CS(CHIPS)':
 'DDR6_SA_DQ14': CDS_PINID='DDR6_SA_DQ14';
NODE_NAME     J13 170
 '@S9S_MB_2U_LIB.S9S_MB_2U(SCH_1):PAGE94_I11@PURE_QUANTA.SCONN288_ADR50017P130CC(CHIPS)':
 'DQ14_A': CDS_PINID='DQ14_A';
NODE_NAME     J14 170
 '@S9S_MB_2U_LIB.S9S_MB_2U(SCH_1):PAGE95_I47@PURE_QUANTA.SCONN288_ADR50017P087CC(CHIPS)':
 'DQ14_A': CDS_PINID='DQ14_A';
NET_NAME
'M_G_CPU0_SA_DQ<15>'
 '@S9S_MB_2U_LIB.S9S_MB_2U(SCH_1):M_G_CPU0_SA_DQ'<15>:
 C_SIGNAL='@s9s_mb_2u_lib.s9s_mb_2u(sch_1):m_g_cpu0_sa_dq(15)';
NODE_NAME     U2 DN68
 '@S9S_MB_2U_LIB.S9S_MB_2U(SCH_1):PAGE26_I169@PURE_QUANTA.SOCKET4677_AZIF0045P001C01CS(CHIPS)':
 'DDR6_SA_DQ15': CDS_PINID='DDR6_SA_DQ15';
NODE_NAME     J13 172
 '@S9S_MB_2U_LIB.S9S_MB_2U(SCH_1):PAGE94_I11@PURE_QUANTA.SCONN288_ADR50017P130CC(CHIPS)':
 'DQ15_A': CDS_PINID='DQ15_A';
NODE_NAME     J14 172
 '@S9S_MB_2U_LIB.S9S_MB_2U(SCH_1):PAGE95_I47@PURE_QUANTA.SCONN288_ADR50017P087CC(CHIPS)':
 'DQ15_A': CDS_PINID='DQ15_A';
NET_NAME
'M_G_CPU0_SA_DQ<16>'
 '@S9S_MB_2U_LIB.S9S_MB_2U(SCH_1):M_G_CPU0_SA_DQ'<16>:
 C_SIGNAL='@s9s_mb_2u_lib.s9s_mb_2u(sch_1):m_g_cpu0_sa_dq(16)';
NODE_NAME     U2 DV63
 '@S9S_MB_2U_LIB.S9S_MB_2U(SCH_1):PAGE26_I169@PURE_QUANTA.SOCKET4677_AZIF0045P001C01CS(CHIPS)':
 'DDR6_SA_DQ16': CDS_PINID='DDR6_SA_DQ16';
NODE_NAME     J13 29
 '@S9S_MB_2U_LIB.S9S_MB_2U(SCH_1):PAGE94_I11@PURE_QUANTA.SCONN288_ADR50017P130CC(CHIPS)':
 'DQ16_A': CDS_PINID='DQ16_A';
NODE_NAME     J14 29
 '@S9S_MB_2U_LIB.S9S_MB_2U(SCH_1):PAGE95_I47@PURE_QUANTA.SCONN288_ADR50017P087CC(CHIPS)':
 'DQ16_A': CDS_PINID='DQ16_A';
NET_NAME
'M_G_CPU0_SA_DQ<17>'
 '@S9S_MB_2U_LIB.S9S_MB_2U(SCH_1):M_G_CPU0_SA_DQ'<17>:
 C_SIGNAL='@s9s_mb_2u_lib.s9s_mb_2u(sch_1):m_g_cpu0_sa_dq(17)';
NODE_NAME     U2 DU62
 '@S9S_MB_2U_LIB.S9S_MB_2U(SCH_1):PAGE26_I169@PURE_QUANTA.SOCKET4677_AZIF0045P001C01CS(CHIPS)':
 'DDR6_SA_DQ17': CDS_PINID='DDR6_SA_DQ17';
NODE_NAME     J13 31
 '@S9S_MB_2U_LIB.S9S_MB_2U(SCH_1):PAGE94_I11@PURE_QUANTA.SCONN288_ADR50017P130CC(CHIPS)':
 'DQ17_A': CDS_PINID='DQ17_A';
NODE_NAME     J14 31
 '@S9S_MB_2U_LIB.S9S_MB_2U(SCH_1):PAGE95_I47@PURE_QUANTA.SCONN288_ADR50017P087CC(CHIPS)':
 'DQ17_A': CDS_PINID='DQ17_A';
NET_NAME
'M_G_CPU0_SA_DQ<18>'
 '@S9S_MB_2U_LIB.S9S_MB_2U(SCH_1):M_G_CPU0_SA_DQ'<18>:
 C_SIGNAL='@s9s_mb_2u_lib.s9s_mb_2u(sch_1):m_g_cpu0_sa_dq(18)';
NODE_NAME     U2 DY63
 '@S9S_MB_2U_LIB.S9S_MB_2U(SCH_1):PAGE26_I169@PURE_QUANTA.SOCKET4677_AZIF0045P001C01CS(CHIPS)':
 'DDR6_SA_DQ18': CDS_PINID='DDR6_SA_DQ18';
NODE_NAME     J13 174
 '@S9S_MB_2U_LIB.S9S_MB_2U(SCH_1):PAGE94_I11@PURE_QUANTA.SCONN288_ADR50017P130CC(CHIPS)':
 'DQ18_A': CDS_PINID='DQ18_A';
NODE_NAME     J14 174
 '@S9S_MB_2U_LIB.S9S_MB_2U(SCH_1):PAGE95_I47@PURE_QUANTA.SCONN288_ADR50017P087CC(CHIPS)':
 'DQ18_A': CDS_PINID='DQ18_A';
NET_NAME
'M_G_CPU0_SA_DQ<19>'
 '@S9S_MB_2U_LIB.S9S_MB_2U(SCH_1):M_G_CPU0_SA_DQ'<19>:
 C_SIGNAL='@s9s_mb_2u_lib.s9s_mb_2u(sch_1):m_g_cpu0_sa_dq(19)';
NODE_NAME     U2 EA62
 '@S9S_MB_2U_LIB.S9S_MB_2U(SCH_1):PAGE26_I169@PURE_QUANTA.SOCKET4677_AZIF0045P001C01CS(CHIPS)':
 'DDR6_SA_DQ19': CDS_PINID='DDR6_SA_DQ19';
NODE_NAME     J13 176
 '@S9S_MB_2U_LIB.S9S_MB_2U(SCH_1):PAGE94_I11@PURE_QUANTA.SCONN288_ADR50017P130CC(CHIPS)':
 'DQ19_A': CDS_PINID='DQ19_A';
NODE_NAME     J14 176
 '@S9S_MB_2U_LIB.S9S_MB_2U(SCH_1):PAGE95_I47@PURE_QUANTA.SCONN288_ADR50017P087CC(CHIPS)':
 'DQ19_A': CDS_PINID='DQ19_A';
NET_NAME
'M_G_CPU0_SA_DQ<1>'
 '@S9S_MB_2U_LIB.S9S_MB_2U(SCH_1):M_G_CPU0_SA_DQ'<1>:
 C_SIGNAL='@s9s_mb_2u_lib.s9s_mb_2u(sch_1):m_g_cpu0_sa_dq(1)';
NODE_NAME     U2 DU74
 '@S9S_MB_2U_LIB.S9S_MB_2U(SCH_1):PAGE26_I169@PURE_QUANTA.SOCKET4677_AZIF0045P001C01CS(CHIPS)':
 'DDR6_SA_DQ1': CDS_PINID='DDR6_SA_DQ1';
NODE_NAME     J13 9
 '@S9S_MB_2U_LIB.S9S_MB_2U(SCH_1):PAGE94_I11@PURE_QUANTA.SCONN288_ADR50017P130CC(CHIPS)':
 'DQ1_A': CDS_PINID='DQ1_A';
NODE_NAME     J14 9
 '@S9S_MB_2U_LIB.S9S_MB_2U(SCH_1):PAGE95_I47@PURE_QUANTA.SCONN288_ADR50017P087CC(CHIPS)':
 'DQ1_A': CDS_PINID='DQ1_A';
NET_NAME
'M_G_CPU0_SA_DQ<20>'
 '@S9S_MB_2U_LIB.S9S_MB_2U(SCH_1):M_G_CPU0_SA_DQ'<20>:
 C_SIGNAL='@s9s_mb_2u_lib.s9s_mb_2u(sch_1):m_g_cpu0_sa_dq(20)';
NODE_NAME     U2 DU60
 '@S9S_MB_2U_LIB.S9S_MB_2U(SCH_1):PAGE26_I169@PURE_QUANTA.SOCKET4677_AZIF0045P001C01CS(CHIPS)':
 'DDR6_SA_DQ20': CDS_PINID='DDR6_SA_DQ20';
NODE_NAME     J13 36
 '@S9S_MB_2U_LIB.S9S_MB_2U(SCH_1):PAGE94_I11@PURE_QUANTA.SCONN288_ADR50017P130CC(CHIPS)':
 'DQ20_A': CDS_PINID='DQ20_A';
NODE_NAME     J14 36
 '@S9S_MB_2U_LIB.S9S_MB_2U(SCH_1):PAGE95_I47@PURE_QUANTA.SCONN288_ADR50017P087CC(CHIPS)':
 'DQ20_A': CDS_PINID='DQ20_A';
NET_NAME
'M_G_CPU0_SA_DQ<21>'
 '@S9S_MB_2U_LIB.S9S_MB_2U(SCH_1):M_G_CPU0_SA_DQ'<21>:
 C_SIGNAL='@s9s_mb_2u_lib.s9s_mb_2u(sch_1):m_g_cpu0_sa_dq(21)';
NODE_NAME     U2 DV59
 '@S9S_MB_2U_LIB.S9S_MB_2U(SCH_1):PAGE26_I169@PURE_QUANTA.SOCKET4677_AZIF0045P001C01CS(CHIPS)':
 'DDR6_SA_DQ21': CDS_PINID='DDR6_SA_DQ21';
NODE_NAME     J13 38
 '@S9S_MB_2U_LIB.S9S_MB_2U(SCH_1):PAGE94_I11@PURE_QUANTA.SCONN288_ADR50017P130CC(CHIPS)':
 'DQ21_A': CDS_PINID='DQ21_A';
NODE_NAME     J14 38
 '@S9S_MB_2U_LIB.S9S_MB_2U(SCH_1):PAGE95_I47@PURE_QUANTA.SCONN288_ADR50017P087CC(CHIPS)':
 'DQ21_A': CDS_PINID='DQ21_A';
NET_NAME
'M_G_CPU0_SA_DQ<22>'
 '@S9S_MB_2U_LIB.S9S_MB_2U(SCH_1):M_G_CPU0_SA_DQ'<22>:
 C_SIGNAL='@s9s_mb_2u_lib.s9s_mb_2u(sch_1):m_g_cpu0_sa_dq(22)';
NODE_NAME     U2 EA60
 '@S9S_MB_2U_LIB.S9S_MB_2U(SCH_1):PAGE26_I169@PURE_QUANTA.SOCKET4677_AZIF0045P001C01CS(CHIPS)':
 'DDR6_SA_DQ22': CDS_PINID='DDR6_SA_DQ22';
NODE_NAME     J13 181
 '@S9S_MB_2U_LIB.S9S_MB_2U(SCH_1):PAGE94_I11@PURE_QUANTA.SCONN288_ADR50017P130CC(CHIPS)':
 'DQ22_A': CDS_PINID='DQ22_A';
NODE_NAME     J14 181
 '@S9S_MB_2U_LIB.S9S_MB_2U(SCH_1):PAGE95_I47@PURE_QUANTA.SCONN288_ADR50017P087CC(CHIPS)':
 'DQ22_A': CDS_PINID='DQ22_A';
NET_NAME
'M_G_CPU0_SA_DQ<23>'
 '@S9S_MB_2U_LIB.S9S_MB_2U(SCH_1):M_G_CPU0_SA_DQ'<23>:
 C_SIGNAL='@s9s_mb_2u_lib.s9s_mb_2u(sch_1):m_g_cpu0_sa_dq(23)';
NODE_NAME     U2 DY59
 '@S9S_MB_2U_LIB.S9S_MB_2U(SCH_1):PAGE26_I169@PURE_QUANTA.SOCKET4677_AZIF0045P001C01CS(CHIPS)':
 'DDR6_SA_DQ23': CDS_PINID='DDR6_SA_DQ23';
NODE_NAME     J13 183
 '@S9S_MB_2U_LIB.S9S_MB_2U(SCH_1):PAGE94_I11@PURE_QUANTA.SCONN288_ADR50017P130CC(CHIPS)':
 'DQ23_A': CDS_PINID='DQ23_A';
NODE_NAME     J14 183
 '@S9S_MB_2U_LIB.S9S_MB_2U(SCH_1):PAGE95_I47@PURE_QUANTA.SCONN288_ADR50017P087CC(CHIPS)':
 'DQ23_A': CDS_PINID='DQ23_A';
NET_NAME
'M_G_CPU0_SA_DQ<24>'
 '@S9S_MB_2U_LIB.S9S_MB_2U(SCH_1):M_G_CPU0_SA_DQ'<24>:
 C_SIGNAL='@s9s_mb_2u_lib.s9s_mb_2u(sch_1):m_g_cpu0_sa_dq(24)';
NODE_NAME     U2 DL66
 '@S9S_MB_2U_LIB.S9S_MB_2U(SCH_1):PAGE26_I169@PURE_QUANTA.SOCKET4677_AZIF0045P001C01CS(CHIPS)':
 'DDR6_SA_DQ24': CDS_PINID='DDR6_SA_DQ24';
NODE_NAME     J13 40
 '@S9S_MB_2U_LIB.S9S_MB_2U(SCH_1):PAGE94_I11@PURE_QUANTA.SCONN288_ADR50017P130CC(CHIPS)':
 'DQ24_A': CDS_PINID='DQ24_A';
NODE_NAME     J14 40
 '@S9S_MB_2U_LIB.S9S_MB_2U(SCH_1):PAGE95_I47@PURE_QUANTA.SCONN288_ADR50017P087CC(CHIPS)':
 'DQ24_A': CDS_PINID='DQ24_A';
NET_NAME
'M_G_CPU0_SA_DQ<25>'
 '@S9S_MB_2U_LIB.S9S_MB_2U(SCH_1):M_G_CPU0_SA_DQ'<25>:
 C_SIGNAL='@s9s_mb_2u_lib.s9s_mb_2u(sch_1):m_g_cpu0_sa_dq(25)';
NODE_NAME     U2 DK65
 '@S9S_MB_2U_LIB.S9S_MB_2U(SCH_1):PAGE26_I169@PURE_QUANTA.SOCKET4677_AZIF0045P001C01CS(CHIPS)':
 'DDR6_SA_DQ25': CDS_PINID='DDR6_SA_DQ25';
NODE_NAME     J13 42
 '@S9S_MB_2U_LIB.S9S_MB_2U(SCH_1):PAGE94_I11@PURE_QUANTA.SCONN288_ADR50017P130CC(CHIPS)':
 'DQ25_A': CDS_PINID='DQ25_A';
NODE_NAME     J14 42
 '@S9S_MB_2U_LIB.S9S_MB_2U(SCH_1):PAGE95_I47@PURE_QUANTA.SCONN288_ADR50017P087CC(CHIPS)':
 'DQ25_A': CDS_PINID='DQ25_A';
NET_NAME
'M_G_CPU0_SA_DQ<26>'
 '@S9S_MB_2U_LIB.S9S_MB_2U(SCH_1):M_G_CPU0_SA_DQ'<26>:
 C_SIGNAL='@s9s_mb_2u_lib.s9s_mb_2u(sch_1):m_g_cpu0_sa_dq(26)';
NODE_NAME     U2 DN66
 '@S9S_MB_2U_LIB.S9S_MB_2U(SCH_1):PAGE26_I169@PURE_QUANTA.SOCKET4677_AZIF0045P001C01CS(CHIPS)':
 'DDR6_SA_DQ26': CDS_PINID='DDR6_SA_DQ26';
NODE_NAME     J13 185
 '@S9S_MB_2U_LIB.S9S_MB_2U(SCH_1):PAGE94_I11@PURE_QUANTA.SCONN288_ADR50017P130CC(CHIPS)':
 'DQ26_A': CDS_PINID='DQ26_A';
NODE_NAME     J14 185
 '@S9S_MB_2U_LIB.S9S_MB_2U(SCH_1):PAGE95_I47@PURE_QUANTA.SCONN288_ADR50017P087CC(CHIPS)':
 'DQ26_A': CDS_PINID='DQ26_A';
NET_NAME
'M_G_CPU0_SA_DQ<27>'
 '@S9S_MB_2U_LIB.S9S_MB_2U(SCH_1):M_G_CPU0_SA_DQ'<27>:
 C_SIGNAL='@s9s_mb_2u_lib.s9s_mb_2u(sch_1):m_g_cpu0_sa_dq(27)';
NODE_NAME     U2 DP65
 '@S9S_MB_2U_LIB.S9S_MB_2U(SCH_1):PAGE26_I169@PURE_QUANTA.SOCKET4677_AZIF0045P001C01CS(CHIPS)':
 'DDR6_SA_DQ27': CDS_PINID='DDR6_SA_DQ27';
NODE_NAME     J13 187
 '@S9S_MB_2U_LIB.S9S_MB_2U(SCH_1):PAGE94_I11@PURE_QUANTA.SCONN288_ADR50017P130CC(CHIPS)':
 'DQ27_A': CDS_PINID='DQ27_A';
NODE_NAME     J14 187
 '@S9S_MB_2U_LIB.S9S_MB_2U(SCH_1):PAGE95_I47@PURE_QUANTA.SCONN288_ADR50017P087CC(CHIPS)':
 'DQ27_A': CDS_PINID='DQ27_A';
NET_NAME
'M_G_CPU0_SA_DQ<28>'
 '@S9S_MB_2U_LIB.S9S_MB_2U(SCH_1):M_G_CPU0_SA_DQ'<28>:
 C_SIGNAL='@s9s_mb_2u_lib.s9s_mb_2u(sch_1):m_g_cpu0_sa_dq(28)';
NODE_NAME     U2 DK63
 '@S9S_MB_2U_LIB.S9S_MB_2U(SCH_1):PAGE26_I169@PURE_QUANTA.SOCKET4677_AZIF0045P001C01CS(CHIPS)':
 'DDR6_SA_DQ28': CDS_PINID='DDR6_SA_DQ28';
NODE_NAME     J13 47
 '@S9S_MB_2U_LIB.S9S_MB_2U(SCH_1):PAGE94_I11@PURE_QUANTA.SCONN288_ADR50017P130CC(CHIPS)':
 'DQ28_A': CDS_PINID='DQ28_A';
NODE_NAME     J14 47
 '@S9S_MB_2U_LIB.S9S_MB_2U(SCH_1):PAGE95_I47@PURE_QUANTA.SCONN288_ADR50017P087CC(CHIPS)':
 'DQ28_A': CDS_PINID='DQ28_A';
NET_NAME
'M_G_CPU0_SA_DQ<29>'
 '@S9S_MB_2U_LIB.S9S_MB_2U(SCH_1):M_G_CPU0_SA_DQ'<29>:
 C_SIGNAL='@s9s_mb_2u_lib.s9s_mb_2u(sch_1):m_g_cpu0_sa_dq(29)';
NODE_NAME     U2 DL62
 '@S9S_MB_2U_LIB.S9S_MB_2U(SCH_1):PAGE26_I169@PURE_QUANTA.SOCKET4677_AZIF0045P001C01CS(CHIPS)':
 'DDR6_SA_DQ29': CDS_PINID='DDR6_SA_DQ29';
NODE_NAME     J13 49
 '@S9S_MB_2U_LIB.S9S_MB_2U(SCH_1):PAGE94_I11@PURE_QUANTA.SCONN288_ADR50017P130CC(CHIPS)':
 'DQ29_A': CDS_PINID='DQ29_A';
NODE_NAME     J14 49
 '@S9S_MB_2U_LIB.S9S_MB_2U(SCH_1):PAGE95_I47@PURE_QUANTA.SCONN288_ADR50017P087CC(CHIPS)':
 'DQ29_A': CDS_PINID='DQ29_A';
NET_NAME
'M_G_CPU0_SA_DQ<2>'
 '@S9S_MB_2U_LIB.S9S_MB_2U(SCH_1):M_G_CPU0_SA_DQ'<2>:
 C_SIGNAL='@s9s_mb_2u_lib.s9s_mb_2u(sch_1):m_g_cpu0_sa_dq(2)';
NODE_NAME     U2 DY75
 '@S9S_MB_2U_LIB.S9S_MB_2U(SCH_1):PAGE26_I169@PURE_QUANTA.SOCKET4677_AZIF0045P001C01CS(CHIPS)':
 'DDR6_SA_DQ2': CDS_PINID='DDR6_SA_DQ2';
NODE_NAME     J13 152
 '@S9S_MB_2U_LIB.S9S_MB_2U(SCH_1):PAGE94_I11@PURE_QUANTA.SCONN288_ADR50017P130CC(CHIPS)':
 'DQ2_A': CDS_PINID='DQ2_A';
NODE_NAME     J14 152
 '@S9S_MB_2U_LIB.S9S_MB_2U(SCH_1):PAGE95_I47@PURE_QUANTA.SCONN288_ADR50017P087CC(CHIPS)':
 'DQ2_A': CDS_PINID='DQ2_A';
NET_NAME
'M_G_CPU0_SA_DQ<30>'
 '@S9S_MB_2U_LIB.S9S_MB_2U(SCH_1):M_G_CPU0_SA_DQ'<30>:
 C_SIGNAL='@s9s_mb_2u_lib.s9s_mb_2u(sch_1):m_g_cpu0_sa_dq(30)';
NODE_NAME     U2 DP63
 '@S9S_MB_2U_LIB.S9S_MB_2U(SCH_1):PAGE26_I169@PURE_QUANTA.SOCKET4677_AZIF0045P001C01CS(CHIPS)':
 'DDR6_SA_DQ30': CDS_PINID='DDR6_SA_DQ30';
NODE_NAME     J13 192
 '@S9S_MB_2U_LIB.S9S_MB_2U(SCH_1):PAGE94_I11@PURE_QUANTA.SCONN288_ADR50017P130CC(CHIPS)':
 'DQ30_A': CDS_PINID='DQ30_A';
NODE_NAME     J14 192
 '@S9S_MB_2U_LIB.S9S_MB_2U(SCH_1):PAGE95_I47@PURE_QUANTA.SCONN288_ADR50017P087CC(CHIPS)':
 'DQ30_A': CDS_PINID='DQ30_A';
NET_NAME
'M_G_CPU0_SA_DQ<31>'
 '@S9S_MB_2U_LIB.S9S_MB_2U(SCH_1):M_G_CPU0_SA_DQ'<31>:
 C_SIGNAL='@s9s_mb_2u_lib.s9s_mb_2u(sch_1):m_g_cpu0_sa_dq(31)';
NODE_NAME     U2 DN62
 '@S9S_MB_2U_LIB.S9S_MB_2U(SCH_1):PAGE26_I169@PURE_QUANTA.SOCKET4677_AZIF0045P001C01CS(CHIPS)':
 'DDR6_SA_DQ31': CDS_PINID='DDR6_SA_DQ31';
NODE_NAME     J13 194
 '@S9S_MB_2U_LIB.S9S_MB_2U(SCH_1):PAGE94_I11@PURE_QUANTA.SCONN288_ADR50017P130CC(CHIPS)':
 'DQ31_A': CDS_PINID='DQ31_A';
NODE_NAME     J14 194
 '@S9S_MB_2U_LIB.S9S_MB_2U(SCH_1):PAGE95_I47@PURE_QUANTA.SCONN288_ADR50017P087CC(CHIPS)':
 'DQ31_A': CDS_PINID='DQ31_A';
NET_NAME
'M_G_CPU0_SA_DQ<3>'
 '@S9S_MB_2U_LIB.S9S_MB_2U(SCH_1):M_G_CPU0_SA_DQ'<3>:
 C_SIGNAL='@s9s_mb_2u_lib.s9s_mb_2u(sch_1):m_g_cpu0_sa_dq(3)';
NODE_NAME     U2 EA74
 '@S9S_MB_2U_LIB.S9S_MB_2U(SCH_1):PAGE26_I169@PURE_QUANTA.SOCKET4677_AZIF0045P001C01CS(CHIPS)':
 'DDR6_SA_DQ3': CDS_PINID='DDR6_SA_DQ3';
NODE_NAME     J13 154
 '@S9S_MB_2U_LIB.S9S_MB_2U(SCH_1):PAGE94_I11@PURE_QUANTA.SCONN288_ADR50017P130CC(CHIPS)':
 'DQ3_A': CDS_PINID='DQ3_A';
NODE_NAME     J14 154
 '@S9S_MB_2U_LIB.S9S_MB_2U(SCH_1):PAGE95_I47@PURE_QUANTA.SCONN288_ADR50017P087CC(CHIPS)':
 'DQ3_A': CDS_PINID='DQ3_A';
NET_NAME
'M_G_CPU0_SA_DQ<4>'
 '@S9S_MB_2U_LIB.S9S_MB_2U(SCH_1):M_G_CPU0_SA_DQ'<4>:
 C_SIGNAL='@s9s_mb_2u_lib.s9s_mb_2u(sch_1):m_g_cpu0_sa_dq(4)';
NODE_NAME     U2 DU72
 '@S9S_MB_2U_LIB.S9S_MB_2U(SCH_1):PAGE26_I169@PURE_QUANTA.SOCKET4677_AZIF0045P001C01CS(CHIPS)':
 'DDR6_SA_DQ4': CDS_PINID='DDR6_SA_DQ4';
NODE_NAME     J13 14
 '@S9S_MB_2U_LIB.S9S_MB_2U(SCH_1):PAGE94_I11@PURE_QUANTA.SCONN288_ADR50017P130CC(CHIPS)':
 'DQ4_A': CDS_PINID='DQ4_A';
NODE_NAME     J14 14
 '@S9S_MB_2U_LIB.S9S_MB_2U(SCH_1):PAGE95_I47@PURE_QUANTA.SCONN288_ADR50017P087CC(CHIPS)':
 'DQ4_A': CDS_PINID='DQ4_A';
NET_NAME
'M_G_CPU0_SA_DQ<5>'
 '@S9S_MB_2U_LIB.S9S_MB_2U(SCH_1):M_G_CPU0_SA_DQ'<5>:
 C_SIGNAL='@s9s_mb_2u_lib.s9s_mb_2u(sch_1):m_g_cpu0_sa_dq(5)';
NODE_NAME     U2 DV71
 '@S9S_MB_2U_LIB.S9S_MB_2U(SCH_1):PAGE26_I169@PURE_QUANTA.SOCKET4677_AZIF0045P001C01CS(CHIPS)':
 'DDR6_SA_DQ5': CDS_PINID='DDR6_SA_DQ5';
NODE_NAME     J13 16
 '@S9S_MB_2U_LIB.S9S_MB_2U(SCH_1):PAGE94_I11@PURE_QUANTA.SCONN288_ADR50017P130CC(CHIPS)':
 'DQ5_A': CDS_PINID='DQ5_A';
NODE_NAME     J14 16
 '@S9S_MB_2U_LIB.S9S_MB_2U(SCH_1):PAGE95_I47@PURE_QUANTA.SCONN288_ADR50017P087CC(CHIPS)':
 'DQ5_A': CDS_PINID='DQ5_A';
NET_NAME
'M_G_CPU0_SA_DQ<6>'
 '@S9S_MB_2U_LIB.S9S_MB_2U(SCH_1):M_G_CPU0_SA_DQ'<6>:
 C_SIGNAL='@s9s_mb_2u_lib.s9s_mb_2u(sch_1):m_g_cpu0_sa_dq(6)';
NODE_NAME     U2 EA72
 '@S9S_MB_2U_LIB.S9S_MB_2U(SCH_1):PAGE26_I169@PURE_QUANTA.SOCKET4677_AZIF0045P001C01CS(CHIPS)':
 'DDR6_SA_DQ6': CDS_PINID='DDR6_SA_DQ6';
NODE_NAME     J13 159
 '@S9S_MB_2U_LIB.S9S_MB_2U(SCH_1):PAGE94_I11@PURE_QUANTA.SCONN288_ADR50017P130CC(CHIPS)':
 'DQ6_A': CDS_PINID='DQ6_A';
NODE_NAME     J14 159
 '@S9S_MB_2U_LIB.S9S_MB_2U(SCH_1):PAGE95_I47@PURE_QUANTA.SCONN288_ADR50017P087CC(CHIPS)':
 'DQ6_A': CDS_PINID='DQ6_A';
NET_NAME
'M_G_CPU0_SA_DQ<7>'
 '@S9S_MB_2U_LIB.S9S_MB_2U(SCH_1):M_G_CPU0_SA_DQ'<7>:
 C_SIGNAL='@s9s_mb_2u_lib.s9s_mb_2u(sch_1):m_g_cpu0_sa_dq(7)';
NODE_NAME     U2 DY71
 '@S9S_MB_2U_LIB.S9S_MB_2U(SCH_1):PAGE26_I169@PURE_QUANTA.SOCKET4677_AZIF0045P001C01CS(CHIPS)':
 'DDR6_SA_DQ7': CDS_PINID='DDR6_SA_DQ7';
NODE_NAME     J13 161
 '@S9S_MB_2U_LIB.S9S_MB_2U(SCH_1):PAGE94_I11@PURE_QUANTA.SCONN288_ADR50017P130CC(CHIPS)':
 'DQ7_A': CDS_PINID='DQ7_A';
NODE_NAME     J14 161
 '@S9S_MB_2U_LIB.S9S_MB_2U(SCH_1):PAGE95_I47@PURE_QUANTA.SCONN288_ADR50017P087CC(CHIPS)':
 'DQ7_A': CDS_PINID='DQ7_A';
NET_NAME
'M_G_CPU0_SA_DQ<8>'
 '@S9S_MB_2U_LIB.S9S_MB_2U(SCH_1):M_G_CPU0_SA_DQ'<8>:
 C_SIGNAL='@s9s_mb_2u_lib.s9s_mb_2u(sch_1):m_g_cpu0_sa_dq(8)';
NODE_NAME     U2 DL72
 '@S9S_MB_2U_LIB.S9S_MB_2U(SCH_1):PAGE26_I169@PURE_QUANTA.SOCKET4677_AZIF0045P001C01CS(CHIPS)':
 'DDR6_SA_DQ8': CDS_PINID='DDR6_SA_DQ8';
NODE_NAME     J13 18
 '@S9S_MB_2U_LIB.S9S_MB_2U(SCH_1):PAGE94_I11@PURE_QUANTA.SCONN288_ADR50017P130CC(CHIPS)':
 'DQ8_A': CDS_PINID='DQ8_A';
NODE_NAME     J14 18
 '@S9S_MB_2U_LIB.S9S_MB_2U(SCH_1):PAGE95_I47@PURE_QUANTA.SCONN288_ADR50017P087CC(CHIPS)':
 'DQ8_A': CDS_PINID='DQ8_A';
NET_NAME
'M_G_CPU0_SA_DQ<9>'
 '@S9S_MB_2U_LIB.S9S_MB_2U(SCH_1):M_G_CPU0_SA_DQ'<9>:
 C_SIGNAL='@s9s_mb_2u_lib.s9s_mb_2u(sch_1):m_g_cpu0_sa_dq(9)';
NODE_NAME     U2 DK71
 '@S9S_MB_2U_LIB.S9S_MB_2U(SCH_1):PAGE26_I169@PURE_QUANTA.SOCKET4677_AZIF0045P001C01CS(CHIPS)':
 'DDR6_SA_DQ9': CDS_PINID='DDR6_SA_DQ9';
NODE_NAME     J13 20
 '@S9S_MB_2U_LIB.S9S_MB_2U(SCH_1):PAGE94_I11@PURE_QUANTA.SCONN288_ADR50017P130CC(CHIPS)':
 'DQ9_A': CDS_PINID='DQ9_A';
NODE_NAME     J14 20
 '@S9S_MB_2U_LIB.S9S_MB_2U(SCH_1):PAGE95_I47@PURE_QUANTA.SCONN288_ADR50017P087CC(CHIPS)':
 'DQ9_A': CDS_PINID='DQ9_A';
NET_NAME
'M_G_CPU0_SA_DQS_DN<0>'
 '@S9S_MB_2U_LIB.S9S_MB_2U(SCH_1):M_G_CPU0_SA_DQS_DN'<0>:
 C_SIGNAL='@s9s_mb_2u_lib.s9s_mb_2u(sch_1):m_g_cpu0_sa_dqs_dn(0)';
NODE_NAME     U2 DV73
 '@S9S_MB_2U_LIB.S9S_MB_2U(SCH_1):PAGE26_I169@PURE_QUANTA.SOCKET4677_AZIF0045P001C01CS(CHIPS)':
 'DDR6_SA_DQS_DN0': CDS_PINID='DDR6_SA_DQS_DN0';
NODE_NAME     J13 12
 '@S9S_MB_2U_LIB.S9S_MB_2U(SCH_1):PAGE94_I178@PURE_QUANTA.SCONN288_ADR50017P130CC(CHIPS)':
 'DQS0_A_C': CDS_PINID='DQS0_A_C';
NODE_NAME     J14 12
 '@S9S_MB_2U_LIB.S9S_MB_2U(SCH_1):PAGE95_I178@PURE_QUANTA.SCONN288_ADR50017P087CC(CHIPS)':
 'DQS0_A_C': CDS_PINID='DQS0_A_C';
NET_NAME
'M_G_CPU0_SA_DQS_DN<1>'
 '@S9S_MB_2U_LIB.S9S_MB_2U(SCH_1):M_G_CPU0_SA_DQS_DN'<1>:
 C_SIGNAL='@s9s_mb_2u_lib.s9s_mb_2u(sch_1):m_g_cpu0_sa_dqs_dn(1)';
NODE_NAME     U2 DJ70
 '@S9S_MB_2U_LIB.S9S_MB_2U(SCH_1):PAGE26_I169@PURE_QUANTA.SOCKET4677_AZIF0045P001C01CS(CHIPS)':
 'DDR6_SA_DQS_DN1': CDS_PINID='DDR6_SA_DQS_DN1';
NODE_NAME     J13 23
 '@S9S_MB_2U_LIB.S9S_MB_2U(SCH_1):PAGE94_I178@PURE_QUANTA.SCONN288_ADR50017P130CC(CHIPS)':
 'DQS1_A_C': CDS_PINID='DQS1_A_C';
NODE_NAME     J14 23
 '@S9S_MB_2U_LIB.S9S_MB_2U(SCH_1):PAGE95_I178@PURE_QUANTA.SCONN288_ADR50017P087CC(CHIPS)':
 'DQS1_A_C': CDS_PINID='DQS1_A_C';
NET_NAME
'M_G_CPU0_SA_DQS_DN<2>'
 '@S9S_MB_2U_LIB.S9S_MB_2U(SCH_1):M_G_CPU0_SA_DQS_DN'<2>:
 C_SIGNAL='@s9s_mb_2u_lib.s9s_mb_2u(sch_1):m_g_cpu0_sa_dqs_dn(2)';
NODE_NAME     U2 DT61
 '@S9S_MB_2U_LIB.S9S_MB_2U(SCH_1):PAGE26_I169@PURE_QUANTA.SOCKET4677_AZIF0045P001C01CS(CHIPS)':
 'DDR6_SA_DQS_DN2': CDS_PINID='DDR6_SA_DQS_DN2';
NODE_NAME     J13 34
 '@S9S_MB_2U_LIB.S9S_MB_2U(SCH_1):PAGE94_I178@PURE_QUANTA.SCONN288_ADR50017P130CC(CHIPS)':
 'DQS2_A_C': CDS_PINID='DQS2_A_C';
NODE_NAME     J14 34
 '@S9S_MB_2U_LIB.S9S_MB_2U(SCH_1):PAGE95_I178@PURE_QUANTA.SCONN288_ADR50017P087CC(CHIPS)':
 'DQS2_A_C': CDS_PINID='DQS2_A_C';
NET_NAME
'M_G_CPU0_SA_DQS_DN<3>'
 '@S9S_MB_2U_LIB.S9S_MB_2U(SCH_1):M_G_CPU0_SA_DQS_DN'<3>:
 C_SIGNAL='@s9s_mb_2u_lib.s9s_mb_2u(sch_1):m_g_cpu0_sa_dqs_dn(3)';
NODE_NAME     U2 DL64
 '@S9S_MB_2U_LIB.S9S_MB_2U(SCH_1):PAGE26_I169@PURE_QUANTA.SOCKET4677_AZIF0045P001C01CS(CHIPS)':
 'DDR6_SA_DQS_DN3': CDS_PINID='DDR6_SA_DQS_DN3';
NODE_NAME     J13 45
 '@S9S_MB_2U_LIB.S9S_MB_2U(SCH_1):PAGE94_I178@PURE_QUANTA.SCONN288_ADR50017P130CC(CHIPS)':
 'DQS3_A_C': CDS_PINID='DQS3_A_C';
NODE_NAME     J14 45
 '@S9S_MB_2U_LIB.S9S_MB_2U(SCH_1):PAGE95_I178@PURE_QUANTA.SCONN288_ADR50017P087CC(CHIPS)':
 'DQS3_A_C': CDS_PINID='DQS3_A_C';
NET_NAME
'M_G_CPU0_SA_DQS_DN<4>'
 '@S9S_MB_2U_LIB.S9S_MB_2U(SCH_1):M_G_CPU0_SA_DQS_DN'<4>:
 C_SIGNAL='@s9s_mb_2u_lib.s9s_mb_2u(sch_1):m_g_cpu0_sa_dqs_dn(4)';
NODE_NAME     U2 DL58
 '@S9S_MB_2U_LIB.S9S_MB_2U(SCH_1):PAGE26_I169@PURE_QUANTA.SOCKET4677_AZIF0045P001C01CS(CHIPS)':
 'DDR6_SA_DQS_DN4': CDS_PINID='DDR6_SA_DQS_DN4';
NODE_NAME     J13 56
 '@S9S_MB_2U_LIB.S9S_MB_2U(SCH_1):PAGE94_I178@PURE_QUANTA.SCONN288_ADR50017P130CC(CHIPS)':
 'DQS4_A_C': CDS_PINID='DQS4_A_C';
NODE_NAME     J14 56
 '@S9S_MB_2U_LIB.S9S_MB_2U(SCH_1):PAGE95_I178@PURE_QUANTA.SCONN288_ADR50017P087CC(CHIPS)':
 'DQS4_A_C': CDS_PINID='DQS4_A_C';
NET_NAME
'M_G_CPU0_SA_DQS_DN<5>'
 '@S9S_MB_2U_LIB.S9S_MB_2U(SCH_1):M_G_CPU0_SA_DQS_DN'<5>:
 C_SIGNAL='@s9s_mb_2u_lib.s9s_mb_2u(sch_1):m_g_cpu0_sa_dqs_dn(5)';
NODE_NAME     U2 EB73
 '@S9S_MB_2U_LIB.S9S_MB_2U(SCH_1):PAGE26_I169@PURE_QUANTA.SOCKET4677_AZIF0045P001C01CS(CHIPS)':
 'DDR6_SA_DQS_DN5': CDS_PINID='DDR6_SA_DQS_DN5';
NODE_NAME     J13 156
 '@S9S_MB_2U_LIB.S9S_MB_2U(SCH_1):PAGE94_I178@PURE_QUANTA.SCONN288_ADR50017P130CC(CHIPS)':
 'DQS5_A_C||TDQS5_A_C||DQS5_A_T||TDQS5_A_T': CDS_PINID='\dqs5_a_c||tdqs5_a_c||dqs5_a_t||tdqs5_a_t\';
NODE_NAME     J14 156
 '@S9S_MB_2U_LIB.S9S_MB_2U(SCH_1):PAGE95_I178@PURE_QUANTA.SCONN288_ADR50017P087CC(CHIPS)':
 'DQS5_A_C||TDQS5_A_C||DQS5_A_T||TDQS5_A_T': CDS_PINID='\dqs5_a_c||tdqs5_a_c||dqs5_a_t||tdqs5_a_t\';
NET_NAME
'M_G_CPU0_SA_DQS_DN<6>'
 '@S9S_MB_2U_LIB.S9S_MB_2U(SCH_1):M_G_CPU0_SA_DQS_DN'<6>:
 C_SIGNAL='@s9s_mb_2u_lib.s9s_mb_2u(sch_1):m_g_cpu0_sa_dqs_dn(6)';
NODE_NAME     U2 DR70
 '@S9S_MB_2U_LIB.S9S_MB_2U(SCH_1):PAGE26_I169@PURE_QUANTA.SOCKET4677_AZIF0045P001C01CS(CHIPS)':
 'DDR6_SA_DQS_DN6': CDS_PINID='DDR6_SA_DQS_DN6';
NODE_NAME     J13 167
 '@S9S_MB_2U_LIB.S9S_MB_2U(SCH_1):PAGE94_I178@PURE_QUANTA.SCONN288_ADR50017P130CC(CHIPS)':
 'DQS6_A_C||TDQS6_A_C||DQS6_A_T||TDQS6_A_T': CDS_PINID='\dqs6_a_c||tdqs6_a_c||dqs6_a_t||tdqs6_a_t\';
NODE_NAME     J14 167
 '@S9S_MB_2U_LIB.S9S_MB_2U(SCH_1):PAGE95_I178@PURE_QUANTA.SCONN288_ADR50017P087CC(CHIPS)':
 'DQS6_A_C||TDQS6_A_C||DQS6_A_T||TDQS6_A_T': CDS_PINID='\dqs6_a_c||tdqs6_a_c||dqs6_a_t||tdqs6_a_t\';
NET_NAME
'M_G_CPU0_SA_DQS_DN<7>'
 '@S9S_MB_2U_LIB.S9S_MB_2U(SCH_1):M_G_CPU0_SA_DQS_DN'<7>:
 C_SIGNAL='@s9s_mb_2u_lib.s9s_mb_2u(sch_1):m_g_cpu0_sa_dqs_dn(7)';
NODE_NAME     U2 EB61
 '@S9S_MB_2U_LIB.S9S_MB_2U(SCH_1):PAGE26_I169@PURE_QUANTA.SOCKET4677_AZIF0045P001C01CS(CHIPS)':
 'DDR6_SA_DQS_DN7': CDS_PINID='DDR6_SA_DQS_DN7';
NODE_NAME     J13 178
 '@S9S_MB_2U_LIB.S9S_MB_2U(SCH_1):PAGE94_I178@PURE_QUANTA.SCONN288_ADR50017P130CC(CHIPS)':
 'DQS7_A_C||TDQS7_A_C': CDS_PINID='\dqs7_a_c||tdqs7_a_c\';
NODE_NAME     J14 178
 '@S9S_MB_2U_LIB.S9S_MB_2U(SCH_1):PAGE95_I178@PURE_QUANTA.SCONN288_ADR50017P087CC(CHIPS)':
 'DQS7_A_C||TDQS7_A_C': CDS_PINID='\dqs7_a_c||tdqs7_a_c\';
NET_NAME
'M_G_CPU0_SA_DQS_DN<8>'
 '@S9S_MB_2U_LIB.S9S_MB_2U(SCH_1):M_G_CPU0_SA_DQS_DN'<8>:
 C_SIGNAL='@s9s_mb_2u_lib.s9s_mb_2u(sch_1):m_g_cpu0_sa_dqs_dn(8)';
NODE_NAME     U2 DR64
 '@S9S_MB_2U_LIB.S9S_MB_2U(SCH_1):PAGE26_I169@PURE_QUANTA.SOCKET4677_AZIF0045P001C01CS(CHIPS)':
 'DDR6_SA_DQS_DN8': CDS_PINID='DDR6_SA_DQS_DN8';
NODE_NAME     J13 189
 '@S9S_MB_2U_LIB.S9S_MB_2U(SCH_1):PAGE94_I178@PURE_QUANTA.SCONN288_ADR50017P130CC(CHIPS)':
 'DQS8_A_C||TDQS8_A_C': CDS_PINID='\dqs8_a_c||tdqs8_a_c\';
NODE_NAME     J14 189
 '@S9S_MB_2U_LIB.S9S_MB_2U(SCH_1):PAGE95_I178@PURE_QUANTA.SCONN288_ADR50017P087CC(CHIPS)':
 'DQS8_A_C||TDQS8_A_C': CDS_PINID='\dqs8_a_c||tdqs8_a_c\';
NET_NAME
'M_G_CPU0_SA_DQS_DN<9>'
 '@S9S_MB_2U_LIB.S9S_MB_2U(SCH_1):M_G_CPU0_SA_DQS_DN'<9>:
 C_SIGNAL='@s9s_mb_2u_lib.s9s_mb_2u(sch_1):m_g_cpu0_sa_dqs_dn(9)';
NODE_NAME     U2 DR58
 '@S9S_MB_2U_LIB.S9S_MB_2U(SCH_1):PAGE26_I169@PURE_QUANTA.SOCKET4677_AZIF0045P001C01CS(CHIPS)':
 'DDR6_SA_DQS_DN9': CDS_PINID='DDR6_SA_DQS_DN9';
NODE_NAME     J13 200
 '@S9S_MB_2U_LIB.S9S_MB_2U(SCH_1):PAGE94_I178@PURE_QUANTA.SCONN288_ADR50017P130CC(CHIPS)':
 'DQS9_A_C||TDQS9_A_C': CDS_PINID='\dqs9_a_c||tdqs9_a_c\';
NODE_NAME     J14 200
 '@S9S_MB_2U_LIB.S9S_MB_2U(SCH_1):PAGE95_I178@PURE_QUANTA.SCONN288_ADR50017P087CC(CHIPS)':
 'DQS9_A_C||TDQS9_A_C': CDS_PINID='\dqs9_a_c||tdqs9_a_c\';
NET_NAME
'M_G_CPU0_SA_DQS_DP<0>'
 '@S9S_MB_2U_LIB.S9S_MB_2U(SCH_1):M_G_CPU0_SA_DQS_DP'<0>:
 C_SIGNAL='@s9s_mb_2u_lib.s9s_mb_2u(sch_1):m_g_cpu0_sa_dqs_dp(0)';
NODE_NAME     U2 DT73
 '@S9S_MB_2U_LIB.S9S_MB_2U(SCH_1):PAGE26_I169@PURE_QUANTA.SOCKET4677_AZIF0045P001C01CS(CHIPS)':
 'DDR6_SA_DQS_DP0': CDS_PINID='DDR6_SA_DQS_DP0';
NODE_NAME     J13 11
 '@S9S_MB_2U_LIB.S9S_MB_2U(SCH_1):PAGE94_I178@PURE_QUANTA.SCONN288_ADR50017P130CC(CHIPS)':
 'DQS0_A_T': CDS_PINID='DQS0_A_T';
NODE_NAME     J14 11
 '@S9S_MB_2U_LIB.S9S_MB_2U(SCH_1):PAGE95_I178@PURE_QUANTA.SCONN288_ADR50017P087CC(CHIPS)':
 'DQS0_A_T': CDS_PINID='DQS0_A_T';
NET_NAME
'M_G_CPU0_SA_DQS_DP<1>'
 '@S9S_MB_2U_LIB.S9S_MB_2U(SCH_1):M_G_CPU0_SA_DQS_DP'<1>:
 C_SIGNAL='@s9s_mb_2u_lib.s9s_mb_2u(sch_1):m_g_cpu0_sa_dqs_dp(1)';
NODE_NAME     U2 DL70
 '@S9S_MB_2U_LIB.S9S_MB_2U(SCH_1):PAGE26_I169@PURE_QUANTA.SOCKET4677_AZIF0045P001C01CS(CHIPS)':
 'DDR6_SA_DQS_DP1': CDS_PINID='DDR6_SA_DQS_DP1';
NODE_NAME     J13 22
 '@S9S_MB_2U_LIB.S9S_MB_2U(SCH_1):PAGE94_I178@PURE_QUANTA.SCONN288_ADR50017P130CC(CHIPS)':
 'DQS1_A_T': CDS_PINID='DQS1_A_T';
NODE_NAME     J14 22
 '@S9S_MB_2U_LIB.S9S_MB_2U(SCH_1):PAGE95_I178@PURE_QUANTA.SCONN288_ADR50017P087CC(CHIPS)':
 'DQS1_A_T': CDS_PINID='DQS1_A_T';
NET_NAME
'M_G_CPU0_SA_DQS_DP<2>'
 '@S9S_MB_2U_LIB.S9S_MB_2U(SCH_1):M_G_CPU0_SA_DQS_DP'<2>:
 C_SIGNAL='@s9s_mb_2u_lib.s9s_mb_2u(sch_1):m_g_cpu0_sa_dqs_dp(2)';
NODE_NAME     U2 DV61
 '@S9S_MB_2U_LIB.S9S_MB_2U(SCH_1):PAGE26_I169@PURE_QUANTA.SOCKET4677_AZIF0045P001C01CS(CHIPS)':
 'DDR6_SA_DQS_DP2': CDS_PINID='DDR6_SA_DQS_DP2';
NODE_NAME     J13 33
 '@S9S_MB_2U_LIB.S9S_MB_2U(SCH_1):PAGE94_I178@PURE_QUANTA.SCONN288_ADR50017P130CC(CHIPS)':
 'DQS2_A_T': CDS_PINID='DQS2_A_T';
NODE_NAME     J14 33
 '@S9S_MB_2U_LIB.S9S_MB_2U(SCH_1):PAGE95_I178@PURE_QUANTA.SCONN288_ADR50017P087CC(CHIPS)':
 'DQS2_A_T': CDS_PINID='DQS2_A_T';
NET_NAME
'M_G_CPU0_SA_DQS_DP<3>'
 '@S9S_MB_2U_LIB.S9S_MB_2U(SCH_1):M_G_CPU0_SA_DQS_DP'<3>:
 C_SIGNAL='@s9s_mb_2u_lib.s9s_mb_2u(sch_1):m_g_cpu0_sa_dqs_dp(3)';
NODE_NAME     U2 DJ64
 '@S9S_MB_2U_LIB.S9S_MB_2U(SCH_1):PAGE26_I169@PURE_QUANTA.SOCKET4677_AZIF0045P001C01CS(CHIPS)':
 'DDR6_SA_DQS_DP3': CDS_PINID='DDR6_SA_DQS_DP3';
NODE_NAME     J13 44
 '@S9S_MB_2U_LIB.S9S_MB_2U(SCH_1):PAGE94_I178@PURE_QUANTA.SCONN288_ADR50017P130CC(CHIPS)':
 'DQS3_A_T': CDS_PINID='DQS3_A_T';
NODE_NAME     J14 44
 '@S9S_MB_2U_LIB.S9S_MB_2U(SCH_1):PAGE95_I178@PURE_QUANTA.SCONN288_ADR50017P087CC(CHIPS)':
 'DQS3_A_T': CDS_PINID='DQS3_A_T';
NET_NAME
'M_G_CPU0_SA_DQS_DP<4>'
 '@S9S_MB_2U_LIB.S9S_MB_2U(SCH_1):M_G_CPU0_SA_DQS_DP'<4>:
 C_SIGNAL='@s9s_mb_2u_lib.s9s_mb_2u(sch_1):m_g_cpu0_sa_dqs_dp(4)';
NODE_NAME     U2 DJ58
 '@S9S_MB_2U_LIB.S9S_MB_2U(SCH_1):PAGE26_I169@PURE_QUANTA.SOCKET4677_AZIF0045P001C01CS(CHIPS)':
 'DDR6_SA_DQS_DP4': CDS_PINID='DDR6_SA_DQS_DP4';
NODE_NAME     J13 55
 '@S9S_MB_2U_LIB.S9S_MB_2U(SCH_1):PAGE94_I178@PURE_QUANTA.SCONN288_ADR50017P130CC(CHIPS)':
 'DQS4_A_T': CDS_PINID='DQS4_A_T';
NODE_NAME     J14 55
 '@S9S_MB_2U_LIB.S9S_MB_2U(SCH_1):PAGE95_I178@PURE_QUANTA.SCONN288_ADR50017P087CC(CHIPS)':
 'DQS4_A_T': CDS_PINID='DQS4_A_T';
NET_NAME
'M_G_CPU0_SA_DQS_DP<5>'
 '@S9S_MB_2U_LIB.S9S_MB_2U(SCH_1):M_G_CPU0_SA_DQS_DP'<5>:
 C_SIGNAL='@s9s_mb_2u_lib.s9s_mb_2u(sch_1):m_g_cpu0_sa_dqs_dp(5)';
NODE_NAME     U2 DY73
 '@S9S_MB_2U_LIB.S9S_MB_2U(SCH_1):PAGE26_I169@PURE_QUANTA.SOCKET4677_AZIF0045P001C01CS(CHIPS)':
 'DDR6_SA_DQS_DP5': CDS_PINID='DDR6_SA_DQS_DP5';
NODE_NAME     J13 157
 '@S9S_MB_2U_LIB.S9S_MB_2U(SCH_1):PAGE94_I178@PURE_QUANTA.SCONN288_ADR50017P130CC(CHIPS)':
 'DQS5_A_T||TDQS5_A_T': CDS_PINID='\dqs5_a_t||tdqs5_a_t\';
NODE_NAME     J14 157
 '@S9S_MB_2U_LIB.S9S_MB_2U(SCH_1):PAGE95_I178@PURE_QUANTA.SCONN288_ADR50017P087CC(CHIPS)':
 'DQS5_A_T||TDQS5_A_T': CDS_PINID='\dqs5_a_t||tdqs5_a_t\';
NET_NAME
'M_G_CPU0_SA_DQS_DP<6>'
 '@S9S_MB_2U_LIB.S9S_MB_2U(SCH_1):M_G_CPU0_SA_DQS_DP'<6>:
 C_SIGNAL='@s9s_mb_2u_lib.s9s_mb_2u(sch_1):m_g_cpu0_sa_dqs_dp(6)';
NODE_NAME     U2 DN70
 '@S9S_MB_2U_LIB.S9S_MB_2U(SCH_1):PAGE26_I169@PURE_QUANTA.SOCKET4677_AZIF0045P001C01CS(CHIPS)':
 'DDR6_SA_DQS_DP6': CDS_PINID='DDR6_SA_DQS_DP6';
NODE_NAME     J13 168
 '@S9S_MB_2U_LIB.S9S_MB_2U(SCH_1):PAGE94_I178@PURE_QUANTA.SCONN288_ADR50017P130CC(CHIPS)':
 'DQS6_A_T||TDQS6_A_T': CDS_PINID='\dqs6_a_t||tdqs6_a_t\';
NODE_NAME     J14 168
 '@S9S_MB_2U_LIB.S9S_MB_2U(SCH_1):PAGE95_I178@PURE_QUANTA.SCONN288_ADR50017P087CC(CHIPS)':
 'DQS6_A_T||TDQS6_A_T': CDS_PINID='\dqs6_a_t||tdqs6_a_t\';
NET_NAME
'M_G_CPU0_SA_DQS_DP<7>'
 '@S9S_MB_2U_LIB.S9S_MB_2U(SCH_1):M_G_CPU0_SA_DQS_DP'<7>:
 C_SIGNAL='@s9s_mb_2u_lib.s9s_mb_2u(sch_1):m_g_cpu0_sa_dqs_dp(7)';
NODE_NAME     U2 DY61
 '@S9S_MB_2U_LIB.S9S_MB_2U(SCH_1):PAGE26_I169@PURE_QUANTA.SOCKET4677_AZIF0045P001C01CS(CHIPS)':
 'DDR6_SA_DQS_DP7': CDS_PINID='DDR6_SA_DQS_DP7';
NODE_NAME     J13 179
 '@S9S_MB_2U_LIB.S9S_MB_2U(SCH_1):PAGE94_I178@PURE_QUANTA.SCONN288_ADR50017P130CC(CHIPS)':
 'DQS7_A_T||TDQS7_A_T': CDS_PINID='\dqs7_a_t||tdqs7_a_t\';
NODE_NAME     J14 179
 '@S9S_MB_2U_LIB.S9S_MB_2U(SCH_1):PAGE95_I178@PURE_QUANTA.SCONN288_ADR50017P087CC(CHIPS)':
 'DQS7_A_T||TDQS7_A_T': CDS_PINID='\dqs7_a_t||tdqs7_a_t\';
NET_NAME
'M_G_CPU0_SA_DQS_DP<8>'
 '@S9S_MB_2U_LIB.S9S_MB_2U(SCH_1):M_G_CPU0_SA_DQS_DP'<8>:
 C_SIGNAL='@s9s_mb_2u_lib.s9s_mb_2u(sch_1):m_g_cpu0_sa_dqs_dp(8)';
NODE_NAME     U2 DN64
 '@S9S_MB_2U_LIB.S9S_MB_2U(SCH_1):PAGE26_I169@PURE_QUANTA.SOCKET4677_AZIF0045P001C01CS(CHIPS)':
 'DDR6_SA_DQS_DP8': CDS_PINID='DDR6_SA_DQS_DP8';
NODE_NAME     J13 190
 '@S9S_MB_2U_LIB.S9S_MB_2U(SCH_1):PAGE94_I178@PURE_QUANTA.SCONN288_ADR50017P130CC(CHIPS)':
 'DQS8_A_T||TDQS8_A_T': CDS_PINID='\dqs8_a_t||tdqs8_a_t\';
NODE_NAME     J14 190
 '@S9S_MB_2U_LIB.S9S_MB_2U(SCH_1):PAGE95_I178@PURE_QUANTA.SCONN288_ADR50017P087CC(CHIPS)':
 'DQS8_A_T||TDQS8_A_T': CDS_PINID='\dqs8_a_t||tdqs8_a_t\';
NET_NAME
'M_G_CPU0_SA_DQS_DP<9>'
 '@S9S_MB_2U_LIB.S9S_MB_2U(SCH_1):M_G_CPU0_SA_DQS_DP'<9>:
 C_SIGNAL='@s9s_mb_2u_lib.s9s_mb_2u(sch_1):m_g_cpu0_sa_dqs_dp(9)';
NODE_NAME     U2 DN58
 '@S9S_MB_2U_LIB.S9S_MB_2U(SCH_1):PAGE26_I169@PURE_QUANTA.SOCKET4677_AZIF0045P001C01CS(CHIPS)':
 'DDR6_SA_DQS_DP9': CDS_PINID='DDR6_SA_DQS_DP9';
NODE_NAME     J13 201
 '@S9S_MB_2U_LIB.S9S_MB_2U(SCH_1):PAGE94_I178@PURE_QUANTA.SCONN288_ADR50017P130CC(CHIPS)':
 'DQS9_A_T||TDQS9_A_T': CDS_PINID='\dqs9_a_t||tdqs9_a_t\';
NODE_NAME     J14 201
 '@S9S_MB_2U_LIB.S9S_MB_2U(SCH_1):PAGE95_I178@PURE_QUANTA.SCONN288_ADR50017P087CC(CHIPS)':
 'DQS9_A_T||TDQS9_A_T': CDS_PINID='\dqs9_a_t||tdqs9_a_t\';
NET_NAME
'M_G_CPU0_SA_PAR'
 '@S9S_MB_2U_LIB.S9S_MB_2U(SCH_1):M_G_CPU0_SA_PAR':
 C_SIGNAL='@s9s_mb_2u_lib.s9s_mb_2u(sch_1):m_g_cpu0_sa_par';
NODE_NAME     U2 DL43
 '@S9S_MB_2U_LIB.S9S_MB_2U(SCH_1):PAGE26_I169@PURE_QUANTA.SOCKET4677_AZIF0045P001C01CS(CHIPS)':
 'DDR6_SA_PAR': CDS_PINID='DDR6_SA_PAR';
NODE_NAME     J13 74
 '@S9S_MB_2U_LIB.S9S_MB_2U(SCH_1):PAGE94_I11@PURE_QUANTA.SCONN288_ADR50017P130CC(CHIPS)':
 'PAR_A': CDS_PINID='PAR_A';
NODE_NAME     J14 74
 '@S9S_MB_2U_LIB.S9S_MB_2U(SCH_1):PAGE95_I47@PURE_QUANTA.SCONN288_ADR50017P087CC(CHIPS)':
 'PAR_A': CDS_PINID='PAR_A';
NET_NAME
'M_G_CPU0_SA_RSP<0>'
 '@S9S_MB_2U_LIB.S9S_MB_2U(SCH_1):M_G_CPU0_SA_RSP'<0>:
 C_SIGNAL='@s9s_mb_2u_lib.s9s_mb_2u(sch_1):m_g_cpu0_sa_rsp(0)';
NODE_NAME     U2 EA48
 '@S9S_MB_2U_LIB.S9S_MB_2U(SCH_1):PAGE26_I169@PURE_QUANTA.SOCKET4677_AZIF0045P001C01CS(CHIPS)':
 'DDR6_A_RSP0': CDS_PINID='DDR6_A_RSP0';
NODE_NAME     J13 86
 '@S9S_MB_2U_LIB.S9S_MB_2U(SCH_1):PAGE94_I11@PURE_QUANTA.SCONN288_ADR50017P130CC(CHIPS)':
 'LBD||RSP_A_N': CDS_PINID='\lbd||rsp_a_n\';
NET_NAME
'M_G_CPU0_SA_RSP<1>'
 '@S9S_MB_2U_LIB.S9S_MB_2U(SCH_1):M_G_CPU0_SA_RSP'<1>:
 C_SIGNAL='@s9s_mb_2u_lib.s9s_mb_2u(sch_1):m_g_cpu0_sa_rsp(1)';
NODE_NAME     U2 DY47
 '@S9S_MB_2U_LIB.S9S_MB_2U(SCH_1):PAGE26_I169@PURE_QUANTA.SOCKET4677_AZIF0045P001C01CS(CHIPS)':
 'DDR6_A_RSP1': CDS_PINID='DDR6_A_RSP1';
NODE_NAME     J14 86
 '@S9S_MB_2U_LIB.S9S_MB_2U(SCH_1):PAGE95_I47@PURE_QUANTA.SCONN288_ADR50017P087CC(CHIPS)':
 'LBD||RSP_A_N': CDS_PINID='\lbd||rsp_a_n\';
NET_NAME
'M_G_CPU0_SB_CA<0>'
 '@S9S_MB_2U_LIB.S9S_MB_2U(SCH_1):M_G_CPU0_SB_CA'<0>:
 C_SIGNAL='@s9s_mb_2u_lib.s9s_mb_2u(sch_1):m_g_cpu0_sb_ca(0)';
NODE_NAME     U2 DN43
 '@S9S_MB_2U_LIB.S9S_MB_2U(SCH_1):PAGE26_I169@PURE_QUANTA.SOCKET4677_AZIF0045P001C01CS(CHIPS)':
 'DDR6_SB_CA0': CDS_PINID='DDR6_SB_CA0';
NODE_NAME     J13 76
 '@S9S_MB_2U_LIB.S9S_MB_2U(SCH_1):PAGE94_I11@PURE_QUANTA.SCONN288_ADR50017P130CC(CHIPS)':
 'CA0_B': CDS_PINID='CA0_B';
NODE_NAME     J14 76
 '@S9S_MB_2U_LIB.S9S_MB_2U(SCH_1):PAGE95_I47@PURE_QUANTA.SCONN288_ADR50017P087CC(CHIPS)':
 'CA0_B': CDS_PINID='CA0_B';
NET_NAME
'M_G_CPU0_SB_CA<1>'
 '@S9S_MB_2U_LIB.S9S_MB_2U(SCH_1):M_G_CPU0_SB_CA'<1>:
 C_SIGNAL='@s9s_mb_2u_lib.s9s_mb_2u(sch_1):m_g_cpu0_sb_ca(1)';
NODE_NAME     U2 DP44
 '@S9S_MB_2U_LIB.S9S_MB_2U(SCH_1):PAGE26_I169@PURE_QUANTA.SOCKET4677_AZIF0045P001C01CS(CHIPS)':
 'DDR6_SB_CA1': CDS_PINID='DDR6_SB_CA1';
NODE_NAME     J13 221
 '@S9S_MB_2U_LIB.S9S_MB_2U(SCH_1):PAGE94_I11@PURE_QUANTA.SCONN288_ADR50017P130CC(CHIPS)':
 'CA1_B': CDS_PINID='CA1_B';
NODE_NAME     J14 221
 '@S9S_MB_2U_LIB.S9S_MB_2U(SCH_1):PAGE95_I47@PURE_QUANTA.SCONN288_ADR50017P087CC(CHIPS)':
 'CA1_B': CDS_PINID='CA1_B';
NET_NAME
'M_G_CPU0_SB_CA<2>'
 '@S9S_MB_2U_LIB.S9S_MB_2U(SCH_1):M_G_CPU0_SB_CA'<2>:
 C_SIGNAL='@s9s_mb_2u_lib.s9s_mb_2u(sch_1):m_g_cpu0_sb_ca(2)';
NODE_NAME     U2 DV44
 '@S9S_MB_2U_LIB.S9S_MB_2U(SCH_1):PAGE26_I169@PURE_QUANTA.SOCKET4677_AZIF0045P001C01CS(CHIPS)':
 'DDR6_SB_CA2': CDS_PINID='DDR6_SB_CA2';
NODE_NAME     J13 78
 '@S9S_MB_2U_LIB.S9S_MB_2U(SCH_1):PAGE94_I11@PURE_QUANTA.SCONN288_ADR50017P130CC(CHIPS)':
 'CA2_B': CDS_PINID='CA2_B';
NODE_NAME     J14 78
 '@S9S_MB_2U_LIB.S9S_MB_2U(SCH_1):PAGE95_I47@PURE_QUANTA.SCONN288_ADR50017P087CC(CHIPS)':
 'CA2_B': CDS_PINID='CA2_B';
NET_NAME
'M_G_CPU0_SB_CA<3>'
 '@S9S_MB_2U_LIB.S9S_MB_2U(SCH_1):M_G_CPU0_SB_CA'<3>:
 C_SIGNAL='@s9s_mb_2u_lib.s9s_mb_2u(sch_1):m_g_cpu0_sb_ca(3)';
NODE_NAME     U2 DY44
 '@S9S_MB_2U_LIB.S9S_MB_2U(SCH_1):PAGE26_I169@PURE_QUANTA.SOCKET4677_AZIF0045P001C01CS(CHIPS)':
 'DDR6_SB_CA3': CDS_PINID='DDR6_SB_CA3';
NODE_NAME     J13 223
 '@S9S_MB_2U_LIB.S9S_MB_2U(SCH_1):PAGE94_I11@PURE_QUANTA.SCONN288_ADR50017P130CC(CHIPS)':
 'CA3_B': CDS_PINID='CA3_B';
NODE_NAME     J14 223
 '@S9S_MB_2U_LIB.S9S_MB_2U(SCH_1):PAGE95_I47@PURE_QUANTA.SCONN288_ADR50017P087CC(CHIPS)':
 'CA3_B': CDS_PINID='CA3_B';
NET_NAME
'M_G_CPU0_SB_CA<4>'
 '@S9S_MB_2U_LIB.S9S_MB_2U(SCH_1):M_G_CPU0_SB_CA'<4>:
 C_SIGNAL='@s9s_mb_2u_lib.s9s_mb_2u(sch_1):m_g_cpu0_sb_ca(4)';
NODE_NAME     U2 DU43
 '@S9S_MB_2U_LIB.S9S_MB_2U(SCH_1):PAGE26_I169@PURE_QUANTA.SOCKET4677_AZIF0045P001C01CS(CHIPS)':
 'DDR6_SB_CA4': CDS_PINID='DDR6_SB_CA4';
NODE_NAME     J13 80
 '@S9S_MB_2U_LIB.S9S_MB_2U(SCH_1):PAGE94_I11@PURE_QUANTA.SCONN288_ADR50017P130CC(CHIPS)':
 'CA4_B': CDS_PINID='CA4_B';
NODE_NAME     J14 80
 '@S9S_MB_2U_LIB.S9S_MB_2U(SCH_1):PAGE95_I47@PURE_QUANTA.SCONN288_ADR50017P087CC(CHIPS)':
 'CA4_B': CDS_PINID='CA4_B';
NET_NAME
'M_G_CPU0_SB_CA<5>'
 '@S9S_MB_2U_LIB.S9S_MB_2U(SCH_1):M_G_CPU0_SB_CA'<5>:
 C_SIGNAL='@s9s_mb_2u_lib.s9s_mb_2u(sch_1):m_g_cpu0_sb_ca(5)';
NODE_NAME     U2 EA43
 '@S9S_MB_2U_LIB.S9S_MB_2U(SCH_1):PAGE26_I169@PURE_QUANTA.SOCKET4677_AZIF0045P001C01CS(CHIPS)':
 'DDR6_SB_CA5': CDS_PINID='DDR6_SB_CA5';
NODE_NAME     J13 225
 '@S9S_MB_2U_LIB.S9S_MB_2U(SCH_1):PAGE94_I11@PURE_QUANTA.SCONN288_ADR50017P130CC(CHIPS)':
 'CA5_B': CDS_PINID='CA5_B';
NODE_NAME     J14 225
 '@S9S_MB_2U_LIB.S9S_MB_2U(SCH_1):PAGE95_I47@PURE_QUANTA.SCONN288_ADR50017P087CC(CHIPS)':
 'CA5_B': CDS_PINID='CA5_B';
NET_NAME
'M_G_CPU0_SB_CA<6>'
 '@S9S_MB_2U_LIB.S9S_MB_2U(SCH_1):M_G_CPU0_SB_CA'<6>:
 C_SIGNAL='@s9s_mb_2u_lib.s9s_mb_2u(sch_1):m_g_cpu0_sb_ca(6)';
NODE_NAME     U2 DT42
 '@S9S_MB_2U_LIB.S9S_MB_2U(SCH_1):PAGE26_I169@PURE_QUANTA.SOCKET4677_AZIF0045P001C01CS(CHIPS)':
 'DDR6_SB_CA6': CDS_PINID='DDR6_SB_CA6';
NODE_NAME     J13 82
 '@S9S_MB_2U_LIB.S9S_MB_2U(SCH_1):PAGE94_I11@PURE_QUANTA.SCONN288_ADR50017P130CC(CHIPS)':
 'CA6_B': CDS_PINID='CA6_B';
NODE_NAME     J14 82
 '@S9S_MB_2U_LIB.S9S_MB_2U(SCH_1):PAGE95_I47@PURE_QUANTA.SCONN288_ADR50017P087CC(CHIPS)':
 'CA6_B': CDS_PINID='CA6_B';
NET_NAME
'M_G_CPU0_SB_CB<0>'
 '@S9S_MB_2U_LIB.S9S_MB_2U(SCH_1):M_G_CPU0_SB_CB'<0>:
 C_SIGNAL='@s9s_mb_2u_lib.s9s_mb_2u(sch_1):m_g_cpu0_sb_cb(0)';
NODE_NAME     U2 DU35
 '@S9S_MB_2U_LIB.S9S_MB_2U(SCH_1):PAGE26_I169@PURE_QUANTA.SOCKET4677_AZIF0045P001C01CS(CHIPS)':
 'DDR6_SB_ECC0': CDS_PINID='DDR6_SB_ECC0';
NODE_NAME     J13 96
 '@S9S_MB_2U_LIB.S9S_MB_2U(SCH_1):PAGE94_I11@PURE_QUANTA.SCONN288_ADR50017P130CC(CHIPS)':
 'CB0_B': CDS_PINID='CB0_B';
NODE_NAME     J14 96
 '@S9S_MB_2U_LIB.S9S_MB_2U(SCH_1):PAGE95_I47@PURE_QUANTA.SCONN288_ADR50017P087CC(CHIPS)':
 'CB0_B': CDS_PINID='CB0_B';
NET_NAME
'M_G_CPU0_SB_CB<1>'
 '@S9S_MB_2U_LIB.S9S_MB_2U(SCH_1):M_G_CPU0_SB_CB'<1>:
 C_SIGNAL='@s9s_mb_2u_lib.s9s_mb_2u(sch_1):m_g_cpu0_sb_cb(1)';
NODE_NAME     U2 DV34
 '@S9S_MB_2U_LIB.S9S_MB_2U(SCH_1):PAGE26_I169@PURE_QUANTA.SOCKET4677_AZIF0045P001C01CS(CHIPS)':
 'DDR6_SB_ECC1': CDS_PINID='DDR6_SB_ECC1';
NODE_NAME     J13 98
 '@S9S_MB_2U_LIB.S9S_MB_2U(SCH_1):PAGE94_I11@PURE_QUANTA.SCONN288_ADR50017P130CC(CHIPS)':
 'CB1_B': CDS_PINID='CB1_B';
NODE_NAME     J14 98
 '@S9S_MB_2U_LIB.S9S_MB_2U(SCH_1):PAGE95_I47@PURE_QUANTA.SCONN288_ADR50017P087CC(CHIPS)':
 'CB1_B': CDS_PINID='CB1_B';
NET_NAME
'M_G_CPU0_SB_CB<2>'
 '@S9S_MB_2U_LIB.S9S_MB_2U(SCH_1):M_G_CPU0_SB_CB'<2>:
 C_SIGNAL='@s9s_mb_2u_lib.s9s_mb_2u(sch_1):m_g_cpu0_sb_cb(2)';
NODE_NAME     U2 EA35
 '@S9S_MB_2U_LIB.S9S_MB_2U(SCH_1):PAGE26_I169@PURE_QUANTA.SOCKET4677_AZIF0045P001C01CS(CHIPS)':
 'DDR6_SB_ECC2': CDS_PINID='DDR6_SB_ECC2';
NODE_NAME     J13 241
 '@S9S_MB_2U_LIB.S9S_MB_2U(SCH_1):PAGE94_I11@PURE_QUANTA.SCONN288_ADR50017P130CC(CHIPS)':
 'CB2_B': CDS_PINID='CB2_B';
NODE_NAME     J14 241
 '@S9S_MB_2U_LIB.S9S_MB_2U(SCH_1):PAGE95_I47@PURE_QUANTA.SCONN288_ADR50017P087CC(CHIPS)':
 'CB2_B': CDS_PINID='CB2_B';
NET_NAME
'M_G_CPU0_SB_CB<3>'
 '@S9S_MB_2U_LIB.S9S_MB_2U(SCH_1):M_G_CPU0_SB_CB'<3>:
 C_SIGNAL='@s9s_mb_2u_lib.s9s_mb_2u(sch_1):m_g_cpu0_sb_cb(3)';
NODE_NAME     U2 DY34
 '@S9S_MB_2U_LIB.S9S_MB_2U(SCH_1):PAGE26_I169@PURE_QUANTA.SOCKET4677_AZIF0045P001C01CS(CHIPS)':
 'DDR6_SB_ECC3': CDS_PINID='DDR6_SB_ECC3';
NODE_NAME     J13 243
 '@S9S_MB_2U_LIB.S9S_MB_2U(SCH_1):PAGE94_I11@PURE_QUANTA.SCONN288_ADR50017P130CC(CHIPS)':
 'CB3_B': CDS_PINID='CB3_B';
NODE_NAME     J14 243
 '@S9S_MB_2U_LIB.S9S_MB_2U(SCH_1):PAGE95_I47@PURE_QUANTA.SCONN288_ADR50017P087CC(CHIPS)':
 'CB3_B': CDS_PINID='CB3_B';
NET_NAME
'M_G_CPU0_SB_CB<4>'
 '@S9S_MB_2U_LIB.S9S_MB_2U(SCH_1):M_G_CPU0_SB_CB'<4>:
 C_SIGNAL='@s9s_mb_2u_lib.s9s_mb_2u(sch_1):m_g_cpu0_sb_cb(4)';
NODE_NAME     U2 DV38
 '@S9S_MB_2U_LIB.S9S_MB_2U(SCH_1):PAGE26_I169@PURE_QUANTA.SOCKET4677_AZIF0045P001C01CS(CHIPS)':
 'DDR6_SB_ECC4': CDS_PINID='DDR6_SB_ECC4';
NODE_NAME     J13 89
 '@S9S_MB_2U_LIB.S9S_MB_2U(SCH_1):PAGE94_I11@PURE_QUANTA.SCONN288_ADR50017P130CC(CHIPS)':
 'CB4_B': CDS_PINID='CB4_B';
NODE_NAME     J14 89
 '@S9S_MB_2U_LIB.S9S_MB_2U(SCH_1):PAGE95_I47@PURE_QUANTA.SCONN288_ADR50017P087CC(CHIPS)':
 'CB4_B': CDS_PINID='CB4_B';
NET_NAME
'M_G_CPU0_SB_CB<5>'
 '@S9S_MB_2U_LIB.S9S_MB_2U(SCH_1):M_G_CPU0_SB_CB'<5>:
 C_SIGNAL='@s9s_mb_2u_lib.s9s_mb_2u(sch_1):m_g_cpu0_sb_cb(5)';
NODE_NAME     U2 DU37
 '@S9S_MB_2U_LIB.S9S_MB_2U(SCH_1):PAGE26_I169@PURE_QUANTA.SOCKET4677_AZIF0045P001C01CS(CHIPS)':
 'DDR6_SB_ECC5': CDS_PINID='DDR6_SB_ECC5';
NODE_NAME     J13 91
 '@S9S_MB_2U_LIB.S9S_MB_2U(SCH_1):PAGE94_I11@PURE_QUANTA.SCONN288_ADR50017P130CC(CHIPS)':
 'CB5_B': CDS_PINID='CB5_B';
NODE_NAME     J14 91
 '@S9S_MB_2U_LIB.S9S_MB_2U(SCH_1):PAGE95_I47@PURE_QUANTA.SCONN288_ADR50017P087CC(CHIPS)':
 'CB5_B': CDS_PINID='CB5_B';
NET_NAME
'M_G_CPU0_SB_CB<6>'
 '@S9S_MB_2U_LIB.S9S_MB_2U(SCH_1):M_G_CPU0_SB_CB'<6>:
 C_SIGNAL='@s9s_mb_2u_lib.s9s_mb_2u(sch_1):m_g_cpu0_sb_cb(6)';
NODE_NAME     U2 DY38
 '@S9S_MB_2U_LIB.S9S_MB_2U(SCH_1):PAGE26_I169@PURE_QUANTA.SOCKET4677_AZIF0045P001C01CS(CHIPS)':
 'DDR6_SB_ECC6': CDS_PINID='DDR6_SB_ECC6';
NODE_NAME     J13 234
 '@S9S_MB_2U_LIB.S9S_MB_2U(SCH_1):PAGE94_I11@PURE_QUANTA.SCONN288_ADR50017P130CC(CHIPS)':
 'CB6_B': CDS_PINID='CB6_B';
NODE_NAME     J14 234
 '@S9S_MB_2U_LIB.S9S_MB_2U(SCH_1):PAGE95_I47@PURE_QUANTA.SCONN288_ADR50017P087CC(CHIPS)':
 'CB6_B': CDS_PINID='CB6_B';
NET_NAME
'M_G_CPU0_SB_CB<7>'
 '@S9S_MB_2U_LIB.S9S_MB_2U(SCH_1):M_G_CPU0_SB_CB'<7>:
 C_SIGNAL='@s9s_mb_2u_lib.s9s_mb_2u(sch_1):m_g_cpu0_sb_cb(7)';
NODE_NAME     U2 EA37
 '@S9S_MB_2U_LIB.S9S_MB_2U(SCH_1):PAGE26_I169@PURE_QUANTA.SOCKET4677_AZIF0045P001C01CS(CHIPS)':
 'DDR6_SB_ECC7': CDS_PINID='DDR6_SB_ECC7';
NODE_NAME     J13 236
 '@S9S_MB_2U_LIB.S9S_MB_2U(SCH_1):PAGE94_I11@PURE_QUANTA.SCONN288_ADR50017P130CC(CHIPS)':
 'CB7_B': CDS_PINID='CB7_B';
NODE_NAME     J14 236
 '@S9S_MB_2U_LIB.S9S_MB_2U(SCH_1):PAGE95_I47@PURE_QUANTA.SCONN288_ADR50017P087CC(CHIPS)':
 'CB7_B': CDS_PINID='CB7_B';
NET_NAME
'M_G_CPU0_SB_CS_N<0>'
 '@S9S_MB_2U_LIB.S9S_MB_2U(SCH_1):M_G_CPU0_SB_CS_N'<0>:
 C_SIGNAL='@s9s_mb_2u_lib.s9s_mb_2u(sch_1):m_g_cpu0_sb_cs_n(0)';
NODE_NAME     U2 EA41
 '@S9S_MB_2U_LIB.S9S_MB_2U(SCH_1):PAGE26_I169@PURE_QUANTA.SOCKET4677_AZIF0045P001C01CS(CHIPS)':
 'DDR6_SB_CS_N0': CDS_PINID='DDR6_SB_CS_N0';
NODE_NAME     J13 84
 '@S9S_MB_2U_LIB.S9S_MB_2U(SCH_1):PAGE94_I11@PURE_QUANTA.SCONN288_ADR50017P130CC(CHIPS)':
 'CS0_B_N': CDS_PINID='CS0_B_N';
NET_NAME
'M_G_CPU0_SB_CS_N<1>'
 '@S9S_MB_2U_LIB.S9S_MB_2U(SCH_1):M_G_CPU0_SB_CS_N'<1>:
 C_SIGNAL='@s9s_mb_2u_lib.s9s_mb_2u(sch_1):m_g_cpu0_sb_cs_n(1)';
NODE_NAME     U2 DY40
 '@S9S_MB_2U_LIB.S9S_MB_2U(SCH_1):PAGE26_I169@PURE_QUANTA.SOCKET4677_AZIF0045P001C01CS(CHIPS)':
 'DDR6_SB_CS_N1': CDS_PINID='DDR6_SB_CS_N1';
NODE_NAME     J13 229
 '@S9S_MB_2U_LIB.S9S_MB_2U(SCH_1):PAGE94_I11@PURE_QUANTA.SCONN288_ADR50017P130CC(CHIPS)':
 'CS1_B_N': CDS_PINID='CS1_B_N';
NET_NAME
'M_G_CPU0_SB_CS_N<2>'
 '@S9S_MB_2U_LIB.S9S_MB_2U(SCH_1):M_G_CPU0_SB_CS_N'<2>:
 C_SIGNAL='@s9s_mb_2u_lib.s9s_mb_2u(sch_1):m_g_cpu0_sb_cs_n(2)';
NODE_NAME     U2 DU41
 '@S9S_MB_2U_LIB.S9S_MB_2U(SCH_1):PAGE26_I169@PURE_QUANTA.SOCKET4677_AZIF0045P001C01CS(CHIPS)':
 'DDR6_SB_CS_N2': CDS_PINID='DDR6_SB_CS_N2';
NODE_NAME     J14 84
 '@S9S_MB_2U_LIB.S9S_MB_2U(SCH_1):PAGE95_I47@PURE_QUANTA.SCONN288_ADR50017P087CC(CHIPS)':
 'CS0_B_N': CDS_PINID='CS0_B_N';
NET_NAME
'M_G_CPU0_SB_CS_N<3>'
 '@S9S_MB_2U_LIB.S9S_MB_2U(SCH_1):M_G_CPU0_SB_CS_N'<3>:
 C_SIGNAL='@s9s_mb_2u_lib.s9s_mb_2u(sch_1):m_g_cpu0_sb_cs_n(3)';
NODE_NAME     U2 DV40
 '@S9S_MB_2U_LIB.S9S_MB_2U(SCH_1):PAGE26_I169@PURE_QUANTA.SOCKET4677_AZIF0045P001C01CS(CHIPS)':
 'DDR6_SB_CS_N3': CDS_PINID='DDR6_SB_CS_N3';
NODE_NAME     J14 229
 '@S9S_MB_2U_LIB.S9S_MB_2U(SCH_1):PAGE95_I47@PURE_QUANTA.SCONN288_ADR50017P087CC(CHIPS)':
 'CS1_B_N': CDS_PINID='CS1_B_N';
NET_NAME
'M_G_CPU0_SB_DQ<0>'
 '@S9S_MB_2U_LIB.S9S_MB_2U(SCH_1):M_G_CPU0_SB_DQ'<0>:
 C_SIGNAL='@s9s_mb_2u_lib.s9s_mb_2u(sch_1):m_g_cpu0_sb_dq(0)';
NODE_NAME     U2 DL35
 '@S9S_MB_2U_LIB.S9S_MB_2U(SCH_1):PAGE26_I169@PURE_QUANTA.SOCKET4677_AZIF0045P001C01CS(CHIPS)':
 'DDR6_SB_DQ0': CDS_PINID='DDR6_SB_DQ0';
NODE_NAME     J13 100
 '@S9S_MB_2U_LIB.S9S_MB_2U(SCH_1):PAGE94_I11@PURE_QUANTA.SCONN288_ADR50017P130CC(CHIPS)':
 'DQ0_B': CDS_PINID='DQ0_B';
NODE_NAME     J14 100
 '@S9S_MB_2U_LIB.S9S_MB_2U(SCH_1):PAGE95_I47@PURE_QUANTA.SCONN288_ADR50017P087CC(CHIPS)':
 'DQ0_B': CDS_PINID='DQ0_B';
NET_NAME
'M_G_CPU0_SB_DQ<10>'
 '@S9S_MB_2U_LIB.S9S_MB_2U(SCH_1):M_G_CPU0_SB_DQ'<10>:
 C_SIGNAL='@s9s_mb_2u_lib.s9s_mb_2u(sch_1):m_g_cpu0_sb_dq(10)';
NODE_NAME     U2 DL29
 '@S9S_MB_2U_LIB.S9S_MB_2U(SCH_1):PAGE26_I169@PURE_QUANTA.SOCKET4677_AZIF0045P001C01CS(CHIPS)':
 'DDR6_SB_DQ10': CDS_PINID='DDR6_SB_DQ10';
NODE_NAME     J13 256
 '@S9S_MB_2U_LIB.S9S_MB_2U(SCH_1):PAGE94_I11@PURE_QUANTA.SCONN288_ADR50017P130CC(CHIPS)':
 'DQ10_B': CDS_PINID='DQ10_B';
NODE_NAME     J14 256
 '@S9S_MB_2U_LIB.S9S_MB_2U(SCH_1):PAGE95_I47@PURE_QUANTA.SCONN288_ADR50017P087CC(CHIPS)':
 'DQ10_B': CDS_PINID='DQ10_B';
NET_NAME
'M_G_CPU0_SB_DQ<11>'
 '@S9S_MB_2U_LIB.S9S_MB_2U(SCH_1):M_G_CPU0_SB_DQ'<11>:
 C_SIGNAL='@s9s_mb_2u_lib.s9s_mb_2u(sch_1):m_g_cpu0_sb_dq(11)';
NODE_NAME     U2 DP28
 '@S9S_MB_2U_LIB.S9S_MB_2U(SCH_1):PAGE26_I169@PURE_QUANTA.SOCKET4677_AZIF0045P001C01CS(CHIPS)':
 'DDR6_SB_DQ11': CDS_PINID='DDR6_SB_DQ11';
NODE_NAME     J13 258
 '@S9S_MB_2U_LIB.S9S_MB_2U(SCH_1):PAGE94_I11@PURE_QUANTA.SCONN288_ADR50017P130CC(CHIPS)':
 'DQ11_B': CDS_PINID='DQ11_B';
NODE_NAME     J14 258
 '@S9S_MB_2U_LIB.S9S_MB_2U(SCH_1):PAGE95_I47@PURE_QUANTA.SCONN288_ADR50017P087CC(CHIPS)':
 'DQ11_B': CDS_PINID='DQ11_B';
NET_NAME
'M_G_CPU0_SB_DQ<12>'
 '@S9S_MB_2U_LIB.S9S_MB_2U(SCH_1):M_G_CPU0_SB_DQ'<12>:
 C_SIGNAL='@s9s_mb_2u_lib.s9s_mb_2u(sch_1):m_g_cpu0_sb_dq(12)';
NODE_NAME     U2 DK26
 '@S9S_MB_2U_LIB.S9S_MB_2U(SCH_1):PAGE26_I169@PURE_QUANTA.SOCKET4677_AZIF0045P001C01CS(CHIPS)':
 'DDR6_SB_DQ12': CDS_PINID='DDR6_SB_DQ12';
NODE_NAME     J13 118
 '@S9S_MB_2U_LIB.S9S_MB_2U(SCH_1):PAGE94_I11@PURE_QUANTA.SCONN288_ADR50017P130CC(CHIPS)':
 'DQ12_B': CDS_PINID='DQ12_B';
NODE_NAME     J14 118
 '@S9S_MB_2U_LIB.S9S_MB_2U(SCH_1):PAGE95_I47@PURE_QUANTA.SCONN288_ADR50017P087CC(CHIPS)':
 'DQ12_B': CDS_PINID='DQ12_B';
NET_NAME
'M_G_CPU0_SB_DQ<13>'
 '@S9S_MB_2U_LIB.S9S_MB_2U(SCH_1):M_G_CPU0_SB_DQ'<13>:
 C_SIGNAL='@s9s_mb_2u_lib.s9s_mb_2u(sch_1):m_g_cpu0_sb_dq(13)';
NODE_NAME     U2 DL25
 '@S9S_MB_2U_LIB.S9S_MB_2U(SCH_1):PAGE26_I169@PURE_QUANTA.SOCKET4677_AZIF0045P001C01CS(CHIPS)':
 'DDR6_SB_DQ13': CDS_PINID='DDR6_SB_DQ13';
NODE_NAME     J13 120
 '@S9S_MB_2U_LIB.S9S_MB_2U(SCH_1):PAGE94_I11@PURE_QUANTA.SCONN288_ADR50017P130CC(CHIPS)':
 'DQ13_B': CDS_PINID='DQ13_B';
NODE_NAME     J14 120
 '@S9S_MB_2U_LIB.S9S_MB_2U(SCH_1):PAGE95_I47@PURE_QUANTA.SCONN288_ADR50017P087CC(CHIPS)':
 'DQ13_B': CDS_PINID='DQ13_B';
NET_NAME
'M_G_CPU0_SB_DQ<14>'
 '@S9S_MB_2U_LIB.S9S_MB_2U(SCH_1):M_G_CPU0_SB_DQ'<14>:
 C_SIGNAL='@s9s_mb_2u_lib.s9s_mb_2u(sch_1):m_g_cpu0_sb_dq(14)';
NODE_NAME     U2 DP26
 '@S9S_MB_2U_LIB.S9S_MB_2U(SCH_1):PAGE26_I169@PURE_QUANTA.SOCKET4677_AZIF0045P001C01CS(CHIPS)':
 'DDR6_SB_DQ14': CDS_PINID='DDR6_SB_DQ14';
NODE_NAME     J13 263
 '@S9S_MB_2U_LIB.S9S_MB_2U(SCH_1):PAGE94_I11@PURE_QUANTA.SCONN288_ADR50017P130CC(CHIPS)':
 'DQ14_B': CDS_PINID='DQ14_B';
NODE_NAME     J14 263
 '@S9S_MB_2U_LIB.S9S_MB_2U(SCH_1):PAGE95_I47@PURE_QUANTA.SCONN288_ADR50017P087CC(CHIPS)':
 'DQ14_B': CDS_PINID='DQ14_B';
NET_NAME
'M_G_CPU0_SB_DQ<15>'
 '@S9S_MB_2U_LIB.S9S_MB_2U(SCH_1):M_G_CPU0_SB_DQ'<15>:
 C_SIGNAL='@s9s_mb_2u_lib.s9s_mb_2u(sch_1):m_g_cpu0_sb_dq(15)';
NODE_NAME     U2 DN25
 '@S9S_MB_2U_LIB.S9S_MB_2U(SCH_1):PAGE26_I169@PURE_QUANTA.SOCKET4677_AZIF0045P001C01CS(CHIPS)':
 'DDR6_SB_DQ15': CDS_PINID='DDR6_SB_DQ15';
NODE_NAME     J13 265
 '@S9S_MB_2U_LIB.S9S_MB_2U(SCH_1):PAGE94_I11@PURE_QUANTA.SCONN288_ADR50017P130CC(CHIPS)':
 'DQ15_B': CDS_PINID='DQ15_B';
NODE_NAME     J14 265
 '@S9S_MB_2U_LIB.S9S_MB_2U(SCH_1):PAGE95_I47@PURE_QUANTA.SCONN288_ADR50017P087CC(CHIPS)':
 'DQ15_B': CDS_PINID='DQ15_B';
NET_NAME
'M_G_CPU0_SB_DQ<16>'
 '@S9S_MB_2U_LIB.S9S_MB_2U(SCH_1):M_G_CPU0_SB_DQ'<16>:
 C_SIGNAL='@s9s_mb_2u_lib.s9s_mb_2u(sch_1):m_g_cpu0_sb_dq(16)';
NODE_NAME     U2 DV26
 '@S9S_MB_2U_LIB.S9S_MB_2U(SCH_1):PAGE26_I169@PURE_QUANTA.SOCKET4677_AZIF0045P001C01CS(CHIPS)':
 'DDR6_SB_DQ16': CDS_PINID='DDR6_SB_DQ16';
NODE_NAME     J13 122
 '@S9S_MB_2U_LIB.S9S_MB_2U(SCH_1):PAGE94_I11@PURE_QUANTA.SCONN288_ADR50017P130CC(CHIPS)':
 'DQ16_B': CDS_PINID='DQ16_B';
NODE_NAME     J14 122
 '@S9S_MB_2U_LIB.S9S_MB_2U(SCH_1):PAGE95_I47@PURE_QUANTA.SCONN288_ADR50017P087CC(CHIPS)':
 'DQ16_B': CDS_PINID='DQ16_B';
NET_NAME
'M_G_CPU0_SB_DQ<17>'
 '@S9S_MB_2U_LIB.S9S_MB_2U(SCH_1):M_G_CPU0_SB_DQ'<17>:
 C_SIGNAL='@s9s_mb_2u_lib.s9s_mb_2u(sch_1):m_g_cpu0_sb_dq(17)';
NODE_NAME     U2 DU25
 '@S9S_MB_2U_LIB.S9S_MB_2U(SCH_1):PAGE26_I169@PURE_QUANTA.SOCKET4677_AZIF0045P001C01CS(CHIPS)':
 'DDR6_SB_DQ17': CDS_PINID='DDR6_SB_DQ17';
NODE_NAME     J13 124
 '@S9S_MB_2U_LIB.S9S_MB_2U(SCH_1):PAGE94_I11@PURE_QUANTA.SCONN288_ADR50017P130CC(CHIPS)':
 'DQ17_B': CDS_PINID='DQ17_B';
NODE_NAME     J14 124
 '@S9S_MB_2U_LIB.S9S_MB_2U(SCH_1):PAGE95_I47@PURE_QUANTA.SCONN288_ADR50017P087CC(CHIPS)':
 'DQ17_B': CDS_PINID='DQ17_B';
NET_NAME
'M_G_CPU0_SB_DQ<18>'
 '@S9S_MB_2U_LIB.S9S_MB_2U(SCH_1):M_G_CPU0_SB_DQ'<18>:
 C_SIGNAL='@s9s_mb_2u_lib.s9s_mb_2u(sch_1):m_g_cpu0_sb_dq(18)';
NODE_NAME     U2 DY26
 '@S9S_MB_2U_LIB.S9S_MB_2U(SCH_1):PAGE26_I169@PURE_QUANTA.SOCKET4677_AZIF0045P001C01CS(CHIPS)':
 'DDR6_SB_DQ18': CDS_PINID='DDR6_SB_DQ18';
NODE_NAME     J13 267
 '@S9S_MB_2U_LIB.S9S_MB_2U(SCH_1):PAGE94_I11@PURE_QUANTA.SCONN288_ADR50017P130CC(CHIPS)':
 'DQ18_B': CDS_PINID='DQ18_B';
NODE_NAME     J14 267
 '@S9S_MB_2U_LIB.S9S_MB_2U(SCH_1):PAGE95_I47@PURE_QUANTA.SCONN288_ADR50017P087CC(CHIPS)':
 'DQ18_B': CDS_PINID='DQ18_B';
NET_NAME
'M_G_CPU0_SB_DQ<19>'
 '@S9S_MB_2U_LIB.S9S_MB_2U(SCH_1):M_G_CPU0_SB_DQ'<19>:
 C_SIGNAL='@s9s_mb_2u_lib.s9s_mb_2u(sch_1):m_g_cpu0_sb_dq(19)';
NODE_NAME     U2 EA25
 '@S9S_MB_2U_LIB.S9S_MB_2U(SCH_1):PAGE26_I169@PURE_QUANTA.SOCKET4677_AZIF0045P001C01CS(CHIPS)':
 'DDR6_SB_DQ19': CDS_PINID='DDR6_SB_DQ19';
NODE_NAME     J13 269
 '@S9S_MB_2U_LIB.S9S_MB_2U(SCH_1):PAGE94_I11@PURE_QUANTA.SCONN288_ADR50017P130CC(CHIPS)':
 'DQ19_B': CDS_PINID='DQ19_B';
NODE_NAME     J14 269
 '@S9S_MB_2U_LIB.S9S_MB_2U(SCH_1):PAGE95_I47@PURE_QUANTA.SCONN288_ADR50017P087CC(CHIPS)':
 'DQ19_B': CDS_PINID='DQ19_B';
NET_NAME
'M_G_CPU0_SB_DQ<1>'
 '@S9S_MB_2U_LIB.S9S_MB_2U(SCH_1):M_G_CPU0_SB_DQ'<1>:
 C_SIGNAL='@s9s_mb_2u_lib.s9s_mb_2u(sch_1):m_g_cpu0_sb_dq(1)';
NODE_NAME     U2 DK34
 '@S9S_MB_2U_LIB.S9S_MB_2U(SCH_1):PAGE26_I169@PURE_QUANTA.SOCKET4677_AZIF0045P001C01CS(CHIPS)':
 'DDR6_SB_DQ1': CDS_PINID='DDR6_SB_DQ1';
NODE_NAME     J13 102
 '@S9S_MB_2U_LIB.S9S_MB_2U(SCH_1):PAGE94_I11@PURE_QUANTA.SCONN288_ADR50017P130CC(CHIPS)':
 'DQ1_B': CDS_PINID='DQ1_B';
NODE_NAME     J14 102
 '@S9S_MB_2U_LIB.S9S_MB_2U(SCH_1):PAGE95_I47@PURE_QUANTA.SCONN288_ADR50017P087CC(CHIPS)':
 'DQ1_B': CDS_PINID='DQ1_B';
NET_NAME
'M_G_CPU0_SB_DQ<20>'
 '@S9S_MB_2U_LIB.S9S_MB_2U(SCH_1):M_G_CPU0_SB_DQ'<20>:
 C_SIGNAL='@s9s_mb_2u_lib.s9s_mb_2u(sch_1):m_g_cpu0_sb_dq(20)';
NODE_NAME     U2 DU23
 '@S9S_MB_2U_LIB.S9S_MB_2U(SCH_1):PAGE26_I169@PURE_QUANTA.SOCKET4677_AZIF0045P001C01CS(CHIPS)':
 'DDR6_SB_DQ20': CDS_PINID='DDR6_SB_DQ20';
NODE_NAME     J13 129
 '@S9S_MB_2U_LIB.S9S_MB_2U(SCH_1):PAGE94_I11@PURE_QUANTA.SCONN288_ADR50017P130CC(CHIPS)':
 'DQ20_B': CDS_PINID='DQ20_B';
NODE_NAME     J14 129
 '@S9S_MB_2U_LIB.S9S_MB_2U(SCH_1):PAGE95_I47@PURE_QUANTA.SCONN288_ADR50017P087CC(CHIPS)':
 'DQ20_B': CDS_PINID='DQ20_B';
NET_NAME
'M_G_CPU0_SB_DQ<21>'
 '@S9S_MB_2U_LIB.S9S_MB_2U(SCH_1):M_G_CPU0_SB_DQ'<21>:
 C_SIGNAL='@s9s_mb_2u_lib.s9s_mb_2u(sch_1):m_g_cpu0_sb_dq(21)';
NODE_NAME     U2 DV22
 '@S9S_MB_2U_LIB.S9S_MB_2U(SCH_1):PAGE26_I169@PURE_QUANTA.SOCKET4677_AZIF0045P001C01CS(CHIPS)':
 'DDR6_SB_DQ21': CDS_PINID='DDR6_SB_DQ21';
NODE_NAME     J13 131
 '@S9S_MB_2U_LIB.S9S_MB_2U(SCH_1):PAGE94_I11@PURE_QUANTA.SCONN288_ADR50017P130CC(CHIPS)':
 'DQ21_B': CDS_PINID='DQ21_B';
NODE_NAME     J14 131
 '@S9S_MB_2U_LIB.S9S_MB_2U(SCH_1):PAGE95_I47@PURE_QUANTA.SCONN288_ADR50017P087CC(CHIPS)':
 'DQ21_B': CDS_PINID='DQ21_B';
NET_NAME
'M_G_CPU0_SB_DQ<22>'
 '@S9S_MB_2U_LIB.S9S_MB_2U(SCH_1):M_G_CPU0_SB_DQ'<22>:
 C_SIGNAL='@s9s_mb_2u_lib.s9s_mb_2u(sch_1):m_g_cpu0_sb_dq(22)';
NODE_NAME     U2 EA23
 '@S9S_MB_2U_LIB.S9S_MB_2U(SCH_1):PAGE26_I169@PURE_QUANTA.SOCKET4677_AZIF0045P001C01CS(CHIPS)':
 'DDR6_SB_DQ22': CDS_PINID='DDR6_SB_DQ22';
NODE_NAME     J13 274
 '@S9S_MB_2U_LIB.S9S_MB_2U(SCH_1):PAGE94_I11@PURE_QUANTA.SCONN288_ADR50017P130CC(CHIPS)':
 'DQ22_B': CDS_PINID='DQ22_B';
NODE_NAME     J14 274
 '@S9S_MB_2U_LIB.S9S_MB_2U(SCH_1):PAGE95_I47@PURE_QUANTA.SCONN288_ADR50017P087CC(CHIPS)':
 'DQ22_B': CDS_PINID='DQ22_B';
NET_NAME
'M_G_CPU0_SB_DQ<23>'
 '@S9S_MB_2U_LIB.S9S_MB_2U(SCH_1):M_G_CPU0_SB_DQ'<23>:
 C_SIGNAL='@s9s_mb_2u_lib.s9s_mb_2u(sch_1):m_g_cpu0_sb_dq(23)';
NODE_NAME     U2 DY22
 '@S9S_MB_2U_LIB.S9S_MB_2U(SCH_1):PAGE26_I169@PURE_QUANTA.SOCKET4677_AZIF0045P001C01CS(CHIPS)':
 'DDR6_SB_DQ23': CDS_PINID='DDR6_SB_DQ23';
NODE_NAME     J13 276
 '@S9S_MB_2U_LIB.S9S_MB_2U(SCH_1):PAGE94_I11@PURE_QUANTA.SCONN288_ADR50017P130CC(CHIPS)':
 'DQ23_B': CDS_PINID='DQ23_B';
NODE_NAME     J14 276
 '@S9S_MB_2U_LIB.S9S_MB_2U(SCH_1):PAGE95_I47@PURE_QUANTA.SCONN288_ADR50017P087CC(CHIPS)':
 'DQ23_B': CDS_PINID='DQ23_B';
NET_NAME
'M_G_CPU0_SB_DQ<24>'
 '@S9S_MB_2U_LIB.S9S_MB_2U(SCH_1):M_G_CPU0_SB_DQ'<24>:
 C_SIGNAL='@s9s_mb_2u_lib.s9s_mb_2u(sch_1):m_g_cpu0_sb_dq(24)';
NODE_NAME     U2 EK8
 '@S9S_MB_2U_LIB.S9S_MB_2U(SCH_1):PAGE26_I169@PURE_QUANTA.SOCKET4677_AZIF0045P001C01CS(CHIPS)':
 'DDR6_SB_DQ24': CDS_PINID='DDR6_SB_DQ24';
NODE_NAME     J13 133
 '@S9S_MB_2U_LIB.S9S_MB_2U(SCH_1):PAGE94_I11@PURE_QUANTA.SCONN288_ADR50017P130CC(CHIPS)':
 'DQ24_B': CDS_PINID='DQ24_B';
NODE_NAME     J14 133
 '@S9S_MB_2U_LIB.S9S_MB_2U(SCH_1):PAGE95_I47@PURE_QUANTA.SCONN288_ADR50017P087CC(CHIPS)':
 'DQ24_B': CDS_PINID='DQ24_B';
NET_NAME
'M_G_CPU0_SB_DQ<25>'
 '@S9S_MB_2U_LIB.S9S_MB_2U(SCH_1):M_G_CPU0_SB_DQ'<25>:
 C_SIGNAL='@s9s_mb_2u_lib.s9s_mb_2u(sch_1):m_g_cpu0_sb_dq(25)';
NODE_NAME     U2 EH8
 '@S9S_MB_2U_LIB.S9S_MB_2U(SCH_1):PAGE26_I169@PURE_QUANTA.SOCKET4677_AZIF0045P001C01CS(CHIPS)':
 'DDR6_SB_DQ25': CDS_PINID='DDR6_SB_DQ25';
NODE_NAME     J13 135
 '@S9S_MB_2U_LIB.S9S_MB_2U(SCH_1):PAGE94_I11@PURE_QUANTA.SCONN288_ADR50017P130CC(CHIPS)':
 'DQ25_B': CDS_PINID='DQ25_B';
NODE_NAME     J14 135
 '@S9S_MB_2U_LIB.S9S_MB_2U(SCH_1):PAGE95_I47@PURE_QUANTA.SCONN288_ADR50017P087CC(CHIPS)':
 'DQ25_B': CDS_PINID='DQ25_B';
NET_NAME
'M_G_CPU0_SB_DQ<26>'
 '@S9S_MB_2U_LIB.S9S_MB_2U(SCH_1):M_G_CPU0_SB_DQ'<26>:
 C_SIGNAL='@s9s_mb_2u_lib.s9s_mb_2u(sch_1):m_g_cpu0_sb_dq(26)';
NODE_NAME     U2 EP8
 '@S9S_MB_2U_LIB.S9S_MB_2U(SCH_1):PAGE26_I169@PURE_QUANTA.SOCKET4677_AZIF0045P001C01CS(CHIPS)':
 'DDR6_SB_DQ26': CDS_PINID='DDR6_SB_DQ26';
NODE_NAME     J13 278
 '@S9S_MB_2U_LIB.S9S_MB_2U(SCH_1):PAGE94_I11@PURE_QUANTA.SCONN288_ADR50017P130CC(CHIPS)':
 'DQ26_B': CDS_PINID='DQ26_B';
NODE_NAME     J14 278
 '@S9S_MB_2U_LIB.S9S_MB_2U(SCH_1):PAGE95_I47@PURE_QUANTA.SCONN288_ADR50017P087CC(CHIPS)':
 'DQ26_B': CDS_PINID='DQ26_B';
NET_NAME
'M_G_CPU0_SB_DQ<27>'
 '@S9S_MB_2U_LIB.S9S_MB_2U(SCH_1):M_G_CPU0_SB_DQ'<27>:
 C_SIGNAL='@s9s_mb_2u_lib.s9s_mb_2u(sch_1):m_g_cpu0_sb_dq(27)';
NODE_NAME     U2 ET8
 '@S9S_MB_2U_LIB.S9S_MB_2U(SCH_1):PAGE26_I169@PURE_QUANTA.SOCKET4677_AZIF0045P001C01CS(CHIPS)':
 'DDR6_SB_DQ27': CDS_PINID='DDR6_SB_DQ27';
NODE_NAME     J13 280
 '@S9S_MB_2U_LIB.S9S_MB_2U(SCH_1):PAGE94_I11@PURE_QUANTA.SCONN288_ADR50017P130CC(CHIPS)':
 'DQ27_B': CDS_PINID='DQ27_B';
NODE_NAME     J14 280
 '@S9S_MB_2U_LIB.S9S_MB_2U(SCH_1):PAGE95_I47@PURE_QUANTA.SCONN288_ADR50017P087CC(CHIPS)':
 'DQ27_B': CDS_PINID='DQ27_B';
NET_NAME
'M_G_CPU0_SB_DQ<28>'
 '@S9S_MB_2U_LIB.S9S_MB_2U(SCH_1):M_G_CPU0_SB_DQ'<28>:
 C_SIGNAL='@s9s_mb_2u_lib.s9s_mb_2u(sch_1):m_g_cpu0_sb_dq(28)';
NODE_NAME     U2 EK6
 '@S9S_MB_2U_LIB.S9S_MB_2U(SCH_1):PAGE26_I169@PURE_QUANTA.SOCKET4677_AZIF0045P001C01CS(CHIPS)':
 'DDR6_SB_DQ28': CDS_PINID='DDR6_SB_DQ28';
NODE_NAME     J13 140
 '@S9S_MB_2U_LIB.S9S_MB_2U(SCH_1):PAGE94_I11@PURE_QUANTA.SCONN288_ADR50017P130CC(CHIPS)':
 'DQ28_B': CDS_PINID='DQ28_B';
NODE_NAME     J14 140
 '@S9S_MB_2U_LIB.S9S_MB_2U(SCH_1):PAGE95_I47@PURE_QUANTA.SCONN288_ADR50017P087CC(CHIPS)':
 'DQ28_B': CDS_PINID='DQ28_B';
NET_NAME
'M_G_CPU0_SB_DQ<29>'
 '@S9S_MB_2U_LIB.S9S_MB_2U(SCH_1):M_G_CPU0_SB_DQ'<29>:
 C_SIGNAL='@s9s_mb_2u_lib.s9s_mb_2u(sch_1):m_g_cpu0_sb_dq(29)';
NODE_NAME     U2 EJ5
 '@S9S_MB_2U_LIB.S9S_MB_2U(SCH_1):PAGE26_I169@PURE_QUANTA.SOCKET4677_AZIF0045P001C01CS(CHIPS)':
 'DDR6_SB_DQ29': CDS_PINID='DDR6_SB_DQ29';
NODE_NAME     J13 142
 '@S9S_MB_2U_LIB.S9S_MB_2U(SCH_1):PAGE94_I11@PURE_QUANTA.SCONN288_ADR50017P130CC(CHIPS)':
 'DQ29_B': CDS_PINID='DQ29_B';
NODE_NAME     J14 142
 '@S9S_MB_2U_LIB.S9S_MB_2U(SCH_1):PAGE95_I47@PURE_QUANTA.SCONN288_ADR50017P087CC(CHIPS)':
 'DQ29_B': CDS_PINID='DQ29_B';
NET_NAME
'M_G_CPU0_SB_DQ<2>'
 '@S9S_MB_2U_LIB.S9S_MB_2U(SCH_1):M_G_CPU0_SB_DQ'<2>:
 C_SIGNAL='@s9s_mb_2u_lib.s9s_mb_2u(sch_1):m_g_cpu0_sb_dq(2)';
NODE_NAME     U2 DN35
 '@S9S_MB_2U_LIB.S9S_MB_2U(SCH_1):PAGE26_I169@PURE_QUANTA.SOCKET4677_AZIF0045P001C01CS(CHIPS)':
 'DDR6_SB_DQ2': CDS_PINID='DDR6_SB_DQ2';
NODE_NAME     J13 245
 '@S9S_MB_2U_LIB.S9S_MB_2U(SCH_1):PAGE94_I11@PURE_QUANTA.SCONN288_ADR50017P130CC(CHIPS)':
 'DQ2_B': CDS_PINID='DQ2_B';
NODE_NAME     J14 245
 '@S9S_MB_2U_LIB.S9S_MB_2U(SCH_1):PAGE95_I47@PURE_QUANTA.SCONN288_ADR50017P087CC(CHIPS)':
 'DQ2_B': CDS_PINID='DQ2_B';
NET_NAME
'M_G_CPU0_SB_DQ<30>'
 '@S9S_MB_2U_LIB.S9S_MB_2U(SCH_1):M_G_CPU0_SB_DQ'<30>:
 C_SIGNAL='@s9s_mb_2u_lib.s9s_mb_2u(sch_1):m_g_cpu0_sb_dq(30)';
NODE_NAME     U2 EP4
 '@S9S_MB_2U_LIB.S9S_MB_2U(SCH_1):PAGE26_I169@PURE_QUANTA.SOCKET4677_AZIF0045P001C01CS(CHIPS)':
 'DDR6_SB_DQ30': CDS_PINID='DDR6_SB_DQ30';
NODE_NAME     J13 285
 '@S9S_MB_2U_LIB.S9S_MB_2U(SCH_1):PAGE94_I11@PURE_QUANTA.SCONN288_ADR50017P130CC(CHIPS)':
 'DQ30_B': CDS_PINID='DQ30_B';
NODE_NAME     J14 285
 '@S9S_MB_2U_LIB.S9S_MB_2U(SCH_1):PAGE95_I47@PURE_QUANTA.SCONN288_ADR50017P087CC(CHIPS)':
 'DQ30_B': CDS_PINID='DQ30_B';
NET_NAME
'M_G_CPU0_SB_DQ<31>'
 '@S9S_MB_2U_LIB.S9S_MB_2U(SCH_1):M_G_CPU0_SB_DQ'<31>:
 C_SIGNAL='@s9s_mb_2u_lib.s9s_mb_2u(sch_1):m_g_cpu0_sb_dq(31)';
NODE_NAME     U2 EM4
 '@S9S_MB_2U_LIB.S9S_MB_2U(SCH_1):PAGE26_I169@PURE_QUANTA.SOCKET4677_AZIF0045P001C01CS(CHIPS)':
 'DDR6_SB_DQ31': CDS_PINID='DDR6_SB_DQ31';
NODE_NAME     J13 287
 '@S9S_MB_2U_LIB.S9S_MB_2U(SCH_1):PAGE94_I11@PURE_QUANTA.SCONN288_ADR50017P130CC(CHIPS)':
 'DQ31_B': CDS_PINID='DQ31_B';
NODE_NAME     J14 287
 '@S9S_MB_2U_LIB.S9S_MB_2U(SCH_1):PAGE95_I47@PURE_QUANTA.SCONN288_ADR50017P087CC(CHIPS)':
 'DQ31_B': CDS_PINID='DQ31_B';
NET_NAME
'M_G_CPU0_SB_DQ<3>'
 '@S9S_MB_2U_LIB.S9S_MB_2U(SCH_1):M_G_CPU0_SB_DQ'<3>:
 C_SIGNAL='@s9s_mb_2u_lib.s9s_mb_2u(sch_1):m_g_cpu0_sb_dq(3)';
NODE_NAME     U2 DP34
 '@S9S_MB_2U_LIB.S9S_MB_2U(SCH_1):PAGE26_I169@PURE_QUANTA.SOCKET4677_AZIF0045P001C01CS(CHIPS)':
 'DDR6_SB_DQ3': CDS_PINID='DDR6_SB_DQ3';
NODE_NAME     J13 247
 '@S9S_MB_2U_LIB.S9S_MB_2U(SCH_1):PAGE94_I11@PURE_QUANTA.SCONN288_ADR50017P130CC(CHIPS)':
 'DQ3_B': CDS_PINID='DQ3_B';
NODE_NAME     J14 247
 '@S9S_MB_2U_LIB.S9S_MB_2U(SCH_1):PAGE95_I47@PURE_QUANTA.SCONN288_ADR50017P087CC(CHIPS)':
 'DQ3_B': CDS_PINID='DQ3_B';
NET_NAME
'M_G_CPU0_SB_DQ<4>'
 '@S9S_MB_2U_LIB.S9S_MB_2U(SCH_1):M_G_CPU0_SB_DQ'<4>:
 C_SIGNAL='@s9s_mb_2u_lib.s9s_mb_2u(sch_1):m_g_cpu0_sb_dq(4)';
NODE_NAME     U2 DK32
 '@S9S_MB_2U_LIB.S9S_MB_2U(SCH_1):PAGE26_I169@PURE_QUANTA.SOCKET4677_AZIF0045P001C01CS(CHIPS)':
 'DDR6_SB_DQ4': CDS_PINID='DDR6_SB_DQ4';
NODE_NAME     J13 107
 '@S9S_MB_2U_LIB.S9S_MB_2U(SCH_1):PAGE94_I11@PURE_QUANTA.SCONN288_ADR50017P130CC(CHIPS)':
 'DQ4_B': CDS_PINID='DQ4_B';
NODE_NAME     J14 107
 '@S9S_MB_2U_LIB.S9S_MB_2U(SCH_1):PAGE95_I47@PURE_QUANTA.SCONN288_ADR50017P087CC(CHIPS)':
 'DQ4_B': CDS_PINID='DQ4_B';
NET_NAME
'M_G_CPU0_SB_DQ<5>'
 '@S9S_MB_2U_LIB.S9S_MB_2U(SCH_1):M_G_CPU0_SB_DQ'<5>:
 C_SIGNAL='@s9s_mb_2u_lib.s9s_mb_2u(sch_1):m_g_cpu0_sb_dq(5)';
NODE_NAME     U2 DL31
 '@S9S_MB_2U_LIB.S9S_MB_2U(SCH_1):PAGE26_I169@PURE_QUANTA.SOCKET4677_AZIF0045P001C01CS(CHIPS)':
 'DDR6_SB_DQ5': CDS_PINID='DDR6_SB_DQ5';
NODE_NAME     J13 109
 '@S9S_MB_2U_LIB.S9S_MB_2U(SCH_1):PAGE94_I11@PURE_QUANTA.SCONN288_ADR50017P130CC(CHIPS)':
 'DQ5_B': CDS_PINID='DQ5_B';
NODE_NAME     J14 109
 '@S9S_MB_2U_LIB.S9S_MB_2U(SCH_1):PAGE95_I47@PURE_QUANTA.SCONN288_ADR50017P087CC(CHIPS)':
 'DQ5_B': CDS_PINID='DQ5_B';
NET_NAME
'M_G_CPU0_SB_DQ<6>'
 '@S9S_MB_2U_LIB.S9S_MB_2U(SCH_1):M_G_CPU0_SB_DQ'<6>:
 C_SIGNAL='@s9s_mb_2u_lib.s9s_mb_2u(sch_1):m_g_cpu0_sb_dq(6)';
NODE_NAME     U2 DP32
 '@S9S_MB_2U_LIB.S9S_MB_2U(SCH_1):PAGE26_I169@PURE_QUANTA.SOCKET4677_AZIF0045P001C01CS(CHIPS)':
 'DDR6_SB_DQ6': CDS_PINID='DDR6_SB_DQ6';
NODE_NAME     J13 252
 '@S9S_MB_2U_LIB.S9S_MB_2U(SCH_1):PAGE94_I11@PURE_QUANTA.SCONN288_ADR50017P130CC(CHIPS)':
 'DQ6_B': CDS_PINID='DQ6_B';
NODE_NAME     J14 252
 '@S9S_MB_2U_LIB.S9S_MB_2U(SCH_1):PAGE95_I47@PURE_QUANTA.SCONN288_ADR50017P087CC(CHIPS)':
 'DQ6_B': CDS_PINID='DQ6_B';
NET_NAME
'M_G_CPU0_SB_DQ<7>'
 '@S9S_MB_2U_LIB.S9S_MB_2U(SCH_1):M_G_CPU0_SB_DQ'<7>:
 C_SIGNAL='@s9s_mb_2u_lib.s9s_mb_2u(sch_1):m_g_cpu0_sb_dq(7)';
NODE_NAME     U2 DN31
 '@S9S_MB_2U_LIB.S9S_MB_2U(SCH_1):PAGE26_I169@PURE_QUANTA.SOCKET4677_AZIF0045P001C01CS(CHIPS)':
 'DDR6_SB_DQ7': CDS_PINID='DDR6_SB_DQ7';
NODE_NAME     J13 254
 '@S9S_MB_2U_LIB.S9S_MB_2U(SCH_1):PAGE94_I11@PURE_QUANTA.SCONN288_ADR50017P130CC(CHIPS)':
 'DQ7_B': CDS_PINID='DQ7_B';
NODE_NAME     J14 254
 '@S9S_MB_2U_LIB.S9S_MB_2U(SCH_1):PAGE95_I47@PURE_QUANTA.SCONN288_ADR50017P087CC(CHIPS)':
 'DQ7_B': CDS_PINID='DQ7_B';
NET_NAME
'M_G_CPU0_SB_DQ<8>'
 '@S9S_MB_2U_LIB.S9S_MB_2U(SCH_1):M_G_CPU0_SB_DQ'<8>:
 C_SIGNAL='@s9s_mb_2u_lib.s9s_mb_2u(sch_1):m_g_cpu0_sb_dq(8)';
NODE_NAME     U2 DN29
 '@S9S_MB_2U_LIB.S9S_MB_2U(SCH_1):PAGE26_I169@PURE_QUANTA.SOCKET4677_AZIF0045P001C01CS(CHIPS)':
 'DDR6_SB_DQ8': CDS_PINID='DDR6_SB_DQ8';
NODE_NAME     J13 111
 '@S9S_MB_2U_LIB.S9S_MB_2U(SCH_1):PAGE94_I11@PURE_QUANTA.SCONN288_ADR50017P130CC(CHIPS)':
 'DQ8_B': CDS_PINID='DQ8_B';
NODE_NAME     J14 111
 '@S9S_MB_2U_LIB.S9S_MB_2U(SCH_1):PAGE95_I47@PURE_QUANTA.SCONN288_ADR50017P087CC(CHIPS)':
 'DQ8_B': CDS_PINID='DQ8_B';
NET_NAME
'M_G_CPU0_SB_DQ<9>'
 '@S9S_MB_2U_LIB.S9S_MB_2U(SCH_1):M_G_CPU0_SB_DQ'<9>:
 C_SIGNAL='@s9s_mb_2u_lib.s9s_mb_2u(sch_1):m_g_cpu0_sb_dq(9)';
NODE_NAME     U2 DK28
 '@S9S_MB_2U_LIB.S9S_MB_2U(SCH_1):PAGE26_I169@PURE_QUANTA.SOCKET4677_AZIF0045P001C01CS(CHIPS)':
 'DDR6_SB_DQ9': CDS_PINID='DDR6_SB_DQ9';
NODE_NAME     J13 113
 '@S9S_MB_2U_LIB.S9S_MB_2U(SCH_1):PAGE94_I11@PURE_QUANTA.SCONN288_ADR50017P130CC(CHIPS)':
 'DQ9_B': CDS_PINID='DQ9_B';
NODE_NAME     J14 113
 '@S9S_MB_2U_LIB.S9S_MB_2U(SCH_1):PAGE95_I47@PURE_QUANTA.SCONN288_ADR50017P087CC(CHIPS)':
 'DQ9_B': CDS_PINID='DQ9_B';
NET_NAME
'M_G_CPU0_SB_DQS_DN<0>'
 '@S9S_MB_2U_LIB.S9S_MB_2U(SCH_1):M_G_CPU0_SB_DQS_DN'<0>:
 C_SIGNAL='@s9s_mb_2u_lib.s9s_mb_2u(sch_1):m_g_cpu0_sb_dqs_dn(0)';
NODE_NAME     U2 DJ33
 '@S9S_MB_2U_LIB.S9S_MB_2U(SCH_1):PAGE26_I169@PURE_QUANTA.SOCKET4677_AZIF0045P001C01CS(CHIPS)':
 'DDR6_SB_DQS_DN0': CDS_PINID='DDR6_SB_DQS_DN0';
NODE_NAME     J13 105
 '@S9S_MB_2U_LIB.S9S_MB_2U(SCH_1):PAGE94_I178@PURE_QUANTA.SCONN288_ADR50017P130CC(CHIPS)':
 'DQS0_B_C': CDS_PINID='DQS0_B_C';
NODE_NAME     J14 105
 '@S9S_MB_2U_LIB.S9S_MB_2U(SCH_1):PAGE95_I178@PURE_QUANTA.SCONN288_ADR50017P087CC(CHIPS)':
 'DQS0_B_C': CDS_PINID='DQS0_B_C';
NET_NAME
'M_G_CPU0_SB_DQS_DN<1>'
 '@S9S_MB_2U_LIB.S9S_MB_2U(SCH_1):M_G_CPU0_SB_DQS_DN'<1>:
 C_SIGNAL='@s9s_mb_2u_lib.s9s_mb_2u(sch_1):m_g_cpu0_sb_dqs_dn(1)';
NODE_NAME     U2 DJ27
 '@S9S_MB_2U_LIB.S9S_MB_2U(SCH_1):PAGE26_I169@PURE_QUANTA.SOCKET4677_AZIF0045P001C01CS(CHIPS)':
 'DDR6_SB_DQS_DN1': CDS_PINID='DDR6_SB_DQS_DN1';
NODE_NAME     J13 116
 '@S9S_MB_2U_LIB.S9S_MB_2U(SCH_1):PAGE94_I178@PURE_QUANTA.SCONN288_ADR50017P130CC(CHIPS)':
 'DQS1_B_C': CDS_PINID='DQS1_B_C';
NODE_NAME     J14 116
 '@S9S_MB_2U_LIB.S9S_MB_2U(SCH_1):PAGE95_I178@PURE_QUANTA.SCONN288_ADR50017P087CC(CHIPS)':
 'DQS1_B_C': CDS_PINID='DQS1_B_C';
NET_NAME
'M_G_CPU0_SB_DQS_DN<2>'
 '@S9S_MB_2U_LIB.S9S_MB_2U(SCH_1):M_G_CPU0_SB_DQS_DN'<2>:
 C_SIGNAL='@s9s_mb_2u_lib.s9s_mb_2u(sch_1):m_g_cpu0_sb_dqs_dn(2)';
NODE_NAME     U2 DV24
 '@S9S_MB_2U_LIB.S9S_MB_2U(SCH_1):PAGE26_I169@PURE_QUANTA.SOCKET4677_AZIF0045P001C01CS(CHIPS)':
 'DDR6_SB_DQS_DN2': CDS_PINID='DDR6_SB_DQS_DN2';
NODE_NAME     J13 127
 '@S9S_MB_2U_LIB.S9S_MB_2U(SCH_1):PAGE94_I178@PURE_QUANTA.SCONN288_ADR50017P130CC(CHIPS)':
 'DQS2_B_C': CDS_PINID='DQS2_B_C';
NODE_NAME     J14 127
 '@S9S_MB_2U_LIB.S9S_MB_2U(SCH_1):PAGE95_I178@PURE_QUANTA.SCONN288_ADR50017P087CC(CHIPS)':
 'DQS2_B_C': CDS_PINID='DQS2_B_C';
NET_NAME
'M_G_CPU0_SB_DQS_DN<3>'
 '@S9S_MB_2U_LIB.S9S_MB_2U(SCH_1):M_G_CPU0_SB_DQS_DN'<3>:
 C_SIGNAL='@s9s_mb_2u_lib.s9s_mb_2u(sch_1):m_g_cpu0_sb_dqs_dn(3)';
NODE_NAME     U2 EP6
 '@S9S_MB_2U_LIB.S9S_MB_2U(SCH_1):PAGE26_I169@PURE_QUANTA.SOCKET4677_AZIF0045P001C01CS(CHIPS)':
 'DDR6_SB_DQS_DN3': CDS_PINID='DDR6_SB_DQS_DN3';
NODE_NAME     J13 138
 '@S9S_MB_2U_LIB.S9S_MB_2U(SCH_1):PAGE94_I178@PURE_QUANTA.SCONN288_ADR50017P130CC(CHIPS)':
 'DQS3_B_C': CDS_PINID='DQS3_B_C';
NODE_NAME     J14 138
 '@S9S_MB_2U_LIB.S9S_MB_2U(SCH_1):PAGE95_I178@PURE_QUANTA.SCONN288_ADR50017P087CC(CHIPS)':
 'DQS3_B_C': CDS_PINID='DQS3_B_C';
NET_NAME
'M_G_CPU0_SB_DQS_DN<4>'
 '@S9S_MB_2U_LIB.S9S_MB_2U(SCH_1):M_G_CPU0_SB_DQS_DN'<4>:
 C_SIGNAL='@s9s_mb_2u_lib.s9s_mb_2u(sch_1):m_g_cpu0_sb_dqs_dn(4)';
NODE_NAME     U2 EB36
 '@S9S_MB_2U_LIB.S9S_MB_2U(SCH_1):PAGE26_I169@PURE_QUANTA.SOCKET4677_AZIF0045P001C01CS(CHIPS)':
 'DDR6_SB_DQS_DN4': CDS_PINID='DDR6_SB_DQS_DN4';
NODE_NAME     J13 238
 '@S9S_MB_2U_LIB.S9S_MB_2U(SCH_1):PAGE94_I178@PURE_QUANTA.SCONN288_ADR50017P130CC(CHIPS)':
 'DQS4_B_C': CDS_PINID='DQS4_B_C';
NODE_NAME     J14 238
 '@S9S_MB_2U_LIB.S9S_MB_2U(SCH_1):PAGE95_I178@PURE_QUANTA.SCONN288_ADR50017P087CC(CHIPS)':
 'DQS4_B_C': CDS_PINID='DQS4_B_C';
NET_NAME
'M_G_CPU0_SB_DQS_DN<5>'
 '@S9S_MB_2U_LIB.S9S_MB_2U(SCH_1):M_G_CPU0_SB_DQS_DN'<5>:
 C_SIGNAL='@s9s_mb_2u_lib.s9s_mb_2u(sch_1):m_g_cpu0_sb_dqs_dn(5)';
NODE_NAME     U2 DR33
 '@S9S_MB_2U_LIB.S9S_MB_2U(SCH_1):PAGE26_I169@PURE_QUANTA.SOCKET4677_AZIF0045P001C01CS(CHIPS)':
 'DDR6_SB_DQS_DN5': CDS_PINID='DDR6_SB_DQS_DN5';
NODE_NAME     J13 249
 '@S9S_MB_2U_LIB.S9S_MB_2U(SCH_1):PAGE94_I178@PURE_QUANTA.SCONN288_ADR50017P130CC(CHIPS)':
 'DQS5_B_C||TDQS5_B_C': CDS_PINID='\dqs5_b_c||tdqs5_b_c\';
NODE_NAME     J14 249
 '@S9S_MB_2U_LIB.S9S_MB_2U(SCH_1):PAGE95_I178@PURE_QUANTA.SCONN288_ADR50017P087CC(CHIPS)':
 'DQS5_B_C||TDQS5_B_C': CDS_PINID='\dqs5_b_c||tdqs5_b_c\';
NET_NAME
'M_G_CPU0_SB_DQS_DN<6>'
 '@S9S_MB_2U_LIB.S9S_MB_2U(SCH_1):M_G_CPU0_SB_DQS_DN'<6>:
 C_SIGNAL='@s9s_mb_2u_lib.s9s_mb_2u(sch_1):m_g_cpu0_sb_dqs_dn(6)';
NODE_NAME     U2 DN27
 '@S9S_MB_2U_LIB.S9S_MB_2U(SCH_1):PAGE26_I169@PURE_QUANTA.SOCKET4677_AZIF0045P001C01CS(CHIPS)':
 'DDR6_SB_DQS_DN6': CDS_PINID='DDR6_SB_DQS_DN6';
NODE_NAME     J13 260
 '@S9S_MB_2U_LIB.S9S_MB_2U(SCH_1):PAGE94_I178@PURE_QUANTA.SCONN288_ADR50017P130CC(CHIPS)':
 'DQS6_B_C||TDQS6_B_C': CDS_PINID='\dqs6_b_c||tdqs6_b_c\';
NODE_NAME     J14 260
 '@S9S_MB_2U_LIB.S9S_MB_2U(SCH_1):PAGE95_I178@PURE_QUANTA.SCONN288_ADR50017P087CC(CHIPS)':
 'DQS6_B_C||TDQS6_B_C': CDS_PINID='\dqs6_b_c||tdqs6_b_c\';
NET_NAME
'M_G_CPU0_SB_DQS_DN<7>'
 '@S9S_MB_2U_LIB.S9S_MB_2U(SCH_1):M_G_CPU0_SB_DQS_DN'<7>:
 C_SIGNAL='@s9s_mb_2u_lib.s9s_mb_2u(sch_1):m_g_cpu0_sb_dqs_dn(7)';
NODE_NAME     U2 EB24
 '@S9S_MB_2U_LIB.S9S_MB_2U(SCH_1):PAGE26_I169@PURE_QUANTA.SOCKET4677_AZIF0045P001C01CS(CHIPS)':
 'DDR6_SB_DQS_DN7': CDS_PINID='DDR6_SB_DQS_DN7';
NODE_NAME     J13 271
 '@S9S_MB_2U_LIB.S9S_MB_2U(SCH_1):PAGE94_I178@PURE_QUANTA.SCONN288_ADR50017P130CC(CHIPS)':
 'DQS7_B_C||TDQS7_B_C': CDS_PINID='\dqs7_b_c||tdqs7_b_c\';
NODE_NAME     J14 271
 '@S9S_MB_2U_LIB.S9S_MB_2U(SCH_1):PAGE95_I178@PURE_QUANTA.SCONN288_ADR50017P087CC(CHIPS)':
 'DQS7_B_C||TDQS7_B_C': CDS_PINID='\dqs7_b_c||tdqs7_b_c\';
NET_NAME
'M_G_CPU0_SB_DQS_DN<8>'
 '@S9S_MB_2U_LIB.S9S_MB_2U(SCH_1):M_G_CPU0_SB_DQS_DN'<8>:
 C_SIGNAL='@s9s_mb_2u_lib.s9s_mb_2u(sch_1):m_g_cpu0_sb_dqs_dn(8)';
NODE_NAME     U2 EM6
 '@S9S_MB_2U_LIB.S9S_MB_2U(SCH_1):PAGE26_I169@PURE_QUANTA.SOCKET4677_AZIF0045P001C01CS(CHIPS)':
 'DDR6_SB_DQS_DN8': CDS_PINID='DDR6_SB_DQS_DN8';
NODE_NAME     J13 282
 '@S9S_MB_2U_LIB.S9S_MB_2U(SCH_1):PAGE94_I178@PURE_QUANTA.SCONN288_ADR50017P130CC(CHIPS)':
 'DQS8_B_C||TDQS8_B_C': CDS_PINID='\dqs8_b_c||tdqs8_b_c\';
NODE_NAME     J14 282
 '@S9S_MB_2U_LIB.S9S_MB_2U(SCH_1):PAGE95_I178@PURE_QUANTA.SCONN288_ADR50017P087CC(CHIPS)':
 'DQS8_B_C||TDQS8_B_C': CDS_PINID='\dqs8_b_c||tdqs8_b_c\';
NET_NAME
'M_G_CPU0_SB_DQS_DN<9>'
 '@S9S_MB_2U_LIB.S9S_MB_2U(SCH_1):M_G_CPU0_SB_DQS_DN'<9>:
 C_SIGNAL='@s9s_mb_2u_lib.s9s_mb_2u(sch_1):m_g_cpu0_sb_dqs_dn(9)';
NODE_NAME     U2 DV36
 '@S9S_MB_2U_LIB.S9S_MB_2U(SCH_1):PAGE26_I169@PURE_QUANTA.SOCKET4677_AZIF0045P001C01CS(CHIPS)':
 'DDR6_SB_DQS_DN9': CDS_PINID='DDR6_SB_DQS_DN9';
NODE_NAME     J13 94
 '@S9S_MB_2U_LIB.S9S_MB_2U(SCH_1):PAGE94_I178@PURE_QUANTA.SCONN288_ADR50017P130CC(CHIPS)':
 'DQS9_B_C||TDQS9_B_C': CDS_PINID='\dqs9_b_c||tdqs9_b_c\';
NODE_NAME     J14 94
 '@S9S_MB_2U_LIB.S9S_MB_2U(SCH_1):PAGE95_I178@PURE_QUANTA.SCONN288_ADR50017P087CC(CHIPS)':
 'DQS9_B_C||TDQS9_B_C': CDS_PINID='\dqs9_b_c||tdqs9_b_c\';
NET_NAME
'M_G_CPU0_SB_DQS_DP<0>'
 '@S9S_MB_2U_LIB.S9S_MB_2U(SCH_1):M_G_CPU0_SB_DQS_DP'<0>:
 C_SIGNAL='@s9s_mb_2u_lib.s9s_mb_2u(sch_1):m_g_cpu0_sb_dqs_dp(0)';
NODE_NAME     U2 DL33
 '@S9S_MB_2U_LIB.S9S_MB_2U(SCH_1):PAGE26_I169@PURE_QUANTA.SOCKET4677_AZIF0045P001C01CS(CHIPS)':
 'DDR6_SB_DQS_DP0': CDS_PINID='DDR6_SB_DQS_DP0';
NODE_NAME     J13 104
 '@S9S_MB_2U_LIB.S9S_MB_2U(SCH_1):PAGE94_I178@PURE_QUANTA.SCONN288_ADR50017P130CC(CHIPS)':
 'DQS0_B_T': CDS_PINID='DQS0_B_T';
NODE_NAME     J14 104
 '@S9S_MB_2U_LIB.S9S_MB_2U(SCH_1):PAGE95_I178@PURE_QUANTA.SCONN288_ADR50017P087CC(CHIPS)':
 'DQS0_B_T': CDS_PINID='DQS0_B_T';
NET_NAME
'M_G_CPU0_SB_DQS_DP<1>'
 '@S9S_MB_2U_LIB.S9S_MB_2U(SCH_1):M_G_CPU0_SB_DQS_DP'<1>:
 C_SIGNAL='@s9s_mb_2u_lib.s9s_mb_2u(sch_1):m_g_cpu0_sb_dqs_dp(1)';
NODE_NAME     U2 DL27
 '@S9S_MB_2U_LIB.S9S_MB_2U(SCH_1):PAGE26_I169@PURE_QUANTA.SOCKET4677_AZIF0045P001C01CS(CHIPS)':
 'DDR6_SB_DQS_DP1': CDS_PINID='DDR6_SB_DQS_DP1';
NODE_NAME     J13 115
 '@S9S_MB_2U_LIB.S9S_MB_2U(SCH_1):PAGE94_I178@PURE_QUANTA.SCONN288_ADR50017P130CC(CHIPS)':
 'DQS1_B_T': CDS_PINID='DQS1_B_T';
NODE_NAME     J14 115
 '@S9S_MB_2U_LIB.S9S_MB_2U(SCH_1):PAGE95_I178@PURE_QUANTA.SCONN288_ADR50017P087CC(CHIPS)':
 'DQS1_B_T': CDS_PINID='DQS1_B_T';
NET_NAME
'M_G_CPU0_SB_DQS_DP<2>'
 '@S9S_MB_2U_LIB.S9S_MB_2U(SCH_1):M_G_CPU0_SB_DQS_DP'<2>:
 C_SIGNAL='@s9s_mb_2u_lib.s9s_mb_2u(sch_1):m_g_cpu0_sb_dqs_dp(2)';
NODE_NAME     U2 DT24
 '@S9S_MB_2U_LIB.S9S_MB_2U(SCH_1):PAGE26_I169@PURE_QUANTA.SOCKET4677_AZIF0045P001C01CS(CHIPS)':
 'DDR6_SB_DQS_DP2': CDS_PINID='DDR6_SB_DQS_DP2';
NODE_NAME     J13 126
 '@S9S_MB_2U_LIB.S9S_MB_2U(SCH_1):PAGE94_I178@PURE_QUANTA.SCONN288_ADR50017P130CC(CHIPS)':
 'DQS2_B_T': CDS_PINID='DQS2_B_T';
NODE_NAME     J14 126
 '@S9S_MB_2U_LIB.S9S_MB_2U(SCH_1):PAGE95_I178@PURE_QUANTA.SCONN288_ADR50017P087CC(CHIPS)':
 'DQS2_B_T': CDS_PINID='DQS2_B_T';
NET_NAME
'M_G_CPU0_SB_DQS_DP<3>'
 '@S9S_MB_2U_LIB.S9S_MB_2U(SCH_1):M_G_CPU0_SB_DQS_DP'<3>:
 C_SIGNAL='@s9s_mb_2u_lib.s9s_mb_2u(sch_1):m_g_cpu0_sb_dqs_dp(3)';
NODE_NAME     U2 EN7
 '@S9S_MB_2U_LIB.S9S_MB_2U(SCH_1):PAGE26_I169@PURE_QUANTA.SOCKET4677_AZIF0045P001C01CS(CHIPS)':
 'DDR6_SB_DQS_DP3': CDS_PINID='DDR6_SB_DQS_DP3';
NODE_NAME     J13 137
 '@S9S_MB_2U_LIB.S9S_MB_2U(SCH_1):PAGE94_I178@PURE_QUANTA.SCONN288_ADR50017P130CC(CHIPS)':
 'DQS3_B_T': CDS_PINID='DQS3_B_T';
NODE_NAME     J14 137
 '@S9S_MB_2U_LIB.S9S_MB_2U(SCH_1):PAGE95_I178@PURE_QUANTA.SCONN288_ADR50017P087CC(CHIPS)':
 'DQS3_B_T': CDS_PINID='DQS3_B_T';
NET_NAME
'M_G_CPU0_SB_DQS_DP<4>'
 '@S9S_MB_2U_LIB.S9S_MB_2U(SCH_1):M_G_CPU0_SB_DQS_DP'<4>:
 C_SIGNAL='@s9s_mb_2u_lib.s9s_mb_2u(sch_1):m_g_cpu0_sb_dqs_dp(4)';
NODE_NAME     U2 DY36
 '@S9S_MB_2U_LIB.S9S_MB_2U(SCH_1):PAGE26_I169@PURE_QUANTA.SOCKET4677_AZIF0045P001C01CS(CHIPS)':
 'DDR6_SB_DQS_DP4': CDS_PINID='DDR6_SB_DQS_DP4';
NODE_NAME     J13 239
 '@S9S_MB_2U_LIB.S9S_MB_2U(SCH_1):PAGE94_I178@PURE_QUANTA.SCONN288_ADR50017P130CC(CHIPS)':
 'DQS4_B_T': CDS_PINID='DQS4_B_T';
NODE_NAME     J14 239
 '@S9S_MB_2U_LIB.S9S_MB_2U(SCH_1):PAGE95_I178@PURE_QUANTA.SCONN288_ADR50017P087CC(CHIPS)':
 'DQS4_B_T': CDS_PINID='DQS4_B_T';
NET_NAME
'M_G_CPU0_SB_DQS_DP<5>'
 '@S9S_MB_2U_LIB.S9S_MB_2U(SCH_1):M_G_CPU0_SB_DQS_DP'<5>:
 C_SIGNAL='@s9s_mb_2u_lib.s9s_mb_2u(sch_1):m_g_cpu0_sb_dqs_dp(5)';
NODE_NAME     U2 DN33
 '@S9S_MB_2U_LIB.S9S_MB_2U(SCH_1):PAGE26_I169@PURE_QUANTA.SOCKET4677_AZIF0045P001C01CS(CHIPS)':
 'DDR6_SB_DQS_DP5': CDS_PINID='DDR6_SB_DQS_DP5';
NODE_NAME     J13 250
 '@S9S_MB_2U_LIB.S9S_MB_2U(SCH_1):PAGE94_I178@PURE_QUANTA.SCONN288_ADR50017P130CC(CHIPS)':
 'DQS5_B_T||TDQS5_B_T': CDS_PINID='\dqs5_b_t||tdqs5_b_t\';
NODE_NAME     J14 250
 '@S9S_MB_2U_LIB.S9S_MB_2U(SCH_1):PAGE95_I178@PURE_QUANTA.SCONN288_ADR50017P087CC(CHIPS)':
 'DQS5_B_T||TDQS5_B_T': CDS_PINID='\dqs5_b_t||tdqs5_b_t\';
NET_NAME
'M_G_CPU0_SB_DQS_DP<6>'
 '@S9S_MB_2U_LIB.S9S_MB_2U(SCH_1):M_G_CPU0_SB_DQS_DP'<6>:
 C_SIGNAL='@s9s_mb_2u_lib.s9s_mb_2u(sch_1):m_g_cpu0_sb_dqs_dp(6)';
NODE_NAME     U2 DR27
 '@S9S_MB_2U_LIB.S9S_MB_2U(SCH_1):PAGE26_I169@PURE_QUANTA.SOCKET4677_AZIF0045P001C01CS(CHIPS)':
 'DDR6_SB_DQS_DP6': CDS_PINID='DDR6_SB_DQS_DP6';
NODE_NAME     J13 261
 '@S9S_MB_2U_LIB.S9S_MB_2U(SCH_1):PAGE94_I178@PURE_QUANTA.SCONN288_ADR50017P130CC(CHIPS)':
 'DQS6_B_T||TDQS6_B_T': CDS_PINID='\dqs6_b_t||tdqs6_b_t\';
NODE_NAME     J14 261
 '@S9S_MB_2U_LIB.S9S_MB_2U(SCH_1):PAGE95_I178@PURE_QUANTA.SCONN288_ADR50017P087CC(CHIPS)':
 'DQS6_B_T||TDQS6_B_T': CDS_PINID='\dqs6_b_t||tdqs6_b_t\';
NET_NAME
'M_G_CPU0_SB_DQS_DP<7>'
 '@S9S_MB_2U_LIB.S9S_MB_2U(SCH_1):M_G_CPU0_SB_DQS_DP'<7>:
 C_SIGNAL='@s9s_mb_2u_lib.s9s_mb_2u(sch_1):m_g_cpu0_sb_dqs_dp(7)';
NODE_NAME     U2 DY24
 '@S9S_MB_2U_LIB.S9S_MB_2U(SCH_1):PAGE26_I169@PURE_QUANTA.SOCKET4677_AZIF0045P001C01CS(CHIPS)':
 'DDR6_SB_DQS_DP7': CDS_PINID='DDR6_SB_DQS_DP7';
NODE_NAME     J13 272
 '@S9S_MB_2U_LIB.S9S_MB_2U(SCH_1):PAGE94_I178@PURE_QUANTA.SCONN288_ADR50017P130CC(CHIPS)':
 'DQS7_B_T||TDQS7_B_T': CDS_PINID='\dqs7_b_t||tdqs7_b_t\';
NODE_NAME     J14 272
 '@S9S_MB_2U_LIB.S9S_MB_2U(SCH_1):PAGE95_I178@PURE_QUANTA.SCONN288_ADR50017P087CC(CHIPS)':
 'DQS7_B_T||TDQS7_B_T': CDS_PINID='\dqs7_b_t||tdqs7_b_t\';
NET_NAME
'M_G_CPU0_SB_DQS_DP<8>'
 '@S9S_MB_2U_LIB.S9S_MB_2U(SCH_1):M_G_CPU0_SB_DQS_DP'<8>:
 C_SIGNAL='@s9s_mb_2u_lib.s9s_mb_2u(sch_1):m_g_cpu0_sb_dqs_dp(8)';
NODE_NAME     U2 EN5
 '@S9S_MB_2U_LIB.S9S_MB_2U(SCH_1):PAGE26_I169@PURE_QUANTA.SOCKET4677_AZIF0045P001C01CS(CHIPS)':
 'DDR6_SB_DQS_DP8': CDS_PINID='DDR6_SB_DQS_DP8';
NODE_NAME     J13 283
 '@S9S_MB_2U_LIB.S9S_MB_2U(SCH_1):PAGE94_I178@PURE_QUANTA.SCONN288_ADR50017P130CC(CHIPS)':
 'DQS8_B_T||TDQS8_B_T': CDS_PINID='\dqs8_b_t||tdqs8_b_t\';
NODE_NAME     J14 283
 '@S9S_MB_2U_LIB.S9S_MB_2U(SCH_1):PAGE95_I178@PURE_QUANTA.SCONN288_ADR50017P087CC(CHIPS)':
 'DQS8_B_T||TDQS8_B_T': CDS_PINID='\dqs8_b_t||tdqs8_b_t\';
NET_NAME
'M_G_CPU0_SB_DQS_DP<9>'
 '@S9S_MB_2U_LIB.S9S_MB_2U(SCH_1):M_G_CPU0_SB_DQS_DP'<9>:
 C_SIGNAL='@s9s_mb_2u_lib.s9s_mb_2u(sch_1):m_g_cpu0_sb_dqs_dp(9)';
NODE_NAME     U2 DT36
 '@S9S_MB_2U_LIB.S9S_MB_2U(SCH_1):PAGE26_I169@PURE_QUANTA.SOCKET4677_AZIF0045P001C01CS(CHIPS)':
 'DDR6_SB_DQS_DP9': CDS_PINID='DDR6_SB_DQS_DP9';
NODE_NAME     J13 93
 '@S9S_MB_2U_LIB.S9S_MB_2U(SCH_1):PAGE94_I178@PURE_QUANTA.SCONN288_ADR50017P130CC(CHIPS)':
 'DQS9_B_T||TDQS9_B_T||DBI4_B_N': CDS_PINID='\dqs9_b_t||tdqs9_b_t||dbi4_b_n\';
NODE_NAME     J14 93
 '@S9S_MB_2U_LIB.S9S_MB_2U(SCH_1):PAGE95_I178@PURE_QUANTA.SCONN288_ADR50017P087CC(CHIPS)':
 'DQS9_B_T||TDQS9_B_T||DBI4_B_N': CDS_PINID='\dqs9_b_t||tdqs9_b_t||dbi4_b_n\';
NET_NAME
'M_G_CPU0_SB_PAR'
 '@S9S_MB_2U_LIB.S9S_MB_2U(SCH_1):M_G_CPU0_SB_PAR':
 C_SIGNAL='@s9s_mb_2u_lib.s9s_mb_2u(sch_1):m_g_cpu0_sb_par';
NODE_NAME     U2 EB42
 '@S9S_MB_2U_LIB.S9S_MB_2U(SCH_1):PAGE26_I169@PURE_QUANTA.SOCKET4677_AZIF0045P001C01CS(CHIPS)':
 'DDR6_SB_PAR': CDS_PINID='DDR6_SB_PAR';
NODE_NAME     J13 227
 '@S9S_MB_2U_LIB.S9S_MB_2U(SCH_1):PAGE94_I11@PURE_QUANTA.SCONN288_ADR50017P130CC(CHIPS)':
 'PAR_B': CDS_PINID='PAR_B';
NODE_NAME     J14 227
 '@S9S_MB_2U_LIB.S9S_MB_2U(SCH_1):PAGE95_I47@PURE_QUANTA.SCONN288_ADR50017P087CC(CHIPS)':
 'PAR_B': CDS_PINID='PAR_B';
NET_NAME
'M_G_CPU0_SB_RSP<0>'
 '@S9S_MB_2U_LIB.S9S_MB_2U(SCH_1):M_G_CPU0_SB_RSP'<0>:
 C_SIGNAL='@s9s_mb_2u_lib.s9s_mb_2u(sch_1):m_g_cpu0_sb_rsp(0)';
NODE_NAME     U2 DU48
 '@S9S_MB_2U_LIB.S9S_MB_2U(SCH_1):PAGE26_I169@PURE_QUANTA.SOCKET4677_AZIF0045P001C01CS(CHIPS)':
 'DDR6_B_RSP0': CDS_PINID='DDR6_B_RSP0';
NODE_NAME     J13 87
 '@S9S_MB_2U_LIB.S9S_MB_2U(SCH_1):PAGE94_I11@PURE_QUANTA.SCONN288_ADR50017P130CC(CHIPS)':
 'LBS||RSP_B_N': CDS_PINID='\lbs||rsp_b_n\';
NET_NAME
'M_G_CPU0_SB_RSP<1>'
 '@S9S_MB_2U_LIB.S9S_MB_2U(SCH_1):M_G_CPU0_SB_RSP'<1>:
 C_SIGNAL='@s9s_mb_2u_lib.s9s_mb_2u(sch_1):m_g_cpu0_sb_rsp(1)';
NODE_NAME     U2 DV47
 '@S9S_MB_2U_LIB.S9S_MB_2U(SCH_1):PAGE26_I169@PURE_QUANTA.SOCKET4677_AZIF0045P001C01CS(CHIPS)':
 'DDR6_B_RSP1': CDS_PINID='DDR6_B_RSP1';
NODE_NAME     J14 87
 '@S9S_MB_2U_LIB.S9S_MB_2U(SCH_1):PAGE95_I47@PURE_QUANTA.SCONN288_ADR50017P087CC(CHIPS)':
 'LBS||RSP_B_N': CDS_PINID='\lbs||rsp_b_n\';
NET_NAME
'M_G_CPU1_ALERT_N'
 '@S9S_MB_2U_LIB.S9S_MB_2U(SCH_1):M_G_CPU1_ALERT_N':
 C_SIGNAL='@s9s_mb_2u_lib.s9s_mb_2u(sch_1):m_g_cpu1_alert_n';
NODE_NAME     U1 CW50
 '@S9S_MB_2U_LIB.S9S_MB_2U(SCH_1):PAGE57_I168@PURE_QUANTA.SOCKET4677_AZIF0045P001C01CS(CHIPS)':
 'DDR6_ALERT_N': CDS_PINID='DDR6_ALERT_N';
NODE_NAME     J29 62
 '@S9S_MB_2U_LIB.S9S_MB_2U(SCH_1):PAGE110_I179@PURE_QUANTA.SCONN288_ADR50017P130CC(CHIPS)':
 'ALERT_N': CDS_PINID='ALERT_N';
NODE_NAME     J30 62
 '@S9S_MB_2U_LIB.S9S_MB_2U(SCH_1):PAGE111_I179@PURE_QUANTA.SCONN288_ADR50017P087CC(CHIPS)':
 'ALERT_N': CDS_PINID='ALERT_N';
NET_NAME
'M_G_CPU1_CLK_DN<0>'
 '@S9S_MB_2U_LIB.S9S_MB_2U(SCH_1):M_G_CPU1_CLK_DN'<0>:
 C_SIGNAL='@s9s_mb_2u_lib.s9s_mb_2u(sch_1):m_g_cpu1_clk_dn(0)';
NODE_NAME     U1 DR45
 '@S9S_MB_2U_LIB.S9S_MB_2U(SCH_1):PAGE57_I168@PURE_QUANTA.SOCKET4677_AZIF0045P001C01CS(CHIPS)':
 'DDR6_CLK_DN0': CDS_PINID='DDR6_CLK_DN0';
NODE_NAME     J29 218
 '@S9S_MB_2U_LIB.S9S_MB_2U(SCH_1):PAGE110_I179@PURE_QUANTA.SCONN288_ADR50017P130CC(CHIPS)':
 'CK_C': CDS_PINID='CK_C';
NET_NAME
'M_G_CPU1_CLK_DN<1>'
 '@S9S_MB_2U_LIB.S9S_MB_2U(SCH_1):M_G_CPU1_CLK_DN'<1>:
 C_SIGNAL='@s9s_mb_2u_lib.s9s_mb_2u(sch_1):m_g_cpu1_clk_dn(1)';
NODE_NAME     U1 DL45
 '@S9S_MB_2U_LIB.S9S_MB_2U(SCH_1):PAGE57_I168@PURE_QUANTA.SOCKET4677_AZIF0045P001C01CS(CHIPS)':
 'DDR6_CLK_DN1': CDS_PINID='DDR6_CLK_DN1';
NODE_NAME     J30 218
 '@S9S_MB_2U_LIB.S9S_MB_2U(SCH_1):PAGE111_I179@PURE_QUANTA.SCONN288_ADR50017P087CC(CHIPS)':
 'CK_C': CDS_PINID='CK_C';
NET_NAME
'M_G_CPU1_CLK_DP<0>'
 '@S9S_MB_2U_LIB.S9S_MB_2U(SCH_1):M_G_CPU1_CLK_DP'<0>:
 C_SIGNAL='@s9s_mb_2u_lib.s9s_mb_2u(sch_1):m_g_cpu1_clk_dp(0)';
NODE_NAME     U1 DN45
 '@S9S_MB_2U_LIB.S9S_MB_2U(SCH_1):PAGE57_I168@PURE_QUANTA.SOCKET4677_AZIF0045P001C01CS(CHIPS)':
 'DDR6_CLK_DP0': CDS_PINID='DDR6_CLK_DP0';
NODE_NAME     J29 217
 '@S9S_MB_2U_LIB.S9S_MB_2U(SCH_1):PAGE110_I179@PURE_QUANTA.SCONN288_ADR50017P130CC(CHIPS)':
 'CK_T': CDS_PINID='CK_T';
NET_NAME
'M_G_CPU1_CLK_DP<1>'
 '@S9S_MB_2U_LIB.S9S_MB_2U(SCH_1):M_G_CPU1_CLK_DP'<1>:
 C_SIGNAL='@s9s_mb_2u_lib.s9s_mb_2u(sch_1):m_g_cpu1_clk_dp(1)';
NODE_NAME     U1 DJ45
 '@S9S_MB_2U_LIB.S9S_MB_2U(SCH_1):PAGE57_I168@PURE_QUANTA.SOCKET4677_AZIF0045P001C01CS(CHIPS)':
 'DDR6_CLK_DP1': CDS_PINID='DDR6_CLK_DP1';
NODE_NAME     J30 217
 '@S9S_MB_2U_LIB.S9S_MB_2U(SCH_1):PAGE111_I179@PURE_QUANTA.SCONN288_ADR50017P087CC(CHIPS)':
 'CK_T': CDS_PINID='CK_T';
NET_NAME
'M_G_CPU1_SA_CA<0>'
 '@S9S_MB_2U_LIB.S9S_MB_2U(SCH_1):M_G_CPU1_SA_CA'<0>:
 C_SIGNAL='@s9s_mb_2u_lib.s9s_mb_2u(sch_1):m_g_cpu1_sa_ca(0)';
NODE_NAME     U1 DJ52
 '@S9S_MB_2U_LIB.S9S_MB_2U(SCH_1):PAGE57_I168@PURE_QUANTA.SOCKET4677_AZIF0045P001C01CS(CHIPS)':
 'DDR6_SA_CA0': CDS_PINID='DDR6_SA_CA0';
NODE_NAME     J29 66
 '@S9S_MB_2U_LIB.S9S_MB_2U(SCH_1):PAGE110_I179@PURE_QUANTA.SCONN288_ADR50017P130CC(CHIPS)':
 'CA0_A': CDS_PINID='CA0_A';
NODE_NAME     J30 66
 '@S9S_MB_2U_LIB.S9S_MB_2U(SCH_1):PAGE111_I179@PURE_QUANTA.SCONN288_ADR50017P087CC(CHIPS)':
 'CA0_A': CDS_PINID='CA0_A';
NET_NAME
'M_G_CPU1_SA_CA<1>'
 '@S9S_MB_2U_LIB.S9S_MB_2U(SCH_1):M_G_CPU1_SA_CA'<1>:
 C_SIGNAL='@s9s_mb_2u_lib.s9s_mb_2u(sch_1):m_g_cpu1_sa_ca(1)';
NODE_NAME     U1 DR52
 '@S9S_MB_2U_LIB.S9S_MB_2U(SCH_1):PAGE57_I168@PURE_QUANTA.SOCKET4677_AZIF0045P001C01CS(CHIPS)':
 'DDR6_SA_CA1': CDS_PINID='DDR6_SA_CA1';
NODE_NAME     J29 211
 '@S9S_MB_2U_LIB.S9S_MB_2U(SCH_1):PAGE110_I179@PURE_QUANTA.SCONN288_ADR50017P130CC(CHIPS)':
 'CA1_A': CDS_PINID='CA1_A';
NODE_NAME     J30 211
 '@S9S_MB_2U_LIB.S9S_MB_2U(SCH_1):PAGE111_I179@PURE_QUANTA.SCONN288_ADR50017P087CC(CHIPS)':
 'CA1_A': CDS_PINID='CA1_A';
NET_NAME
'M_G_CPU1_SA_CA<2>'
 '@S9S_MB_2U_LIB.S9S_MB_2U(SCH_1):M_G_CPU1_SA_CA'<2>:
 C_SIGNAL='@s9s_mb_2u_lib.s9s_mb_2u(sch_1):m_g_cpu1_sa_ca(2)';
NODE_NAME     U1 DK51
 '@S9S_MB_2U_LIB.S9S_MB_2U(SCH_1):PAGE57_I168@PURE_QUANTA.SOCKET4677_AZIF0045P001C01CS(CHIPS)':
 'DDR6_SA_CA2': CDS_PINID='DDR6_SA_CA2';
NODE_NAME     J29 68
 '@S9S_MB_2U_LIB.S9S_MB_2U(SCH_1):PAGE110_I179@PURE_QUANTA.SCONN288_ADR50017P130CC(CHIPS)':
 'CA2_A': CDS_PINID='CA2_A';
NODE_NAME     J30 68
 '@S9S_MB_2U_LIB.S9S_MB_2U(SCH_1):PAGE111_I179@PURE_QUANTA.SCONN288_ADR50017P087CC(CHIPS)':
 'CA2_A': CDS_PINID='CA2_A';
NET_NAME
'M_G_CPU1_SA_CA<3>'
 '@S9S_MB_2U_LIB.S9S_MB_2U(SCH_1):M_G_CPU1_SA_CA'<3>:
 C_SIGNAL='@s9s_mb_2u_lib.s9s_mb_2u(sch_1):m_g_cpu1_sa_ca(3)';
NODE_NAME     U1 DP51
 '@S9S_MB_2U_LIB.S9S_MB_2U(SCH_1):PAGE57_I168@PURE_QUANTA.SOCKET4677_AZIF0045P001C01CS(CHIPS)':
 'DDR6_SA_CA3': CDS_PINID='DDR6_SA_CA3';
NODE_NAME     J29 213
 '@S9S_MB_2U_LIB.S9S_MB_2U(SCH_1):PAGE110_I179@PURE_QUANTA.SCONN288_ADR50017P130CC(CHIPS)':
 'CA3_A': CDS_PINID='CA3_A';
NODE_NAME     J30 213
 '@S9S_MB_2U_LIB.S9S_MB_2U(SCH_1):PAGE111_I179@PURE_QUANTA.SCONN288_ADR50017P087CC(CHIPS)':
 'CA3_A': CDS_PINID='CA3_A';
NET_NAME
'M_G_CPU1_SA_CA<4>'
 '@S9S_MB_2U_LIB.S9S_MB_2U(SCH_1):M_G_CPU1_SA_CA'<4>:
 C_SIGNAL='@s9s_mb_2u_lib.s9s_mb_2u(sch_1):m_g_cpu1_sa_ca(4)';
NODE_NAME     U1 DL50
 '@S9S_MB_2U_LIB.S9S_MB_2U(SCH_1):PAGE57_I168@PURE_QUANTA.SOCKET4677_AZIF0045P001C01CS(CHIPS)':
 'DDR6_SA_CA4': CDS_PINID='DDR6_SA_CA4';
NODE_NAME     J29 70
 '@S9S_MB_2U_LIB.S9S_MB_2U(SCH_1):PAGE110_I179@PURE_QUANTA.SCONN288_ADR50017P130CC(CHIPS)':
 'CA4_A': CDS_PINID='CA4_A';
NODE_NAME     J30 70
 '@S9S_MB_2U_LIB.S9S_MB_2U(SCH_1):PAGE111_I179@PURE_QUANTA.SCONN288_ADR50017P087CC(CHIPS)':
 'CA4_A': CDS_PINID='CA4_A';
NET_NAME
'M_G_CPU1_SA_CA<5>'
 '@S9S_MB_2U_LIB.S9S_MB_2U(SCH_1):M_G_CPU1_SA_CA'<5>:
 C_SIGNAL='@s9s_mb_2u_lib.s9s_mb_2u(sch_1):m_g_cpu1_sa_ca(5)';
NODE_NAME     U1 DN50
 '@S9S_MB_2U_LIB.S9S_MB_2U(SCH_1):PAGE57_I168@PURE_QUANTA.SOCKET4677_AZIF0045P001C01CS(CHIPS)':
 'DDR6_SA_CA5': CDS_PINID='DDR6_SA_CA5';
NODE_NAME     J29 215
 '@S9S_MB_2U_LIB.S9S_MB_2U(SCH_1):PAGE110_I179@PURE_QUANTA.SCONN288_ADR50017P130CC(CHIPS)':
 'CA5_A': CDS_PINID='CA5_A';
NODE_NAME     J30 215
 '@S9S_MB_2U_LIB.S9S_MB_2U(SCH_1):PAGE111_I179@PURE_QUANTA.SCONN288_ADR50017P087CC(CHIPS)':
 'CA5_A': CDS_PINID='CA5_A';
NET_NAME
'M_G_CPU1_SA_CA<6>'
 '@S9S_MB_2U_LIB.S9S_MB_2U(SCH_1):M_G_CPU1_SA_CA'<6>:
 C_SIGNAL='@s9s_mb_2u_lib.s9s_mb_2u(sch_1):m_g_cpu1_sa_ca(6)';
NODE_NAME     U1 DK44
 '@S9S_MB_2U_LIB.S9S_MB_2U(SCH_1):PAGE57_I168@PURE_QUANTA.SOCKET4677_AZIF0045P001C01CS(CHIPS)':
 'DDR6_SA_CA6': CDS_PINID='DDR6_SA_CA6';
NODE_NAME     J29 72
 '@S9S_MB_2U_LIB.S9S_MB_2U(SCH_1):PAGE110_I179@PURE_QUANTA.SCONN288_ADR50017P130CC(CHIPS)':
 'CA6_A': CDS_PINID='CA6_A';
NODE_NAME     J30 72
 '@S9S_MB_2U_LIB.S9S_MB_2U(SCH_1):PAGE111_I179@PURE_QUANTA.SCONN288_ADR50017P087CC(CHIPS)':
 'CA6_A': CDS_PINID='CA6_A';
NET_NAME
'M_G_CPU1_SA_CB<0>'
 '@S9S_MB_2U_LIB.S9S_MB_2U(SCH_1):M_G_CPU1_SA_CB'<0>:
 C_SIGNAL='@s9s_mb_2u_lib.s9s_mb_2u(sch_1):m_g_cpu1_sa_cb(0)';
NODE_NAME     U1 DL60
 '@S9S_MB_2U_LIB.S9S_MB_2U(SCH_1):PAGE57_I168@PURE_QUANTA.SOCKET4677_AZIF0045P001C01CS(CHIPS)':
 'DDR6_SA_ECC0': CDS_PINID='DDR6_SA_ECC0';
NODE_NAME     J29 51
 '@S9S_MB_2U_LIB.S9S_MB_2U(SCH_1):PAGE110_I179@PURE_QUANTA.SCONN288_ADR50017P130CC(CHIPS)':
 'CB0_A': CDS_PINID='CB0_A';
NODE_NAME     J30 51
 '@S9S_MB_2U_LIB.S9S_MB_2U(SCH_1):PAGE111_I179@PURE_QUANTA.SCONN288_ADR50017P087CC(CHIPS)':
 'CB0_A': CDS_PINID='CB0_A';
NET_NAME
'M_G_CPU1_SA_CB<1>'
 '@S9S_MB_2U_LIB.S9S_MB_2U(SCH_1):M_G_CPU1_SA_CB'<1>:
 C_SIGNAL='@s9s_mb_2u_lib.s9s_mb_2u(sch_1):m_g_cpu1_sa_cb(1)';
NODE_NAME     U1 DK59
 '@S9S_MB_2U_LIB.S9S_MB_2U(SCH_1):PAGE57_I168@PURE_QUANTA.SOCKET4677_AZIF0045P001C01CS(CHIPS)':
 'DDR6_SA_ECC1': CDS_PINID='DDR6_SA_ECC1';
NODE_NAME     J29 53
 '@S9S_MB_2U_LIB.S9S_MB_2U(SCH_1):PAGE110_I179@PURE_QUANTA.SCONN288_ADR50017P130CC(CHIPS)':
 'CB1_A': CDS_PINID='CB1_A';
NODE_NAME     J30 53
 '@S9S_MB_2U_LIB.S9S_MB_2U(SCH_1):PAGE111_I179@PURE_QUANTA.SCONN288_ADR50017P087CC(CHIPS)':
 'CB1_A': CDS_PINID='CB1_A';
NET_NAME
'M_G_CPU1_SA_CB<2>'
 '@S9S_MB_2U_LIB.S9S_MB_2U(SCH_1):M_G_CPU1_SA_CB'<2>:
 C_SIGNAL='@s9s_mb_2u_lib.s9s_mb_2u(sch_1):m_g_cpu1_sa_cb(2)';
NODE_NAME     U1 DN60
 '@S9S_MB_2U_LIB.S9S_MB_2U(SCH_1):PAGE57_I168@PURE_QUANTA.SOCKET4677_AZIF0045P001C01CS(CHIPS)':
 'DDR6_SA_ECC2': CDS_PINID='DDR6_SA_ECC2';
NODE_NAME     J29 196
 '@S9S_MB_2U_LIB.S9S_MB_2U(SCH_1):PAGE110_I179@PURE_QUANTA.SCONN288_ADR50017P130CC(CHIPS)':
 'CB2_A': CDS_PINID='CB2_A';
NODE_NAME     J30 196
 '@S9S_MB_2U_LIB.S9S_MB_2U(SCH_1):PAGE111_I179@PURE_QUANTA.SCONN288_ADR50017P087CC(CHIPS)':
 'CB2_A': CDS_PINID='CB2_A';
NET_NAME
'M_G_CPU1_SA_CB<3>'
 '@S9S_MB_2U_LIB.S9S_MB_2U(SCH_1):M_G_CPU1_SA_CB'<3>:
 C_SIGNAL='@s9s_mb_2u_lib.s9s_mb_2u(sch_1):m_g_cpu1_sa_cb(3)';
NODE_NAME     U1 DP59
 '@S9S_MB_2U_LIB.S9S_MB_2U(SCH_1):PAGE57_I168@PURE_QUANTA.SOCKET4677_AZIF0045P001C01CS(CHIPS)':
 'DDR6_SA_ECC3': CDS_PINID='DDR6_SA_ECC3';
NODE_NAME     J29 198
 '@S9S_MB_2U_LIB.S9S_MB_2U(SCH_1):PAGE110_I179@PURE_QUANTA.SCONN288_ADR50017P130CC(CHIPS)':
 'CB3_A': CDS_PINID='CB3_A';
NODE_NAME     J30 198
 '@S9S_MB_2U_LIB.S9S_MB_2U(SCH_1):PAGE111_I179@PURE_QUANTA.SCONN288_ADR50017P087CC(CHIPS)':
 'CB3_A': CDS_PINID='CB3_A';
NET_NAME
'M_G_CPU1_SA_CB<4>'
 '@S9S_MB_2U_LIB.S9S_MB_2U(SCH_1):M_G_CPU1_SA_CB'<4>:
 C_SIGNAL='@s9s_mb_2u_lib.s9s_mb_2u(sch_1):m_g_cpu1_sa_cb(4)';
NODE_NAME     U1 DK57
 '@S9S_MB_2U_LIB.S9S_MB_2U(SCH_1):PAGE57_I168@PURE_QUANTA.SOCKET4677_AZIF0045P001C01CS(CHIPS)':
 'DDR6_SA_ECC4': CDS_PINID='DDR6_SA_ECC4';
NODE_NAME     J29 58
 '@S9S_MB_2U_LIB.S9S_MB_2U(SCH_1):PAGE110_I179@PURE_QUANTA.SCONN288_ADR50017P130CC(CHIPS)':
 'CB4_A': CDS_PINID='CB4_A';
NODE_NAME     J30 58
 '@S9S_MB_2U_LIB.S9S_MB_2U(SCH_1):PAGE111_I179@PURE_QUANTA.SCONN288_ADR50017P087CC(CHIPS)':
 'CB4_A': CDS_PINID='CB4_A';
NET_NAME
'M_G_CPU1_SA_CB<5>'
 '@S9S_MB_2U_LIB.S9S_MB_2U(SCH_1):M_G_CPU1_SA_CB'<5>:
 C_SIGNAL='@s9s_mb_2u_lib.s9s_mb_2u(sch_1):m_g_cpu1_sa_cb(5)';
NODE_NAME     U1 DL56
 '@S9S_MB_2U_LIB.S9S_MB_2U(SCH_1):PAGE57_I168@PURE_QUANTA.SOCKET4677_AZIF0045P001C01CS(CHIPS)':
 'DDR6_SA_ECC5': CDS_PINID='DDR6_SA_ECC5';
NODE_NAME     J29 60
 '@S9S_MB_2U_LIB.S9S_MB_2U(SCH_1):PAGE110_I179@PURE_QUANTA.SCONN288_ADR50017P130CC(CHIPS)':
 'CB5_A': CDS_PINID='CB5_A';
NODE_NAME     J30 60
 '@S9S_MB_2U_LIB.S9S_MB_2U(SCH_1):PAGE111_I179@PURE_QUANTA.SCONN288_ADR50017P087CC(CHIPS)':
 'CB5_A': CDS_PINID='CB5_A';
NET_NAME
'M_G_CPU1_SA_CB<6>'
 '@S9S_MB_2U_LIB.S9S_MB_2U(SCH_1):M_G_CPU1_SA_CB'<6>:
 C_SIGNAL='@s9s_mb_2u_lib.s9s_mb_2u(sch_1):m_g_cpu1_sa_cb(6)';
NODE_NAME     U1 DP57
 '@S9S_MB_2U_LIB.S9S_MB_2U(SCH_1):PAGE57_I168@PURE_QUANTA.SOCKET4677_AZIF0045P001C01CS(CHIPS)':
 'DDR6_SA_ECC6': CDS_PINID='DDR6_SA_ECC6';
NODE_NAME     J29 203
 '@S9S_MB_2U_LIB.S9S_MB_2U(SCH_1):PAGE110_I179@PURE_QUANTA.SCONN288_ADR50017P130CC(CHIPS)':
 'CB6_A': CDS_PINID='CB6_A';
NODE_NAME     J30 203
 '@S9S_MB_2U_LIB.S9S_MB_2U(SCH_1):PAGE111_I179@PURE_QUANTA.SCONN288_ADR50017P087CC(CHIPS)':
 'CB6_A': CDS_PINID='CB6_A';
NET_NAME
'M_G_CPU1_SA_CB<7>'
 '@S9S_MB_2U_LIB.S9S_MB_2U(SCH_1):M_G_CPU1_SA_CB'<7>:
 C_SIGNAL='@s9s_mb_2u_lib.s9s_mb_2u(sch_1):m_g_cpu1_sa_cb(7)';
NODE_NAME     U1 DN56
 '@S9S_MB_2U_LIB.S9S_MB_2U(SCH_1):PAGE57_I168@PURE_QUANTA.SOCKET4677_AZIF0045P001C01CS(CHIPS)':
 'DDR6_SA_ECC7': CDS_PINID='DDR6_SA_ECC7';
NODE_NAME     J29 205
 '@S9S_MB_2U_LIB.S9S_MB_2U(SCH_1):PAGE110_I179@PURE_QUANTA.SCONN288_ADR50017P130CC(CHIPS)':
 'CB7_A': CDS_PINID='CB7_A';
NODE_NAME     J30 205
 '@S9S_MB_2U_LIB.S9S_MB_2U(SCH_1):PAGE111_I179@PURE_QUANTA.SCONN288_ADR50017P087CC(CHIPS)':
 'CB7_A': CDS_PINID='CB7_A';
NET_NAME
'M_G_CPU1_SA_CS_N<0>'
 '@S9S_MB_2U_LIB.S9S_MB_2U(SCH_1):M_G_CPU1_SA_CS_N'<0>:
 C_SIGNAL='@s9s_mb_2u_lib.s9s_mb_2u(sch_1):m_g_cpu1_sa_cs_n(0)';
NODE_NAME     U1 DN54
 '@S9S_MB_2U_LIB.S9S_MB_2U(SCH_1):PAGE57_I168@PURE_QUANTA.SOCKET4677_AZIF0045P001C01CS(CHIPS)':
 'DDR6_SA_CS_N0': CDS_PINID='DDR6_SA_CS_N0';
NODE_NAME     J29 64
 '@S9S_MB_2U_LIB.S9S_MB_2U(SCH_1):PAGE110_I179@PURE_QUANTA.SCONN288_ADR50017P130CC(CHIPS)':
 'CS0_A_N': CDS_PINID='CS0_A_N';
NET_NAME
'M_G_CPU1_SA_CS_N<1>'
 '@S9S_MB_2U_LIB.S9S_MB_2U(SCH_1):M_G_CPU1_SA_CS_N'<1>:
 C_SIGNAL='@s9s_mb_2u_lib.s9s_mb_2u(sch_1):m_g_cpu1_sa_cs_n(1)';
NODE_NAME     U1 DP53
 '@S9S_MB_2U_LIB.S9S_MB_2U(SCH_1):PAGE57_I168@PURE_QUANTA.SOCKET4677_AZIF0045P001C01CS(CHIPS)':
 'DDR6_SA_CS_N1': CDS_PINID='DDR6_SA_CS_N1';
NODE_NAME     J29 209
 '@S9S_MB_2U_LIB.S9S_MB_2U(SCH_1):PAGE110_I179@PURE_QUANTA.SCONN288_ADR50017P130CC(CHIPS)':
 'CS1_A_N': CDS_PINID='CS1_A_N';
NET_NAME
'M_G_CPU1_SA_CS_N<2>'
 '@S9S_MB_2U_LIB.S9S_MB_2U(SCH_1):M_G_CPU1_SA_CS_N'<2>:
 C_SIGNAL='@s9s_mb_2u_lib.s9s_mb_2u(sch_1):m_g_cpu1_sa_cs_n(2)';
NODE_NAME     U1 DL54
 '@S9S_MB_2U_LIB.S9S_MB_2U(SCH_1):PAGE57_I168@PURE_QUANTA.SOCKET4677_AZIF0045P001C01CS(CHIPS)':
 'DDR6_SA_CS_N2': CDS_PINID='DDR6_SA_CS_N2';
NODE_NAME     J30 64
 '@S9S_MB_2U_LIB.S9S_MB_2U(SCH_1):PAGE111_I179@PURE_QUANTA.SCONN288_ADR50017P087CC(CHIPS)':
 'CS0_A_N': CDS_PINID='CS0_A_N';
NET_NAME
'M_G_CPU1_SA_CS_N<3>'
 '@S9S_MB_2U_LIB.S9S_MB_2U(SCH_1):M_G_CPU1_SA_CS_N'<3>:
 C_SIGNAL='@s9s_mb_2u_lib.s9s_mb_2u(sch_1):m_g_cpu1_sa_cs_n(3)';
NODE_NAME     U1 DK53
 '@S9S_MB_2U_LIB.S9S_MB_2U(SCH_1):PAGE57_I168@PURE_QUANTA.SOCKET4677_AZIF0045P001C01CS(CHIPS)':
 'DDR6_SA_CS_N3': CDS_PINID='DDR6_SA_CS_N3';
NODE_NAME     J30 209
 '@S9S_MB_2U_LIB.S9S_MB_2U(SCH_1):PAGE111_I179@PURE_QUANTA.SCONN288_ADR50017P087CC(CHIPS)':
 'CS1_A_N': CDS_PINID='CS1_A_N';
NET_NAME
'M_G_CPU1_SA_DQ<0>'
 '@S9S_MB_2U_LIB.S9S_MB_2U(SCH_1):M_G_CPU1_SA_DQ'<0>:
 C_SIGNAL='@s9s_mb_2u_lib.s9s_mb_2u(sch_1):m_g_cpu1_sa_dq(0)';
NODE_NAME     U1 DV75
 '@S9S_MB_2U_LIB.S9S_MB_2U(SCH_1):PAGE57_I168@PURE_QUANTA.SOCKET4677_AZIF0045P001C01CS(CHIPS)':
 'DDR6_SA_DQ0': CDS_PINID='DDR6_SA_DQ0';
NODE_NAME     J29 7
 '@S9S_MB_2U_LIB.S9S_MB_2U(SCH_1):PAGE110_I179@PURE_QUANTA.SCONN288_ADR50017P130CC(CHIPS)':
 'DQ0_A': CDS_PINID='DQ0_A';
NODE_NAME     J30 7
 '@S9S_MB_2U_LIB.S9S_MB_2U(SCH_1):PAGE111_I179@PURE_QUANTA.SCONN288_ADR50017P087CC(CHIPS)':
 'DQ0_A': CDS_PINID='DQ0_A';
NET_NAME
'M_G_CPU1_SA_DQ<10>'
 '@S9S_MB_2U_LIB.S9S_MB_2U(SCH_1):M_G_CPU1_SA_DQ'<10>:
 C_SIGNAL='@s9s_mb_2u_lib.s9s_mb_2u(sch_1):m_g_cpu1_sa_dq(10)';
NODE_NAME     U1 DN72
 '@S9S_MB_2U_LIB.S9S_MB_2U(SCH_1):PAGE57_I168@PURE_QUANTA.SOCKET4677_AZIF0045P001C01CS(CHIPS)':
 'DDR6_SA_DQ10': CDS_PINID='DDR6_SA_DQ10';
NODE_NAME     J29 163
 '@S9S_MB_2U_LIB.S9S_MB_2U(SCH_1):PAGE110_I179@PURE_QUANTA.SCONN288_ADR50017P130CC(CHIPS)':
 'DQ10_A': CDS_PINID='DQ10_A';
NODE_NAME     J30 163
 '@S9S_MB_2U_LIB.S9S_MB_2U(SCH_1):PAGE111_I179@PURE_QUANTA.SCONN288_ADR50017P087CC(CHIPS)':
 'DQ10_A': CDS_PINID='DQ10_A';
NET_NAME
'M_G_CPU1_SA_DQ<11>'
 '@S9S_MB_2U_LIB.S9S_MB_2U(SCH_1):M_G_CPU1_SA_DQ'<11>:
 C_SIGNAL='@s9s_mb_2u_lib.s9s_mb_2u(sch_1):m_g_cpu1_sa_dq(11)';
NODE_NAME     U1 DP71
 '@S9S_MB_2U_LIB.S9S_MB_2U(SCH_1):PAGE57_I168@PURE_QUANTA.SOCKET4677_AZIF0045P001C01CS(CHIPS)':
 'DDR6_SA_DQ11': CDS_PINID='DDR6_SA_DQ11';
NODE_NAME     J29 165
 '@S9S_MB_2U_LIB.S9S_MB_2U(SCH_1):PAGE110_I179@PURE_QUANTA.SCONN288_ADR50017P130CC(CHIPS)':
 'DQ11_A': CDS_PINID='DQ11_A';
NODE_NAME     J30 165
 '@S9S_MB_2U_LIB.S9S_MB_2U(SCH_1):PAGE111_I179@PURE_QUANTA.SCONN288_ADR50017P087CC(CHIPS)':
 'DQ11_A': CDS_PINID='DQ11_A';
NET_NAME
'M_G_CPU1_SA_DQ<12>'
 '@S9S_MB_2U_LIB.S9S_MB_2U(SCH_1):M_G_CPU1_SA_DQ'<12>:
 C_SIGNAL='@s9s_mb_2u_lib.s9s_mb_2u(sch_1):m_g_cpu1_sa_dq(12)';
NODE_NAME     U1 DK69
 '@S9S_MB_2U_LIB.S9S_MB_2U(SCH_1):PAGE57_I168@PURE_QUANTA.SOCKET4677_AZIF0045P001C01CS(CHIPS)':
 'DDR6_SA_DQ12': CDS_PINID='DDR6_SA_DQ12';
NODE_NAME     J29 25
 '@S9S_MB_2U_LIB.S9S_MB_2U(SCH_1):PAGE110_I179@PURE_QUANTA.SCONN288_ADR50017P130CC(CHIPS)':
 'DQ12_A': CDS_PINID='DQ12_A';
NODE_NAME     J30 25
 '@S9S_MB_2U_LIB.S9S_MB_2U(SCH_1):PAGE111_I179@PURE_QUANTA.SCONN288_ADR50017P087CC(CHIPS)':
 'DQ12_A': CDS_PINID='DQ12_A';
NET_NAME
'M_G_CPU1_SA_DQ<13>'
 '@S9S_MB_2U_LIB.S9S_MB_2U(SCH_1):M_G_CPU1_SA_DQ'<13>:
 C_SIGNAL='@s9s_mb_2u_lib.s9s_mb_2u(sch_1):m_g_cpu1_sa_dq(13)';
NODE_NAME     U1 DL68
 '@S9S_MB_2U_LIB.S9S_MB_2U(SCH_1):PAGE57_I168@PURE_QUANTA.SOCKET4677_AZIF0045P001C01CS(CHIPS)':
 'DDR6_SA_DQ13': CDS_PINID='DDR6_SA_DQ13';
NODE_NAME     J29 27
 '@S9S_MB_2U_LIB.S9S_MB_2U(SCH_1):PAGE110_I179@PURE_QUANTA.SCONN288_ADR50017P130CC(CHIPS)':
 'DQ13_A': CDS_PINID='DQ13_A';
NODE_NAME     J30 27
 '@S9S_MB_2U_LIB.S9S_MB_2U(SCH_1):PAGE111_I179@PURE_QUANTA.SCONN288_ADR50017P087CC(CHIPS)':
 'DQ13_A': CDS_PINID='DQ13_A';
NET_NAME
'M_G_CPU1_SA_DQ<14>'
 '@S9S_MB_2U_LIB.S9S_MB_2U(SCH_1):M_G_CPU1_SA_DQ'<14>:
 C_SIGNAL='@s9s_mb_2u_lib.s9s_mb_2u(sch_1):m_g_cpu1_sa_dq(14)';
NODE_NAME     U1 DP69
 '@S9S_MB_2U_LIB.S9S_MB_2U(SCH_1):PAGE57_I168@PURE_QUANTA.SOCKET4677_AZIF0045P001C01CS(CHIPS)':
 'DDR6_SA_DQ14': CDS_PINID='DDR6_SA_DQ14';
NODE_NAME     J29 170
 '@S9S_MB_2U_LIB.S9S_MB_2U(SCH_1):PAGE110_I179@PURE_QUANTA.SCONN288_ADR50017P130CC(CHIPS)':
 'DQ14_A': CDS_PINID='DQ14_A';
NODE_NAME     J30 170
 '@S9S_MB_2U_LIB.S9S_MB_2U(SCH_1):PAGE111_I179@PURE_QUANTA.SCONN288_ADR50017P087CC(CHIPS)':
 'DQ14_A': CDS_PINID='DQ14_A';
NET_NAME
'M_G_CPU1_SA_DQ<15>'
 '@S9S_MB_2U_LIB.S9S_MB_2U(SCH_1):M_G_CPU1_SA_DQ'<15>:
 C_SIGNAL='@s9s_mb_2u_lib.s9s_mb_2u(sch_1):m_g_cpu1_sa_dq(15)';
NODE_NAME     U1 DN68
 '@S9S_MB_2U_LIB.S9S_MB_2U(SCH_1):PAGE57_I168@PURE_QUANTA.SOCKET4677_AZIF0045P001C01CS(CHIPS)':
 'DDR6_SA_DQ15': CDS_PINID='DDR6_SA_DQ15';
NODE_NAME     J29 172
 '@S9S_MB_2U_LIB.S9S_MB_2U(SCH_1):PAGE110_I179@PURE_QUANTA.SCONN288_ADR50017P130CC(CHIPS)':
 'DQ15_A': CDS_PINID='DQ15_A';
NODE_NAME     J30 172
 '@S9S_MB_2U_LIB.S9S_MB_2U(SCH_1):PAGE111_I179@PURE_QUANTA.SCONN288_ADR50017P087CC(CHIPS)':
 'DQ15_A': CDS_PINID='DQ15_A';
NET_NAME
'M_G_CPU1_SA_DQ<16>'
 '@S9S_MB_2U_LIB.S9S_MB_2U(SCH_1):M_G_CPU1_SA_DQ'<16>:
 C_SIGNAL='@s9s_mb_2u_lib.s9s_mb_2u(sch_1):m_g_cpu1_sa_dq(16)';
NODE_NAME     U1 DV63
 '@S9S_MB_2U_LIB.S9S_MB_2U(SCH_1):PAGE57_I168@PURE_QUANTA.SOCKET4677_AZIF0045P001C01CS(CHIPS)':
 'DDR6_SA_DQ16': CDS_PINID='DDR6_SA_DQ16';
NODE_NAME     J29 29
 '@S9S_MB_2U_LIB.S9S_MB_2U(SCH_1):PAGE110_I179@PURE_QUANTA.SCONN288_ADR50017P130CC(CHIPS)':
 'DQ16_A': CDS_PINID='DQ16_A';
NODE_NAME     J30 29
 '@S9S_MB_2U_LIB.S9S_MB_2U(SCH_1):PAGE111_I179@PURE_QUANTA.SCONN288_ADR50017P087CC(CHIPS)':
 'DQ16_A': CDS_PINID='DQ16_A';
NET_NAME
'M_G_CPU1_SA_DQ<17>'
 '@S9S_MB_2U_LIB.S9S_MB_2U(SCH_1):M_G_CPU1_SA_DQ'<17>:
 C_SIGNAL='@s9s_mb_2u_lib.s9s_mb_2u(sch_1):m_g_cpu1_sa_dq(17)';
NODE_NAME     U1 DU62
 '@S9S_MB_2U_LIB.S9S_MB_2U(SCH_1):PAGE57_I168@PURE_QUANTA.SOCKET4677_AZIF0045P001C01CS(CHIPS)':
 'DDR6_SA_DQ17': CDS_PINID='DDR6_SA_DQ17';
NODE_NAME     J29 31
 '@S9S_MB_2U_LIB.S9S_MB_2U(SCH_1):PAGE110_I179@PURE_QUANTA.SCONN288_ADR50017P130CC(CHIPS)':
 'DQ17_A': CDS_PINID='DQ17_A';
NODE_NAME     J30 31
 '@S9S_MB_2U_LIB.S9S_MB_2U(SCH_1):PAGE111_I179@PURE_QUANTA.SCONN288_ADR50017P087CC(CHIPS)':
 'DQ17_A': CDS_PINID='DQ17_A';
NET_NAME
'M_G_CPU1_SA_DQ<18>'
 '@S9S_MB_2U_LIB.S9S_MB_2U(SCH_1):M_G_CPU1_SA_DQ'<18>:
 C_SIGNAL='@s9s_mb_2u_lib.s9s_mb_2u(sch_1):m_g_cpu1_sa_dq(18)';
NODE_NAME     U1 DY63
 '@S9S_MB_2U_LIB.S9S_MB_2U(SCH_1):PAGE57_I168@PURE_QUANTA.SOCKET4677_AZIF0045P001C01CS(CHIPS)':
 'DDR6_SA_DQ18': CDS_PINID='DDR6_SA_DQ18';
NODE_NAME     J29 174
 '@S9S_MB_2U_LIB.S9S_MB_2U(SCH_1):PAGE110_I179@PURE_QUANTA.SCONN288_ADR50017P130CC(CHIPS)':
 'DQ18_A': CDS_PINID='DQ18_A';
NODE_NAME     J30 174
 '@S9S_MB_2U_LIB.S9S_MB_2U(SCH_1):PAGE111_I179@PURE_QUANTA.SCONN288_ADR50017P087CC(CHIPS)':
 'DQ18_A': CDS_PINID='DQ18_A';
NET_NAME
'M_G_CPU1_SA_DQ<19>'
 '@S9S_MB_2U_LIB.S9S_MB_2U(SCH_1):M_G_CPU1_SA_DQ'<19>:
 C_SIGNAL='@s9s_mb_2u_lib.s9s_mb_2u(sch_1):m_g_cpu1_sa_dq(19)';
NODE_NAME     U1 EA62
 '@S9S_MB_2U_LIB.S9S_MB_2U(SCH_1):PAGE57_I168@PURE_QUANTA.SOCKET4677_AZIF0045P001C01CS(CHIPS)':
 'DDR6_SA_DQ19': CDS_PINID='DDR6_SA_DQ19';
NODE_NAME     J29 176
 '@S9S_MB_2U_LIB.S9S_MB_2U(SCH_1):PAGE110_I179@PURE_QUANTA.SCONN288_ADR50017P130CC(CHIPS)':
 'DQ19_A': CDS_PINID='DQ19_A';
NODE_NAME     J30 176
 '@S9S_MB_2U_LIB.S9S_MB_2U(SCH_1):PAGE111_I179@PURE_QUANTA.SCONN288_ADR50017P087CC(CHIPS)':
 'DQ19_A': CDS_PINID='DQ19_A';
NET_NAME
'M_G_CPU1_SA_DQ<1>'
 '@S9S_MB_2U_LIB.S9S_MB_2U(SCH_1):M_G_CPU1_SA_DQ'<1>:
 C_SIGNAL='@s9s_mb_2u_lib.s9s_mb_2u(sch_1):m_g_cpu1_sa_dq(1)';
NODE_NAME     U1 DU74
 '@S9S_MB_2U_LIB.S9S_MB_2U(SCH_1):PAGE57_I168@PURE_QUANTA.SOCKET4677_AZIF0045P001C01CS(CHIPS)':
 'DDR6_SA_DQ1': CDS_PINID='DDR6_SA_DQ1';
NODE_NAME     J29 9
 '@S9S_MB_2U_LIB.S9S_MB_2U(SCH_1):PAGE110_I179@PURE_QUANTA.SCONN288_ADR50017P130CC(CHIPS)':
 'DQ1_A': CDS_PINID='DQ1_A';
NODE_NAME     J30 9
 '@S9S_MB_2U_LIB.S9S_MB_2U(SCH_1):PAGE111_I179@PURE_QUANTA.SCONN288_ADR50017P087CC(CHIPS)':
 'DQ1_A': CDS_PINID='DQ1_A';
NET_NAME
'M_G_CPU1_SA_DQ<20>'
 '@S9S_MB_2U_LIB.S9S_MB_2U(SCH_1):M_G_CPU1_SA_DQ'<20>:
 C_SIGNAL='@s9s_mb_2u_lib.s9s_mb_2u(sch_1):m_g_cpu1_sa_dq(20)';
NODE_NAME     U1 DU60
 '@S9S_MB_2U_LIB.S9S_MB_2U(SCH_1):PAGE57_I168@PURE_QUANTA.SOCKET4677_AZIF0045P001C01CS(CHIPS)':
 'DDR6_SA_DQ20': CDS_PINID='DDR6_SA_DQ20';
NODE_NAME     J29 36
 '@S9S_MB_2U_LIB.S9S_MB_2U(SCH_1):PAGE110_I179@PURE_QUANTA.SCONN288_ADR50017P130CC(CHIPS)':
 'DQ20_A': CDS_PINID='DQ20_A';
NODE_NAME     J30 36
 '@S9S_MB_2U_LIB.S9S_MB_2U(SCH_1):PAGE111_I179@PURE_QUANTA.SCONN288_ADR50017P087CC(CHIPS)':
 'DQ20_A': CDS_PINID='DQ20_A';
NET_NAME
'M_G_CPU1_SA_DQ<21>'
 '@S9S_MB_2U_LIB.S9S_MB_2U(SCH_1):M_G_CPU1_SA_DQ'<21>:
 C_SIGNAL='@s9s_mb_2u_lib.s9s_mb_2u(sch_1):m_g_cpu1_sa_dq(21)';
NODE_NAME     U1 DV59
 '@S9S_MB_2U_LIB.S9S_MB_2U(SCH_1):PAGE57_I168@PURE_QUANTA.SOCKET4677_AZIF0045P001C01CS(CHIPS)':
 'DDR6_SA_DQ21': CDS_PINID='DDR6_SA_DQ21';
NODE_NAME     J29 38
 '@S9S_MB_2U_LIB.S9S_MB_2U(SCH_1):PAGE110_I179@PURE_QUANTA.SCONN288_ADR50017P130CC(CHIPS)':
 'DQ21_A': CDS_PINID='DQ21_A';
NODE_NAME     J30 38
 '@S9S_MB_2U_LIB.S9S_MB_2U(SCH_1):PAGE111_I179@PURE_QUANTA.SCONN288_ADR50017P087CC(CHIPS)':
 'DQ21_A': CDS_PINID='DQ21_A';
NET_NAME
'M_G_CPU1_SA_DQ<22>'
 '@S9S_MB_2U_LIB.S9S_MB_2U(SCH_1):M_G_CPU1_SA_DQ'<22>:
 C_SIGNAL='@s9s_mb_2u_lib.s9s_mb_2u(sch_1):m_g_cpu1_sa_dq(22)';
NODE_NAME     U1 EA60
 '@S9S_MB_2U_LIB.S9S_MB_2U(SCH_1):PAGE57_I168@PURE_QUANTA.SOCKET4677_AZIF0045P001C01CS(CHIPS)':
 'DDR6_SA_DQ22': CDS_PINID='DDR6_SA_DQ22';
NODE_NAME     J29 181
 '@S9S_MB_2U_LIB.S9S_MB_2U(SCH_1):PAGE110_I179@PURE_QUANTA.SCONN288_ADR50017P130CC(CHIPS)':
 'DQ22_A': CDS_PINID='DQ22_A';
NODE_NAME     J30 181
 '@S9S_MB_2U_LIB.S9S_MB_2U(SCH_1):PAGE111_I179@PURE_QUANTA.SCONN288_ADR50017P087CC(CHIPS)':
 'DQ22_A': CDS_PINID='DQ22_A';
NET_NAME
'M_G_CPU1_SA_DQ<23>'
 '@S9S_MB_2U_LIB.S9S_MB_2U(SCH_1):M_G_CPU1_SA_DQ'<23>:
 C_SIGNAL='@s9s_mb_2u_lib.s9s_mb_2u(sch_1):m_g_cpu1_sa_dq(23)';
NODE_NAME     U1 DY59
 '@S9S_MB_2U_LIB.S9S_MB_2U(SCH_1):PAGE57_I168@PURE_QUANTA.SOCKET4677_AZIF0045P001C01CS(CHIPS)':
 'DDR6_SA_DQ23': CDS_PINID='DDR6_SA_DQ23';
NODE_NAME     J29 183
 '@S9S_MB_2U_LIB.S9S_MB_2U(SCH_1):PAGE110_I179@PURE_QUANTA.SCONN288_ADR50017P130CC(CHIPS)':
 'DQ23_A': CDS_PINID='DQ23_A';
NODE_NAME     J30 183
 '@S9S_MB_2U_LIB.S9S_MB_2U(SCH_1):PAGE111_I179@PURE_QUANTA.SCONN288_ADR50017P087CC(CHIPS)':
 'DQ23_A': CDS_PINID='DQ23_A';
NET_NAME
'M_G_CPU1_SA_DQ<24>'
 '@S9S_MB_2U_LIB.S9S_MB_2U(SCH_1):M_G_CPU1_SA_DQ'<24>:
 C_SIGNAL='@s9s_mb_2u_lib.s9s_mb_2u(sch_1):m_g_cpu1_sa_dq(24)';
NODE_NAME     U1 DL66
 '@S9S_MB_2U_LIB.S9S_MB_2U(SCH_1):PAGE57_I168@PURE_QUANTA.SOCKET4677_AZIF0045P001C01CS(CHIPS)':
 'DDR6_SA_DQ24': CDS_PINID='DDR6_SA_DQ24';
NODE_NAME     J29 40
 '@S9S_MB_2U_LIB.S9S_MB_2U(SCH_1):PAGE110_I179@PURE_QUANTA.SCONN288_ADR50017P130CC(CHIPS)':
 'DQ24_A': CDS_PINID='DQ24_A';
NODE_NAME     J30 40
 '@S9S_MB_2U_LIB.S9S_MB_2U(SCH_1):PAGE111_I179@PURE_QUANTA.SCONN288_ADR50017P087CC(CHIPS)':
 'DQ24_A': CDS_PINID='DQ24_A';
NET_NAME
'M_G_CPU1_SA_DQ<25>'
 '@S9S_MB_2U_LIB.S9S_MB_2U(SCH_1):M_G_CPU1_SA_DQ'<25>:
 C_SIGNAL='@s9s_mb_2u_lib.s9s_mb_2u(sch_1):m_g_cpu1_sa_dq(25)';
NODE_NAME     U1 DK65
 '@S9S_MB_2U_LIB.S9S_MB_2U(SCH_1):PAGE57_I168@PURE_QUANTA.SOCKET4677_AZIF0045P001C01CS(CHIPS)':
 'DDR6_SA_DQ25': CDS_PINID='DDR6_SA_DQ25';
NODE_NAME     J29 42
 '@S9S_MB_2U_LIB.S9S_MB_2U(SCH_1):PAGE110_I179@PURE_QUANTA.SCONN288_ADR50017P130CC(CHIPS)':
 'DQ25_A': CDS_PINID='DQ25_A';
NODE_NAME     J30 42
 '@S9S_MB_2U_LIB.S9S_MB_2U(SCH_1):PAGE111_I179@PURE_QUANTA.SCONN288_ADR50017P087CC(CHIPS)':
 'DQ25_A': CDS_PINID='DQ25_A';
NET_NAME
'M_G_CPU1_SA_DQ<26>'
 '@S9S_MB_2U_LIB.S9S_MB_2U(SCH_1):M_G_CPU1_SA_DQ'<26>:
 C_SIGNAL='@s9s_mb_2u_lib.s9s_mb_2u(sch_1):m_g_cpu1_sa_dq(26)';
NODE_NAME     U1 DN66
 '@S9S_MB_2U_LIB.S9S_MB_2U(SCH_1):PAGE57_I168@PURE_QUANTA.SOCKET4677_AZIF0045P001C01CS(CHIPS)':
 'DDR6_SA_DQ26': CDS_PINID='DDR6_SA_DQ26';
NODE_NAME     J29 185
 '@S9S_MB_2U_LIB.S9S_MB_2U(SCH_1):PAGE110_I179@PURE_QUANTA.SCONN288_ADR50017P130CC(CHIPS)':
 'DQ26_A': CDS_PINID='DQ26_A';
NODE_NAME     J30 185
 '@S9S_MB_2U_LIB.S9S_MB_2U(SCH_1):PAGE111_I179@PURE_QUANTA.SCONN288_ADR50017P087CC(CHIPS)':
 'DQ26_A': CDS_PINID='DQ26_A';
NET_NAME
'M_G_CPU1_SA_DQ<27>'
 '@S9S_MB_2U_LIB.S9S_MB_2U(SCH_1):M_G_CPU1_SA_DQ'<27>:
 C_SIGNAL='@s9s_mb_2u_lib.s9s_mb_2u(sch_1):m_g_cpu1_sa_dq(27)';
NODE_NAME     U1 DP65
 '@S9S_MB_2U_LIB.S9S_MB_2U(SCH_1):PAGE57_I168@PURE_QUANTA.SOCKET4677_AZIF0045P001C01CS(CHIPS)':
 'DDR6_SA_DQ27': CDS_PINID='DDR6_SA_DQ27';
NODE_NAME     J29 187
 '@S9S_MB_2U_LIB.S9S_MB_2U(SCH_1):PAGE110_I179@PURE_QUANTA.SCONN288_ADR50017P130CC(CHIPS)':
 'DQ27_A': CDS_PINID='DQ27_A';
NODE_NAME     J30 187
 '@S9S_MB_2U_LIB.S9S_MB_2U(SCH_1):PAGE111_I179@PURE_QUANTA.SCONN288_ADR50017P087CC(CHIPS)':
 'DQ27_A': CDS_PINID='DQ27_A';
NET_NAME
'M_G_CPU1_SA_DQ<28>'
 '@S9S_MB_2U_LIB.S9S_MB_2U(SCH_1):M_G_CPU1_SA_DQ'<28>:
 C_SIGNAL='@s9s_mb_2u_lib.s9s_mb_2u(sch_1):m_g_cpu1_sa_dq(28)';
NODE_NAME     U1 DK63
 '@S9S_MB_2U_LIB.S9S_MB_2U(SCH_1):PAGE57_I168@PURE_QUANTA.SOCKET4677_AZIF0045P001C01CS(CHIPS)':
 'DDR6_SA_DQ28': CDS_PINID='DDR6_SA_DQ28';
NODE_NAME     J29 47
 '@S9S_MB_2U_LIB.S9S_MB_2U(SCH_1):PAGE110_I179@PURE_QUANTA.SCONN288_ADR50017P130CC(CHIPS)':
 'DQ28_A': CDS_PINID='DQ28_A';
NODE_NAME     J30 47
 '@S9S_MB_2U_LIB.S9S_MB_2U(SCH_1):PAGE111_I179@PURE_QUANTA.SCONN288_ADR50017P087CC(CHIPS)':
 'DQ28_A': CDS_PINID='DQ28_A';
NET_NAME
'M_G_CPU1_SA_DQ<29>'
 '@S9S_MB_2U_LIB.S9S_MB_2U(SCH_1):M_G_CPU1_SA_DQ'<29>:
 C_SIGNAL='@s9s_mb_2u_lib.s9s_mb_2u(sch_1):m_g_cpu1_sa_dq(29)';
NODE_NAME     U1 DL62
 '@S9S_MB_2U_LIB.S9S_MB_2U(SCH_1):PAGE57_I168@PURE_QUANTA.SOCKET4677_AZIF0045P001C01CS(CHIPS)':
 'DDR6_SA_DQ29': CDS_PINID='DDR6_SA_DQ29';
NODE_NAME     J29 49
 '@S9S_MB_2U_LIB.S9S_MB_2U(SCH_1):PAGE110_I179@PURE_QUANTA.SCONN288_ADR50017P130CC(CHIPS)':
 'DQ29_A': CDS_PINID='DQ29_A';
NODE_NAME     J30 49
 '@S9S_MB_2U_LIB.S9S_MB_2U(SCH_1):PAGE111_I179@PURE_QUANTA.SCONN288_ADR50017P087CC(CHIPS)':
 'DQ29_A': CDS_PINID='DQ29_A';
NET_NAME
'M_G_CPU1_SA_DQ<2>'
 '@S9S_MB_2U_LIB.S9S_MB_2U(SCH_1):M_G_CPU1_SA_DQ'<2>:
 C_SIGNAL='@s9s_mb_2u_lib.s9s_mb_2u(sch_1):m_g_cpu1_sa_dq(2)';
NODE_NAME     U1 DY75
 '@S9S_MB_2U_LIB.S9S_MB_2U(SCH_1):PAGE57_I168@PURE_QUANTA.SOCKET4677_AZIF0045P001C01CS(CHIPS)':
 'DDR6_SA_DQ2': CDS_PINID='DDR6_SA_DQ2';
NODE_NAME     J29 152
 '@S9S_MB_2U_LIB.S9S_MB_2U(SCH_1):PAGE110_I179@PURE_QUANTA.SCONN288_ADR50017P130CC(CHIPS)':
 'DQ2_A': CDS_PINID='DQ2_A';
NODE_NAME     J30 152
 '@S9S_MB_2U_LIB.S9S_MB_2U(SCH_1):PAGE111_I179@PURE_QUANTA.SCONN288_ADR50017P087CC(CHIPS)':
 'DQ2_A': CDS_PINID='DQ2_A';
NET_NAME
'M_G_CPU1_SA_DQ<30>'
 '@S9S_MB_2U_LIB.S9S_MB_2U(SCH_1):M_G_CPU1_SA_DQ'<30>:
 C_SIGNAL='@s9s_mb_2u_lib.s9s_mb_2u(sch_1):m_g_cpu1_sa_dq(30)';
NODE_NAME     U1 DP63
 '@S9S_MB_2U_LIB.S9S_MB_2U(SCH_1):PAGE57_I168@PURE_QUANTA.SOCKET4677_AZIF0045P001C01CS(CHIPS)':
 'DDR6_SA_DQ30': CDS_PINID='DDR6_SA_DQ30';
NODE_NAME     J29 192
 '@S9S_MB_2U_LIB.S9S_MB_2U(SCH_1):PAGE110_I179@PURE_QUANTA.SCONN288_ADR50017P130CC(CHIPS)':
 'DQ30_A': CDS_PINID='DQ30_A';
NODE_NAME     J30 192
 '@S9S_MB_2U_LIB.S9S_MB_2U(SCH_1):PAGE111_I179@PURE_QUANTA.SCONN288_ADR50017P087CC(CHIPS)':
 'DQ30_A': CDS_PINID='DQ30_A';
NET_NAME
'M_G_CPU1_SA_DQ<31>'
 '@S9S_MB_2U_LIB.S9S_MB_2U(SCH_1):M_G_CPU1_SA_DQ'<31>:
 C_SIGNAL='@s9s_mb_2u_lib.s9s_mb_2u(sch_1):m_g_cpu1_sa_dq(31)';
NODE_NAME     U1 DN62
 '@S9S_MB_2U_LIB.S9S_MB_2U(SCH_1):PAGE57_I168@PURE_QUANTA.SOCKET4677_AZIF0045P001C01CS(CHIPS)':
 'DDR6_SA_DQ31': CDS_PINID='DDR6_SA_DQ31';
NODE_NAME     J29 194
 '@S9S_MB_2U_LIB.S9S_MB_2U(SCH_1):PAGE110_I179@PURE_QUANTA.SCONN288_ADR50017P130CC(CHIPS)':
 'DQ31_A': CDS_PINID='DQ31_A';
NODE_NAME     J30 194
 '@S9S_MB_2U_LIB.S9S_MB_2U(SCH_1):PAGE111_I179@PURE_QUANTA.SCONN288_ADR50017P087CC(CHIPS)':
 'DQ31_A': CDS_PINID='DQ31_A';
NET_NAME
'M_G_CPU1_SA_DQ<3>'
 '@S9S_MB_2U_LIB.S9S_MB_2U(SCH_1):M_G_CPU1_SA_DQ'<3>:
 C_SIGNAL='@s9s_mb_2u_lib.s9s_mb_2u(sch_1):m_g_cpu1_sa_dq(3)';
NODE_NAME     U1 EA74
 '@S9S_MB_2U_LIB.S9S_MB_2U(SCH_1):PAGE57_I168@PURE_QUANTA.SOCKET4677_AZIF0045P001C01CS(CHIPS)':
 'DDR6_SA_DQ3': CDS_PINID='DDR6_SA_DQ3';
NODE_NAME     J29 154
 '@S9S_MB_2U_LIB.S9S_MB_2U(SCH_1):PAGE110_I179@PURE_QUANTA.SCONN288_ADR50017P130CC(CHIPS)':
 'DQ3_A': CDS_PINID='DQ3_A';
NODE_NAME     J30 154
 '@S9S_MB_2U_LIB.S9S_MB_2U(SCH_1):PAGE111_I179@PURE_QUANTA.SCONN288_ADR50017P087CC(CHIPS)':
 'DQ3_A': CDS_PINID='DQ3_A';
NET_NAME
'M_G_CPU1_SA_DQ<4>'
 '@S9S_MB_2U_LIB.S9S_MB_2U(SCH_1):M_G_CPU1_SA_DQ'<4>:
 C_SIGNAL='@s9s_mb_2u_lib.s9s_mb_2u(sch_1):m_g_cpu1_sa_dq(4)';
NODE_NAME     U1 DU72
 '@S9S_MB_2U_LIB.S9S_MB_2U(SCH_1):PAGE57_I168@PURE_QUANTA.SOCKET4677_AZIF0045P001C01CS(CHIPS)':
 'DDR6_SA_DQ4': CDS_PINID='DDR6_SA_DQ4';
NODE_NAME     J29 14
 '@S9S_MB_2U_LIB.S9S_MB_2U(SCH_1):PAGE110_I179@PURE_QUANTA.SCONN288_ADR50017P130CC(CHIPS)':
 'DQ4_A': CDS_PINID='DQ4_A';
NODE_NAME     J30 14
 '@S9S_MB_2U_LIB.S9S_MB_2U(SCH_1):PAGE111_I179@PURE_QUANTA.SCONN288_ADR50017P087CC(CHIPS)':
 'DQ4_A': CDS_PINID='DQ4_A';
NET_NAME
'M_G_CPU1_SA_DQ<5>'
 '@S9S_MB_2U_LIB.S9S_MB_2U(SCH_1):M_G_CPU1_SA_DQ'<5>:
 C_SIGNAL='@s9s_mb_2u_lib.s9s_mb_2u(sch_1):m_g_cpu1_sa_dq(5)';
NODE_NAME     U1 DV71
 '@S9S_MB_2U_LIB.S9S_MB_2U(SCH_1):PAGE57_I168@PURE_QUANTA.SOCKET4677_AZIF0045P001C01CS(CHIPS)':
 'DDR6_SA_DQ5': CDS_PINID='DDR6_SA_DQ5';
NODE_NAME     J29 16
 '@S9S_MB_2U_LIB.S9S_MB_2U(SCH_1):PAGE110_I179@PURE_QUANTA.SCONN288_ADR50017P130CC(CHIPS)':
 'DQ5_A': CDS_PINID='DQ5_A';
NODE_NAME     J30 16
 '@S9S_MB_2U_LIB.S9S_MB_2U(SCH_1):PAGE111_I179@PURE_QUANTA.SCONN288_ADR50017P087CC(CHIPS)':
 'DQ5_A': CDS_PINID='DQ5_A';
NET_NAME
'M_G_CPU1_SA_DQ<6>'
 '@S9S_MB_2U_LIB.S9S_MB_2U(SCH_1):M_G_CPU1_SA_DQ'<6>:
 C_SIGNAL='@s9s_mb_2u_lib.s9s_mb_2u(sch_1):m_g_cpu1_sa_dq(6)';
NODE_NAME     U1 EA72
 '@S9S_MB_2U_LIB.S9S_MB_2U(SCH_1):PAGE57_I168@PURE_QUANTA.SOCKET4677_AZIF0045P001C01CS(CHIPS)':
 'DDR6_SA_DQ6': CDS_PINID='DDR6_SA_DQ6';
NODE_NAME     J29 159
 '@S9S_MB_2U_LIB.S9S_MB_2U(SCH_1):PAGE110_I179@PURE_QUANTA.SCONN288_ADR50017P130CC(CHIPS)':
 'DQ6_A': CDS_PINID='DQ6_A';
NODE_NAME     J30 159
 '@S9S_MB_2U_LIB.S9S_MB_2U(SCH_1):PAGE111_I179@PURE_QUANTA.SCONN288_ADR50017P087CC(CHIPS)':
 'DQ6_A': CDS_PINID='DQ6_A';
NET_NAME
'M_G_CPU1_SA_DQ<7>'
 '@S9S_MB_2U_LIB.S9S_MB_2U(SCH_1):M_G_CPU1_SA_DQ'<7>:
 C_SIGNAL='@s9s_mb_2u_lib.s9s_mb_2u(sch_1):m_g_cpu1_sa_dq(7)';
NODE_NAME     U1 DY71
 '@S9S_MB_2U_LIB.S9S_MB_2U(SCH_1):PAGE57_I168@PURE_QUANTA.SOCKET4677_AZIF0045P001C01CS(CHIPS)':
 'DDR6_SA_DQ7': CDS_PINID='DDR6_SA_DQ7';
NODE_NAME     J29 161
 '@S9S_MB_2U_LIB.S9S_MB_2U(SCH_1):PAGE110_I179@PURE_QUANTA.SCONN288_ADR50017P130CC(CHIPS)':
 'DQ7_A': CDS_PINID='DQ7_A';
NODE_NAME     J30 161
 '@S9S_MB_2U_LIB.S9S_MB_2U(SCH_1):PAGE111_I179@PURE_QUANTA.SCONN288_ADR50017P087CC(CHIPS)':
 'DQ7_A': CDS_PINID='DQ7_A';
NET_NAME
'M_G_CPU1_SA_DQ<8>'
 '@S9S_MB_2U_LIB.S9S_MB_2U(SCH_1):M_G_CPU1_SA_DQ'<8>:
 C_SIGNAL='@s9s_mb_2u_lib.s9s_mb_2u(sch_1):m_g_cpu1_sa_dq(8)';
NODE_NAME     U1 DL72
 '@S9S_MB_2U_LIB.S9S_MB_2U(SCH_1):PAGE57_I168@PURE_QUANTA.SOCKET4677_AZIF0045P001C01CS(CHIPS)':
 'DDR6_SA_DQ8': CDS_PINID='DDR6_SA_DQ8';
NODE_NAME     J29 18
 '@S9S_MB_2U_LIB.S9S_MB_2U(SCH_1):PAGE110_I179@PURE_QUANTA.SCONN288_ADR50017P130CC(CHIPS)':
 'DQ8_A': CDS_PINID='DQ8_A';
NODE_NAME     J30 18
 '@S9S_MB_2U_LIB.S9S_MB_2U(SCH_1):PAGE111_I179@PURE_QUANTA.SCONN288_ADR50017P087CC(CHIPS)':
 'DQ8_A': CDS_PINID='DQ8_A';
NET_NAME
'M_G_CPU1_SA_DQ<9>'
 '@S9S_MB_2U_LIB.S9S_MB_2U(SCH_1):M_G_CPU1_SA_DQ'<9>:
 C_SIGNAL='@s9s_mb_2u_lib.s9s_mb_2u(sch_1):m_g_cpu1_sa_dq(9)';
NODE_NAME     U1 DK71
 '@S9S_MB_2U_LIB.S9S_MB_2U(SCH_1):PAGE57_I168@PURE_QUANTA.SOCKET4677_AZIF0045P001C01CS(CHIPS)':
 'DDR6_SA_DQ9': CDS_PINID='DDR6_SA_DQ9';
NODE_NAME     J29 20
 '@S9S_MB_2U_LIB.S9S_MB_2U(SCH_1):PAGE110_I179@PURE_QUANTA.SCONN288_ADR50017P130CC(CHIPS)':
 'DQ9_A': CDS_PINID='DQ9_A';
NODE_NAME     J30 20
 '@S9S_MB_2U_LIB.S9S_MB_2U(SCH_1):PAGE111_I179@PURE_QUANTA.SCONN288_ADR50017P087CC(CHIPS)':
 'DQ9_A': CDS_PINID='DQ9_A';
NET_NAME
'M_G_CPU1_SA_DQS_DN<0>'
 '@S9S_MB_2U_LIB.S9S_MB_2U(SCH_1):M_G_CPU1_SA_DQS_DN'<0>:
 C_SIGNAL='@s9s_mb_2u_lib.s9s_mb_2u(sch_1):m_g_cpu1_sa_dqs_dn(0)';
NODE_NAME     U1 DV73
 '@S9S_MB_2U_LIB.S9S_MB_2U(SCH_1):PAGE57_I168@PURE_QUANTA.SOCKET4677_AZIF0045P001C01CS(CHIPS)':
 'DDR6_SA_DQS_DN0': CDS_PINID='DDR6_SA_DQS_DN0';
NODE_NAME     J29 12
 '@S9S_MB_2U_LIB.S9S_MB_2U(SCH_1):PAGE110_I180@PURE_QUANTA.SCONN288_ADR50017P130CC(CHIPS)':
 'DQS0_A_C': CDS_PINID='DQS0_A_C';
NODE_NAME     J30 12
 '@S9S_MB_2U_LIB.S9S_MB_2U(SCH_1):PAGE111_I180@PURE_QUANTA.SCONN288_ADR50017P087CC(CHIPS)':
 'DQS0_A_C': CDS_PINID='DQS0_A_C';
NET_NAME
'M_G_CPU1_SA_DQS_DN<1>'
 '@S9S_MB_2U_LIB.S9S_MB_2U(SCH_1):M_G_CPU1_SA_DQS_DN'<1>:
 C_SIGNAL='@s9s_mb_2u_lib.s9s_mb_2u(sch_1):m_g_cpu1_sa_dqs_dn(1)';
NODE_NAME     U1 DJ70
 '@S9S_MB_2U_LIB.S9S_MB_2U(SCH_1):PAGE57_I168@PURE_QUANTA.SOCKET4677_AZIF0045P001C01CS(CHIPS)':
 'DDR6_SA_DQS_DN1': CDS_PINID='DDR6_SA_DQS_DN1';
NODE_NAME     J29 23
 '@S9S_MB_2U_LIB.S9S_MB_2U(SCH_1):PAGE110_I180@PURE_QUANTA.SCONN288_ADR50017P130CC(CHIPS)':
 'DQS1_A_C': CDS_PINID='DQS1_A_C';
NODE_NAME     J30 23
 '@S9S_MB_2U_LIB.S9S_MB_2U(SCH_1):PAGE111_I180@PURE_QUANTA.SCONN288_ADR50017P087CC(CHIPS)':
 'DQS1_A_C': CDS_PINID='DQS1_A_C';
NET_NAME
'M_G_CPU1_SA_DQS_DN<2>'
 '@S9S_MB_2U_LIB.S9S_MB_2U(SCH_1):M_G_CPU1_SA_DQS_DN'<2>:
 C_SIGNAL='@s9s_mb_2u_lib.s9s_mb_2u(sch_1):m_g_cpu1_sa_dqs_dn(2)';
NODE_NAME     U1 DT61
 '@S9S_MB_2U_LIB.S9S_MB_2U(SCH_1):PAGE57_I168@PURE_QUANTA.SOCKET4677_AZIF0045P001C01CS(CHIPS)':
 'DDR6_SA_DQS_DN2': CDS_PINID='DDR6_SA_DQS_DN2';
NODE_NAME     J29 34
 '@S9S_MB_2U_LIB.S9S_MB_2U(SCH_1):PAGE110_I180@PURE_QUANTA.SCONN288_ADR50017P130CC(CHIPS)':
 'DQS2_A_C': CDS_PINID='DQS2_A_C';
NODE_NAME     J30 34
 '@S9S_MB_2U_LIB.S9S_MB_2U(SCH_1):PAGE111_I180@PURE_QUANTA.SCONN288_ADR50017P087CC(CHIPS)':
 'DQS2_A_C': CDS_PINID='DQS2_A_C';
NET_NAME
'M_G_CPU1_SA_DQS_DN<3>'
 '@S9S_MB_2U_LIB.S9S_MB_2U(SCH_1):M_G_CPU1_SA_DQS_DN'<3>:
 C_SIGNAL='@s9s_mb_2u_lib.s9s_mb_2u(sch_1):m_g_cpu1_sa_dqs_dn(3)';
NODE_NAME     U1 DL64
 '@S9S_MB_2U_LIB.S9S_MB_2U(SCH_1):PAGE57_I168@PURE_QUANTA.SOCKET4677_AZIF0045P001C01CS(CHIPS)':
 'DDR6_SA_DQS_DN3': CDS_PINID='DDR6_SA_DQS_DN3';
NODE_NAME     J29 45
 '@S9S_MB_2U_LIB.S9S_MB_2U(SCH_1):PAGE110_I180@PURE_QUANTA.SCONN288_ADR50017P130CC(CHIPS)':
 'DQS3_A_C': CDS_PINID='DQS3_A_C';
NODE_NAME     J30 45
 '@S9S_MB_2U_LIB.S9S_MB_2U(SCH_1):PAGE111_I180@PURE_QUANTA.SCONN288_ADR50017P087CC(CHIPS)':
 'DQS3_A_C': CDS_PINID='DQS3_A_C';
NET_NAME
'M_G_CPU1_SA_DQS_DN<4>'
 '@S9S_MB_2U_LIB.S9S_MB_2U(SCH_1):M_G_CPU1_SA_DQS_DN'<4>:
 C_SIGNAL='@s9s_mb_2u_lib.s9s_mb_2u(sch_1):m_g_cpu1_sa_dqs_dn(4)';
NODE_NAME     U1 DL58
 '@S9S_MB_2U_LIB.S9S_MB_2U(SCH_1):PAGE57_I168@PURE_QUANTA.SOCKET4677_AZIF0045P001C01CS(CHIPS)':
 'DDR6_SA_DQS_DN4': CDS_PINID='DDR6_SA_DQS_DN4';
NODE_NAME     J29 56
 '@S9S_MB_2U_LIB.S9S_MB_2U(SCH_1):PAGE110_I180@PURE_QUANTA.SCONN288_ADR50017P130CC(CHIPS)':
 'DQS4_A_C': CDS_PINID='DQS4_A_C';
NODE_NAME     J30 56
 '@S9S_MB_2U_LIB.S9S_MB_2U(SCH_1):PAGE111_I180@PURE_QUANTA.SCONN288_ADR50017P087CC(CHIPS)':
 'DQS4_A_C': CDS_PINID='DQS4_A_C';
NET_NAME
'M_G_CPU1_SA_DQS_DN<5>'
 '@S9S_MB_2U_LIB.S9S_MB_2U(SCH_1):M_G_CPU1_SA_DQS_DN'<5>:
 C_SIGNAL='@s9s_mb_2u_lib.s9s_mb_2u(sch_1):m_g_cpu1_sa_dqs_dn(5)';
NODE_NAME     U1 EB73
 '@S9S_MB_2U_LIB.S9S_MB_2U(SCH_1):PAGE57_I168@PURE_QUANTA.SOCKET4677_AZIF0045P001C01CS(CHIPS)':
 'DDR6_SA_DQS_DN5': CDS_PINID='DDR6_SA_DQS_DN5';
NODE_NAME     J29 156
 '@S9S_MB_2U_LIB.S9S_MB_2U(SCH_1):PAGE110_I180@PURE_QUANTA.SCONN288_ADR50017P130CC(CHIPS)':
 'DQS5_A_C||TDQS5_A_C||DQS5_A_T||TDQS5_A_T': CDS_PINID='\dqs5_a_c||tdqs5_a_c||dqs5_a_t||tdqs5_a_t\';
NODE_NAME     J30 156
 '@S9S_MB_2U_LIB.S9S_MB_2U(SCH_1):PAGE111_I180@PURE_QUANTA.SCONN288_ADR50017P087CC(CHIPS)':
 'DQS5_A_C||TDQS5_A_C||DQS5_A_T||TDQS5_A_T': CDS_PINID='\dqs5_a_c||tdqs5_a_c||dqs5_a_t||tdqs5_a_t\';
NET_NAME
'M_G_CPU1_SA_DQS_DN<6>'
 '@S9S_MB_2U_LIB.S9S_MB_2U(SCH_1):M_G_CPU1_SA_DQS_DN'<6>:
 C_SIGNAL='@s9s_mb_2u_lib.s9s_mb_2u(sch_1):m_g_cpu1_sa_dqs_dn(6)';
NODE_NAME     U1 DR70
 '@S9S_MB_2U_LIB.S9S_MB_2U(SCH_1):PAGE57_I168@PURE_QUANTA.SOCKET4677_AZIF0045P001C01CS(CHIPS)':
 'DDR6_SA_DQS_DN6': CDS_PINID='DDR6_SA_DQS_DN6';
NODE_NAME     J29 167
 '@S9S_MB_2U_LIB.S9S_MB_2U(SCH_1):PAGE110_I180@PURE_QUANTA.SCONN288_ADR50017P130CC(CHIPS)':
 'DQS6_A_C||TDQS6_A_C||DQS6_A_T||TDQS6_A_T': CDS_PINID='\dqs6_a_c||tdqs6_a_c||dqs6_a_t||tdqs6_a_t\';
NODE_NAME     J30 167
 '@S9S_MB_2U_LIB.S9S_MB_2U(SCH_1):PAGE111_I180@PURE_QUANTA.SCONN288_ADR50017P087CC(CHIPS)':
 'DQS6_A_C||TDQS6_A_C||DQS6_A_T||TDQS6_A_T': CDS_PINID='\dqs6_a_c||tdqs6_a_c||dqs6_a_t||tdqs6_a_t\';
NET_NAME
'M_G_CPU1_SA_DQS_DN<7>'
 '@S9S_MB_2U_LIB.S9S_MB_2U(SCH_1):M_G_CPU1_SA_DQS_DN'<7>:
 C_SIGNAL='@s9s_mb_2u_lib.s9s_mb_2u(sch_1):m_g_cpu1_sa_dqs_dn(7)';
NODE_NAME     U1 EB61
 '@S9S_MB_2U_LIB.S9S_MB_2U(SCH_1):PAGE57_I168@PURE_QUANTA.SOCKET4677_AZIF0045P001C01CS(CHIPS)':
 'DDR6_SA_DQS_DN7': CDS_PINID='DDR6_SA_DQS_DN7';
NODE_NAME     J29 178
 '@S9S_MB_2U_LIB.S9S_MB_2U(SCH_1):PAGE110_I180@PURE_QUANTA.SCONN288_ADR50017P130CC(CHIPS)':
 'DQS7_A_C||TDQS7_A_C': CDS_PINID='\dqs7_a_c||tdqs7_a_c\';
NODE_NAME     J30 178
 '@S9S_MB_2U_LIB.S9S_MB_2U(SCH_1):PAGE111_I180@PURE_QUANTA.SCONN288_ADR50017P087CC(CHIPS)':
 'DQS7_A_C||TDQS7_A_C': CDS_PINID='\dqs7_a_c||tdqs7_a_c\';
NET_NAME
'M_G_CPU1_SA_DQS_DN<8>'
 '@S9S_MB_2U_LIB.S9S_MB_2U(SCH_1):M_G_CPU1_SA_DQS_DN'<8>:
 C_SIGNAL='@s9s_mb_2u_lib.s9s_mb_2u(sch_1):m_g_cpu1_sa_dqs_dn(8)';
NODE_NAME     U1 DR64
 '@S9S_MB_2U_LIB.S9S_MB_2U(SCH_1):PAGE57_I168@PURE_QUANTA.SOCKET4677_AZIF0045P001C01CS(CHIPS)':
 'DDR6_SA_DQS_DN8': CDS_PINID='DDR6_SA_DQS_DN8';
NODE_NAME     J29 189
 '@S9S_MB_2U_LIB.S9S_MB_2U(SCH_1):PAGE110_I180@PURE_QUANTA.SCONN288_ADR50017P130CC(CHIPS)':
 'DQS8_A_C||TDQS8_A_C': CDS_PINID='\dqs8_a_c||tdqs8_a_c\';
NODE_NAME     J30 189
 '@S9S_MB_2U_LIB.S9S_MB_2U(SCH_1):PAGE111_I180@PURE_QUANTA.SCONN288_ADR50017P087CC(CHIPS)':
 'DQS8_A_C||TDQS8_A_C': CDS_PINID='\dqs8_a_c||tdqs8_a_c\';
NET_NAME
'M_G_CPU1_SA_DQS_DN<9>'
 '@S9S_MB_2U_LIB.S9S_MB_2U(SCH_1):M_G_CPU1_SA_DQS_DN'<9>:
 C_SIGNAL='@s9s_mb_2u_lib.s9s_mb_2u(sch_1):m_g_cpu1_sa_dqs_dn(9)';
NODE_NAME     U1 DR58
 '@S9S_MB_2U_LIB.S9S_MB_2U(SCH_1):PAGE57_I168@PURE_QUANTA.SOCKET4677_AZIF0045P001C01CS(CHIPS)':
 'DDR6_SA_DQS_DN9': CDS_PINID='DDR6_SA_DQS_DN9';
NODE_NAME     J29 200
 '@S9S_MB_2U_LIB.S9S_MB_2U(SCH_1):PAGE110_I180@PURE_QUANTA.SCONN288_ADR50017P130CC(CHIPS)':
 'DQS9_A_C||TDQS9_A_C': CDS_PINID='\dqs9_a_c||tdqs9_a_c\';
NODE_NAME     J30 200
 '@S9S_MB_2U_LIB.S9S_MB_2U(SCH_1):PAGE111_I180@PURE_QUANTA.SCONN288_ADR50017P087CC(CHIPS)':
 'DQS9_A_C||TDQS9_A_C': CDS_PINID='\dqs9_a_c||tdqs9_a_c\';
NET_NAME
'M_G_CPU1_SA_DQS_DP<0>'
 '@S9S_MB_2U_LIB.S9S_MB_2U(SCH_1):M_G_CPU1_SA_DQS_DP'<0>:
 C_SIGNAL='@s9s_mb_2u_lib.s9s_mb_2u(sch_1):m_g_cpu1_sa_dqs_dp(0)';
NODE_NAME     U1 DT73
 '@S9S_MB_2U_LIB.S9S_MB_2U(SCH_1):PAGE57_I168@PURE_QUANTA.SOCKET4677_AZIF0045P001C01CS(CHIPS)':
 'DDR6_SA_DQS_DP0': CDS_PINID='DDR6_SA_DQS_DP0';
NODE_NAME     J29 11
 '@S9S_MB_2U_LIB.S9S_MB_2U(SCH_1):PAGE110_I180@PURE_QUANTA.SCONN288_ADR50017P130CC(CHIPS)':
 'DQS0_A_T': CDS_PINID='DQS0_A_T';
NODE_NAME     J30 11
 '@S9S_MB_2U_LIB.S9S_MB_2U(SCH_1):PAGE111_I180@PURE_QUANTA.SCONN288_ADR50017P087CC(CHIPS)':
 'DQS0_A_T': CDS_PINID='DQS0_A_T';
NET_NAME
'M_G_CPU1_SA_DQS_DP<1>'
 '@S9S_MB_2U_LIB.S9S_MB_2U(SCH_1):M_G_CPU1_SA_DQS_DP'<1>:
 C_SIGNAL='@s9s_mb_2u_lib.s9s_mb_2u(sch_1):m_g_cpu1_sa_dqs_dp(1)';
NODE_NAME     U1 DL70
 '@S9S_MB_2U_LIB.S9S_MB_2U(SCH_1):PAGE57_I168@PURE_QUANTA.SOCKET4677_AZIF0045P001C01CS(CHIPS)':
 'DDR6_SA_DQS_DP1': CDS_PINID='DDR6_SA_DQS_DP1';
NODE_NAME     J29 22
 '@S9S_MB_2U_LIB.S9S_MB_2U(SCH_1):PAGE110_I180@PURE_QUANTA.SCONN288_ADR50017P130CC(CHIPS)':
 'DQS1_A_T': CDS_PINID='DQS1_A_T';
NODE_NAME     J30 22
 '@S9S_MB_2U_LIB.S9S_MB_2U(SCH_1):PAGE111_I180@PURE_QUANTA.SCONN288_ADR50017P087CC(CHIPS)':
 'DQS1_A_T': CDS_PINID='DQS1_A_T';
NET_NAME
'M_G_CPU1_SA_DQS_DP<2>'
 '@S9S_MB_2U_LIB.S9S_MB_2U(SCH_1):M_G_CPU1_SA_DQS_DP'<2>:
 C_SIGNAL='@s9s_mb_2u_lib.s9s_mb_2u(sch_1):m_g_cpu1_sa_dqs_dp(2)';
NODE_NAME     U1 DV61
 '@S9S_MB_2U_LIB.S9S_MB_2U(SCH_1):PAGE57_I168@PURE_QUANTA.SOCKET4677_AZIF0045P001C01CS(CHIPS)':
 'DDR6_SA_DQS_DP2': CDS_PINID='DDR6_SA_DQS_DP2';
NODE_NAME     J29 33
 '@S9S_MB_2U_LIB.S9S_MB_2U(SCH_1):PAGE110_I180@PURE_QUANTA.SCONN288_ADR50017P130CC(CHIPS)':
 'DQS2_A_T': CDS_PINID='DQS2_A_T';
NODE_NAME     J30 33
 '@S9S_MB_2U_LIB.S9S_MB_2U(SCH_1):PAGE111_I180@PURE_QUANTA.SCONN288_ADR50017P087CC(CHIPS)':
 'DQS2_A_T': CDS_PINID='DQS2_A_T';
NET_NAME
'M_G_CPU1_SA_DQS_DP<3>'
 '@S9S_MB_2U_LIB.S9S_MB_2U(SCH_1):M_G_CPU1_SA_DQS_DP'<3>:
 C_SIGNAL='@s9s_mb_2u_lib.s9s_mb_2u(sch_1):m_g_cpu1_sa_dqs_dp(3)';
NODE_NAME     U1 DJ64
 '@S9S_MB_2U_LIB.S9S_MB_2U(SCH_1):PAGE57_I168@PURE_QUANTA.SOCKET4677_AZIF0045P001C01CS(CHIPS)':
 'DDR6_SA_DQS_DP3': CDS_PINID='DDR6_SA_DQS_DP3';
NODE_NAME     J29 44
 '@S9S_MB_2U_LIB.S9S_MB_2U(SCH_1):PAGE110_I180@PURE_QUANTA.SCONN288_ADR50017P130CC(CHIPS)':
 'DQS3_A_T': CDS_PINID='DQS3_A_T';
NODE_NAME     J30 44
 '@S9S_MB_2U_LIB.S9S_MB_2U(SCH_1):PAGE111_I180@PURE_QUANTA.SCONN288_ADR50017P087CC(CHIPS)':
 'DQS3_A_T': CDS_PINID='DQS3_A_T';
NET_NAME
'M_G_CPU1_SA_DQS_DP<4>'
 '@S9S_MB_2U_LIB.S9S_MB_2U(SCH_1):M_G_CPU1_SA_DQS_DP'<4>:
 C_SIGNAL='@s9s_mb_2u_lib.s9s_mb_2u(sch_1):m_g_cpu1_sa_dqs_dp(4)';
NODE_NAME     U1 DJ58
 '@S9S_MB_2U_LIB.S9S_MB_2U(SCH_1):PAGE57_I168@PURE_QUANTA.SOCKET4677_AZIF0045P001C01CS(CHIPS)':
 'DDR6_SA_DQS_DP4': CDS_PINID='DDR6_SA_DQS_DP4';
NODE_NAME     J29 55
 '@S9S_MB_2U_LIB.S9S_MB_2U(SCH_1):PAGE110_I180@PURE_QUANTA.SCONN288_ADR50017P130CC(CHIPS)':
 'DQS4_A_T': CDS_PINID='DQS4_A_T';
NODE_NAME     J30 55
 '@S9S_MB_2U_LIB.S9S_MB_2U(SCH_1):PAGE111_I180@PURE_QUANTA.SCONN288_ADR50017P087CC(CHIPS)':
 'DQS4_A_T': CDS_PINID='DQS4_A_T';
NET_NAME
'M_G_CPU1_SA_DQS_DP<5>'
 '@S9S_MB_2U_LIB.S9S_MB_2U(SCH_1):M_G_CPU1_SA_DQS_DP'<5>:
 C_SIGNAL='@s9s_mb_2u_lib.s9s_mb_2u(sch_1):m_g_cpu1_sa_dqs_dp(5)';
NODE_NAME     U1 DY73
 '@S9S_MB_2U_LIB.S9S_MB_2U(SCH_1):PAGE57_I168@PURE_QUANTA.SOCKET4677_AZIF0045P001C01CS(CHIPS)':
 'DDR6_SA_DQS_DP5': CDS_PINID='DDR6_SA_DQS_DP5';
NODE_NAME     J29 157
 '@S9S_MB_2U_LIB.S9S_MB_2U(SCH_1):PAGE110_I180@PURE_QUANTA.SCONN288_ADR50017P130CC(CHIPS)':
 'DQS5_A_T||TDQS5_A_T': CDS_PINID='\dqs5_a_t||tdqs5_a_t\';
NODE_NAME     J30 157
 '@S9S_MB_2U_LIB.S9S_MB_2U(SCH_1):PAGE111_I180@PURE_QUANTA.SCONN288_ADR50017P087CC(CHIPS)':
 'DQS5_A_T||TDQS5_A_T': CDS_PINID='\dqs5_a_t||tdqs5_a_t\';
NET_NAME
'M_G_CPU1_SA_DQS_DP<6>'
 '@S9S_MB_2U_LIB.S9S_MB_2U(SCH_1):M_G_CPU1_SA_DQS_DP'<6>:
 C_SIGNAL='@s9s_mb_2u_lib.s9s_mb_2u(sch_1):m_g_cpu1_sa_dqs_dp(6)';
NODE_NAME     U1 DN70
 '@S9S_MB_2U_LIB.S9S_MB_2U(SCH_1):PAGE57_I168@PURE_QUANTA.SOCKET4677_AZIF0045P001C01CS(CHIPS)':
 'DDR6_SA_DQS_DP6': CDS_PINID='DDR6_SA_DQS_DP6';
NODE_NAME     J29 168
 '@S9S_MB_2U_LIB.S9S_MB_2U(SCH_1):PAGE110_I180@PURE_QUANTA.SCONN288_ADR50017P130CC(CHIPS)':
 'DQS6_A_T||TDQS6_A_T': CDS_PINID='\dqs6_a_t||tdqs6_a_t\';
NODE_NAME     J30 168
 '@S9S_MB_2U_LIB.S9S_MB_2U(SCH_1):PAGE111_I180@PURE_QUANTA.SCONN288_ADR50017P087CC(CHIPS)':
 'DQS6_A_T||TDQS6_A_T': CDS_PINID='\dqs6_a_t||tdqs6_a_t\';
NET_NAME
'M_G_CPU1_SA_DQS_DP<7>'
 '@S9S_MB_2U_LIB.S9S_MB_2U(SCH_1):M_G_CPU1_SA_DQS_DP'<7>:
 C_SIGNAL='@s9s_mb_2u_lib.s9s_mb_2u(sch_1):m_g_cpu1_sa_dqs_dp(7)';
NODE_NAME     U1 DY61
 '@S9S_MB_2U_LIB.S9S_MB_2U(SCH_1):PAGE57_I168@PURE_QUANTA.SOCKET4677_AZIF0045P001C01CS(CHIPS)':
 'DDR6_SA_DQS_DP7': CDS_PINID='DDR6_SA_DQS_DP7';
NODE_NAME     J29 179
 '@S9S_MB_2U_LIB.S9S_MB_2U(SCH_1):PAGE110_I180@PURE_QUANTA.SCONN288_ADR50017P130CC(CHIPS)':
 'DQS7_A_T||TDQS7_A_T': CDS_PINID='\dqs7_a_t||tdqs7_a_t\';
NODE_NAME     J30 179
 '@S9S_MB_2U_LIB.S9S_MB_2U(SCH_1):PAGE111_I180@PURE_QUANTA.SCONN288_ADR50017P087CC(CHIPS)':
 'DQS7_A_T||TDQS7_A_T': CDS_PINID='\dqs7_a_t||tdqs7_a_t\';
NET_NAME
'M_G_CPU1_SA_DQS_DP<8>'
 '@S9S_MB_2U_LIB.S9S_MB_2U(SCH_1):M_G_CPU1_SA_DQS_DP'<8>:
 C_SIGNAL='@s9s_mb_2u_lib.s9s_mb_2u(sch_1):m_g_cpu1_sa_dqs_dp(8)';
NODE_NAME     U1 DN64
 '@S9S_MB_2U_LIB.S9S_MB_2U(SCH_1):PAGE57_I168@PURE_QUANTA.SOCKET4677_AZIF0045P001C01CS(CHIPS)':
 'DDR6_SA_DQS_DP8': CDS_PINID='DDR6_SA_DQS_DP8';
NODE_NAME     J29 190
 '@S9S_MB_2U_LIB.S9S_MB_2U(SCH_1):PAGE110_I180@PURE_QUANTA.SCONN288_ADR50017P130CC(CHIPS)':
 'DQS8_A_T||TDQS8_A_T': CDS_PINID='\dqs8_a_t||tdqs8_a_t\';
NODE_NAME     J30 190
 '@S9S_MB_2U_LIB.S9S_MB_2U(SCH_1):PAGE111_I180@PURE_QUANTA.SCONN288_ADR50017P087CC(CHIPS)':
 'DQS8_A_T||TDQS8_A_T': CDS_PINID='\dqs8_a_t||tdqs8_a_t\';
NET_NAME
'M_G_CPU1_SA_DQS_DP<9>'
 '@S9S_MB_2U_LIB.S9S_MB_2U(SCH_1):M_G_CPU1_SA_DQS_DP'<9>:
 C_SIGNAL='@s9s_mb_2u_lib.s9s_mb_2u(sch_1):m_g_cpu1_sa_dqs_dp(9)';
NODE_NAME     U1 DN58
 '@S9S_MB_2U_LIB.S9S_MB_2U(SCH_1):PAGE57_I168@PURE_QUANTA.SOCKET4677_AZIF0045P001C01CS(CHIPS)':
 'DDR6_SA_DQS_DP9': CDS_PINID='DDR6_SA_DQS_DP9';
NODE_NAME     J29 201
 '@S9S_MB_2U_LIB.S9S_MB_2U(SCH_1):PAGE110_I180@PURE_QUANTA.SCONN288_ADR50017P130CC(CHIPS)':
 'DQS9_A_T||TDQS9_A_T': CDS_PINID='\dqs9_a_t||tdqs9_a_t\';
NODE_NAME     J30 201
 '@S9S_MB_2U_LIB.S9S_MB_2U(SCH_1):PAGE111_I180@PURE_QUANTA.SCONN288_ADR50017P087CC(CHIPS)':
 'DQS9_A_T||TDQS9_A_T': CDS_PINID='\dqs9_a_t||tdqs9_a_t\';
NET_NAME
'M_G_CPU1_SA_PAR'
 '@S9S_MB_2U_LIB.S9S_MB_2U(SCH_1):M_G_CPU1_SA_PAR':
 C_SIGNAL='@s9s_mb_2u_lib.s9s_mb_2u(sch_1):m_g_cpu1_sa_par';
NODE_NAME     U1 DL43
 '@S9S_MB_2U_LIB.S9S_MB_2U(SCH_1):PAGE57_I168@PURE_QUANTA.SOCKET4677_AZIF0045P001C01CS(CHIPS)':
 'DDR6_SA_PAR': CDS_PINID='DDR6_SA_PAR';
NODE_NAME     J29 74
 '@S9S_MB_2U_LIB.S9S_MB_2U(SCH_1):PAGE110_I179@PURE_QUANTA.SCONN288_ADR50017P130CC(CHIPS)':
 'PAR_A': CDS_PINID='PAR_A';
NODE_NAME     J30 74
 '@S9S_MB_2U_LIB.S9S_MB_2U(SCH_1):PAGE111_I179@PURE_QUANTA.SCONN288_ADR50017P087CC(CHIPS)':
 'PAR_A': CDS_PINID='PAR_A';
NET_NAME
'M_G_CPU1_SA_RSP<0>'
 '@S9S_MB_2U_LIB.S9S_MB_2U(SCH_1):M_G_CPU1_SA_RSP'<0>:
 C_SIGNAL='@s9s_mb_2u_lib.s9s_mb_2u(sch_1):m_g_cpu1_sa_rsp(0)';
NODE_NAME     U1 EA48
 '@S9S_MB_2U_LIB.S9S_MB_2U(SCH_1):PAGE57_I168@PURE_QUANTA.SOCKET4677_AZIF0045P001C01CS(CHIPS)':
 'DDR6_A_RSP0': CDS_PINID='DDR6_A_RSP0';
NODE_NAME     J29 86
 '@S9S_MB_2U_LIB.S9S_MB_2U(SCH_1):PAGE110_I179@PURE_QUANTA.SCONN288_ADR50017P130CC(CHIPS)':
 'LBD||RSP_A_N': CDS_PINID='\lbd||rsp_a_n\';
NET_NAME
'M_G_CPU1_SA_RSP<1>'
 '@S9S_MB_2U_LIB.S9S_MB_2U(SCH_1):M_G_CPU1_SA_RSP'<1>:
 C_SIGNAL='@s9s_mb_2u_lib.s9s_mb_2u(sch_1):m_g_cpu1_sa_rsp(1)';
NODE_NAME     U1 DY47
 '@S9S_MB_2U_LIB.S9S_MB_2U(SCH_1):PAGE57_I168@PURE_QUANTA.SOCKET4677_AZIF0045P001C01CS(CHIPS)':
 'DDR6_A_RSP1': CDS_PINID='DDR6_A_RSP1';
NODE_NAME     J30 86
 '@S9S_MB_2U_LIB.S9S_MB_2U(SCH_1):PAGE111_I179@PURE_QUANTA.SCONN288_ADR50017P087CC(CHIPS)':
 'LBD||RSP_A_N': CDS_PINID='\lbd||rsp_a_n\';
NET_NAME
'M_G_CPU1_SB_CA<0>'
 '@S9S_MB_2U_LIB.S9S_MB_2U(SCH_1):M_G_CPU1_SB_CA'<0>:
 C_SIGNAL='@s9s_mb_2u_lib.s9s_mb_2u(sch_1):m_g_cpu1_sb_ca(0)';
NODE_NAME     U1 DN43
 '@S9S_MB_2U_LIB.S9S_MB_2U(SCH_1):PAGE57_I168@PURE_QUANTA.SOCKET4677_AZIF0045P001C01CS(CHIPS)':
 'DDR6_SB_CA0': CDS_PINID='DDR6_SB_CA0';
NODE_NAME     J29 76
 '@S9S_MB_2U_LIB.S9S_MB_2U(SCH_1):PAGE110_I179@PURE_QUANTA.SCONN288_ADR50017P130CC(CHIPS)':
 'CA0_B': CDS_PINID='CA0_B';
NODE_NAME     J30 76
 '@S9S_MB_2U_LIB.S9S_MB_2U(SCH_1):PAGE111_I179@PURE_QUANTA.SCONN288_ADR50017P087CC(CHIPS)':
 'CA0_B': CDS_PINID='CA0_B';
NET_NAME
'M_G_CPU1_SB_CA<1>'
 '@S9S_MB_2U_LIB.S9S_MB_2U(SCH_1):M_G_CPU1_SB_CA'<1>:
 C_SIGNAL='@s9s_mb_2u_lib.s9s_mb_2u(sch_1):m_g_cpu1_sb_ca(1)';
NODE_NAME     U1 DP44
 '@S9S_MB_2U_LIB.S9S_MB_2U(SCH_1):PAGE57_I168@PURE_QUANTA.SOCKET4677_AZIF0045P001C01CS(CHIPS)':
 'DDR6_SB_CA1': CDS_PINID='DDR6_SB_CA1';
NODE_NAME     J29 221
 '@S9S_MB_2U_LIB.S9S_MB_2U(SCH_1):PAGE110_I179@PURE_QUANTA.SCONN288_ADR50017P130CC(CHIPS)':
 'CA1_B': CDS_PINID='CA1_B';
NODE_NAME     J30 221
 '@S9S_MB_2U_LIB.S9S_MB_2U(SCH_1):PAGE111_I179@PURE_QUANTA.SCONN288_ADR50017P087CC(CHIPS)':
 'CA1_B': CDS_PINID='CA1_B';
NET_NAME
'M_G_CPU1_SB_CA<2>'
 '@S9S_MB_2U_LIB.S9S_MB_2U(SCH_1):M_G_CPU1_SB_CA'<2>:
 C_SIGNAL='@s9s_mb_2u_lib.s9s_mb_2u(sch_1):m_g_cpu1_sb_ca(2)';
NODE_NAME     U1 DV44
 '@S9S_MB_2U_LIB.S9S_MB_2U(SCH_1):PAGE57_I168@PURE_QUANTA.SOCKET4677_AZIF0045P001C01CS(CHIPS)':
 'DDR6_SB_CA2': CDS_PINID='DDR6_SB_CA2';
NODE_NAME     J29 78
 '@S9S_MB_2U_LIB.S9S_MB_2U(SCH_1):PAGE110_I179@PURE_QUANTA.SCONN288_ADR50017P130CC(CHIPS)':
 'CA2_B': CDS_PINID='CA2_B';
NODE_NAME     J30 78
 '@S9S_MB_2U_LIB.S9S_MB_2U(SCH_1):PAGE111_I179@PURE_QUANTA.SCONN288_ADR50017P087CC(CHIPS)':
 'CA2_B': CDS_PINID='CA2_B';
NET_NAME
'M_G_CPU1_SB_CA<3>'
 '@S9S_MB_2U_LIB.S9S_MB_2U(SCH_1):M_G_CPU1_SB_CA'<3>:
 C_SIGNAL='@s9s_mb_2u_lib.s9s_mb_2u(sch_1):m_g_cpu1_sb_ca(3)';
NODE_NAME     U1 DY44
 '@S9S_MB_2U_LIB.S9S_MB_2U(SCH_1):PAGE57_I168@PURE_QUANTA.SOCKET4677_AZIF0045P001C01CS(CHIPS)':
 'DDR6_SB_CA3': CDS_PINID='DDR6_SB_CA3';
NODE_NAME     J29 223
 '@S9S_MB_2U_LIB.S9S_MB_2U(SCH_1):PAGE110_I179@PURE_QUANTA.SCONN288_ADR50017P130CC(CHIPS)':
 'CA3_B': CDS_PINID='CA3_B';
NODE_NAME     J30 223
 '@S9S_MB_2U_LIB.S9S_MB_2U(SCH_1):PAGE111_I179@PURE_QUANTA.SCONN288_ADR50017P087CC(CHIPS)':
 'CA3_B': CDS_PINID='CA3_B';
NET_NAME
'M_G_CPU1_SB_CA<4>'
 '@S9S_MB_2U_LIB.S9S_MB_2U(SCH_1):M_G_CPU1_SB_CA'<4>:
 C_SIGNAL='@s9s_mb_2u_lib.s9s_mb_2u(sch_1):m_g_cpu1_sb_ca(4)';
NODE_NAME     U1 DU43
 '@S9S_MB_2U_LIB.S9S_MB_2U(SCH_1):PAGE57_I168@PURE_QUANTA.SOCKET4677_AZIF0045P001C01CS(CHIPS)':
 'DDR6_SB_CA4': CDS_PINID='DDR6_SB_CA4';
NODE_NAME     J29 80
 '@S9S_MB_2U_LIB.S9S_MB_2U(SCH_1):PAGE110_I179@PURE_QUANTA.SCONN288_ADR50017P130CC(CHIPS)':
 'CA4_B': CDS_PINID='CA4_B';
NODE_NAME     J30 80
 '@S9S_MB_2U_LIB.S9S_MB_2U(SCH_1):PAGE111_I179@PURE_QUANTA.SCONN288_ADR50017P087CC(CHIPS)':
 'CA4_B': CDS_PINID='CA4_B';
NET_NAME
'M_G_CPU1_SB_CA<5>'
 '@S9S_MB_2U_LIB.S9S_MB_2U(SCH_1):M_G_CPU1_SB_CA'<5>:
 C_SIGNAL='@s9s_mb_2u_lib.s9s_mb_2u(sch_1):m_g_cpu1_sb_ca(5)';
NODE_NAME     U1 EA43
 '@S9S_MB_2U_LIB.S9S_MB_2U(SCH_1):PAGE57_I168@PURE_QUANTA.SOCKET4677_AZIF0045P001C01CS(CHIPS)':
 'DDR6_SB_CA5': CDS_PINID='DDR6_SB_CA5';
NODE_NAME     J29 225
 '@S9S_MB_2U_LIB.S9S_MB_2U(SCH_1):PAGE110_I179@PURE_QUANTA.SCONN288_ADR50017P130CC(CHIPS)':
 'CA5_B': CDS_PINID='CA5_B';
NODE_NAME     J30 225
 '@S9S_MB_2U_LIB.S9S_MB_2U(SCH_1):PAGE111_I179@PURE_QUANTA.SCONN288_ADR50017P087CC(CHIPS)':
 'CA5_B': CDS_PINID='CA5_B';
NET_NAME
'M_G_CPU1_SB_CA<6>'
 '@S9S_MB_2U_LIB.S9S_MB_2U(SCH_1):M_G_CPU1_SB_CA'<6>:
 C_SIGNAL='@s9s_mb_2u_lib.s9s_mb_2u(sch_1):m_g_cpu1_sb_ca(6)';
NODE_NAME     U1 DT42
 '@S9S_MB_2U_LIB.S9S_MB_2U(SCH_1):PAGE57_I168@PURE_QUANTA.SOCKET4677_AZIF0045P001C01CS(CHIPS)':
 'DDR6_SB_CA6': CDS_PINID='DDR6_SB_CA6';
NODE_NAME     J29 82
 '@S9S_MB_2U_LIB.S9S_MB_2U(SCH_1):PAGE110_I179@PURE_QUANTA.SCONN288_ADR50017P130CC(CHIPS)':
 'CA6_B': CDS_PINID='CA6_B';
NODE_NAME     J30 82
 '@S9S_MB_2U_LIB.S9S_MB_2U(SCH_1):PAGE111_I179@PURE_QUANTA.SCONN288_ADR50017P087CC(CHIPS)':
 'CA6_B': CDS_PINID='CA6_B';
NET_NAME
'M_G_CPU1_SB_CB<0>'
 '@S9S_MB_2U_LIB.S9S_MB_2U(SCH_1):M_G_CPU1_SB_CB'<0>:
 C_SIGNAL='@s9s_mb_2u_lib.s9s_mb_2u(sch_1):m_g_cpu1_sb_cb(0)';
NODE_NAME     U1 DU35
 '@S9S_MB_2U_LIB.S9S_MB_2U(SCH_1):PAGE57_I168@PURE_QUANTA.SOCKET4677_AZIF0045P001C01CS(CHIPS)':
 'DDR6_SB_ECC0': CDS_PINID='DDR6_SB_ECC0';
NODE_NAME     J29 96
 '@S9S_MB_2U_LIB.S9S_MB_2U(SCH_1):PAGE110_I179@PURE_QUANTA.SCONN288_ADR50017P130CC(CHIPS)':
 'CB0_B': CDS_PINID='CB0_B';
NODE_NAME     J30 96
 '@S9S_MB_2U_LIB.S9S_MB_2U(SCH_1):PAGE111_I179@PURE_QUANTA.SCONN288_ADR50017P087CC(CHIPS)':
 'CB0_B': CDS_PINID='CB0_B';
NET_NAME
'M_G_CPU1_SB_CB<1>'
 '@S9S_MB_2U_LIB.S9S_MB_2U(SCH_1):M_G_CPU1_SB_CB'<1>:
 C_SIGNAL='@s9s_mb_2u_lib.s9s_mb_2u(sch_1):m_g_cpu1_sb_cb(1)';
NODE_NAME     U1 DV34
 '@S9S_MB_2U_LIB.S9S_MB_2U(SCH_1):PAGE57_I168@PURE_QUANTA.SOCKET4677_AZIF0045P001C01CS(CHIPS)':
 'DDR6_SB_ECC1': CDS_PINID='DDR6_SB_ECC1';
NODE_NAME     J29 98
 '@S9S_MB_2U_LIB.S9S_MB_2U(SCH_1):PAGE110_I179@PURE_QUANTA.SCONN288_ADR50017P130CC(CHIPS)':
 'CB1_B': CDS_PINID='CB1_B';
NODE_NAME     J30 98
 '@S9S_MB_2U_LIB.S9S_MB_2U(SCH_1):PAGE111_I179@PURE_QUANTA.SCONN288_ADR50017P087CC(CHIPS)':
 'CB1_B': CDS_PINID='CB1_B';
NET_NAME
'M_G_CPU1_SB_CB<2>'
 '@S9S_MB_2U_LIB.S9S_MB_2U(SCH_1):M_G_CPU1_SB_CB'<2>:
 C_SIGNAL='@s9s_mb_2u_lib.s9s_mb_2u(sch_1):m_g_cpu1_sb_cb(2)';
NODE_NAME     U1 EA35
 '@S9S_MB_2U_LIB.S9S_MB_2U(SCH_1):PAGE57_I168@PURE_QUANTA.SOCKET4677_AZIF0045P001C01CS(CHIPS)':
 'DDR6_SB_ECC2': CDS_PINID='DDR6_SB_ECC2';
NODE_NAME     J29 241
 '@S9S_MB_2U_LIB.S9S_MB_2U(SCH_1):PAGE110_I179@PURE_QUANTA.SCONN288_ADR50017P130CC(CHIPS)':
 'CB2_B': CDS_PINID='CB2_B';
NODE_NAME     J30 241
 '@S9S_MB_2U_LIB.S9S_MB_2U(SCH_1):PAGE111_I179@PURE_QUANTA.SCONN288_ADR50017P087CC(CHIPS)':
 'CB2_B': CDS_PINID='CB2_B';
NET_NAME
'M_G_CPU1_SB_CB<3>'
 '@S9S_MB_2U_LIB.S9S_MB_2U(SCH_1):M_G_CPU1_SB_CB'<3>:
 C_SIGNAL='@s9s_mb_2u_lib.s9s_mb_2u(sch_1):m_g_cpu1_sb_cb(3)';
NODE_NAME     U1 DY34
 '@S9S_MB_2U_LIB.S9S_MB_2U(SCH_1):PAGE57_I168@PURE_QUANTA.SOCKET4677_AZIF0045P001C01CS(CHIPS)':
 'DDR6_SB_ECC3': CDS_PINID='DDR6_SB_ECC3';
NODE_NAME     J29 243
 '@S9S_MB_2U_LIB.S9S_MB_2U(SCH_1):PAGE110_I179@PURE_QUANTA.SCONN288_ADR50017P130CC(CHIPS)':
 'CB3_B': CDS_PINID='CB3_B';
NODE_NAME     J30 243
 '@S9S_MB_2U_LIB.S9S_MB_2U(SCH_1):PAGE111_I179@PURE_QUANTA.SCONN288_ADR50017P087CC(CHIPS)':
 'CB3_B': CDS_PINID='CB3_B';
NET_NAME
'M_G_CPU1_SB_CB<4>'
 '@S9S_MB_2U_LIB.S9S_MB_2U(SCH_1):M_G_CPU1_SB_CB'<4>:
 C_SIGNAL='@s9s_mb_2u_lib.s9s_mb_2u(sch_1):m_g_cpu1_sb_cb(4)';
NODE_NAME     U1 DV38
 '@S9S_MB_2U_LIB.S9S_MB_2U(SCH_1):PAGE57_I168@PURE_QUANTA.SOCKET4677_AZIF0045P001C01CS(CHIPS)':
 'DDR6_SB_ECC4': CDS_PINID='DDR6_SB_ECC4';
NODE_NAME     J29 89
 '@S9S_MB_2U_LIB.S9S_MB_2U(SCH_1):PAGE110_I179@PURE_QUANTA.SCONN288_ADR50017P130CC(CHIPS)':
 'CB4_B': CDS_PINID='CB4_B';
NODE_NAME     J30 89
 '@S9S_MB_2U_LIB.S9S_MB_2U(SCH_1):PAGE111_I179@PURE_QUANTA.SCONN288_ADR50017P087CC(CHIPS)':
 'CB4_B': CDS_PINID='CB4_B';
NET_NAME
'M_G_CPU1_SB_CB<5>'
 '@S9S_MB_2U_LIB.S9S_MB_2U(SCH_1):M_G_CPU1_SB_CB'<5>:
 C_SIGNAL='@s9s_mb_2u_lib.s9s_mb_2u(sch_1):m_g_cpu1_sb_cb(5)';
NODE_NAME     U1 DU37
 '@S9S_MB_2U_LIB.S9S_MB_2U(SCH_1):PAGE57_I168@PURE_QUANTA.SOCKET4677_AZIF0045P001C01CS(CHIPS)':
 'DDR6_SB_ECC5': CDS_PINID='DDR6_SB_ECC5';
NODE_NAME     J29 91
 '@S9S_MB_2U_LIB.S9S_MB_2U(SCH_1):PAGE110_I179@PURE_QUANTA.SCONN288_ADR50017P130CC(CHIPS)':
 'CB5_B': CDS_PINID='CB5_B';
NODE_NAME     J30 91
 '@S9S_MB_2U_LIB.S9S_MB_2U(SCH_1):PAGE111_I179@PURE_QUANTA.SCONN288_ADR50017P087CC(CHIPS)':
 'CB5_B': CDS_PINID='CB5_B';
NET_NAME
'M_G_CPU1_SB_CB<6>'
 '@S9S_MB_2U_LIB.S9S_MB_2U(SCH_1):M_G_CPU1_SB_CB'<6>:
 C_SIGNAL='@s9s_mb_2u_lib.s9s_mb_2u(sch_1):m_g_cpu1_sb_cb(6)';
NODE_NAME     U1 DY38
 '@S9S_MB_2U_LIB.S9S_MB_2U(SCH_1):PAGE57_I168@PURE_QUANTA.SOCKET4677_AZIF0045P001C01CS(CHIPS)':
 'DDR6_SB_ECC6': CDS_PINID='DDR6_SB_ECC6';
NODE_NAME     J29 234
 '@S9S_MB_2U_LIB.S9S_MB_2U(SCH_1):PAGE110_I179@PURE_QUANTA.SCONN288_ADR50017P130CC(CHIPS)':
 'CB6_B': CDS_PINID='CB6_B';
NODE_NAME     J30 234
 '@S9S_MB_2U_LIB.S9S_MB_2U(SCH_1):PAGE111_I179@PURE_QUANTA.SCONN288_ADR50017P087CC(CHIPS)':
 'CB6_B': CDS_PINID='CB6_B';
NET_NAME
'M_G_CPU1_SB_CB<7>'
 '@S9S_MB_2U_LIB.S9S_MB_2U(SCH_1):M_G_CPU1_SB_CB'<7>:
 C_SIGNAL='@s9s_mb_2u_lib.s9s_mb_2u(sch_1):m_g_cpu1_sb_cb(7)';
NODE_NAME     U1 EA37
 '@S9S_MB_2U_LIB.S9S_MB_2U(SCH_1):PAGE57_I168@PURE_QUANTA.SOCKET4677_AZIF0045P001C01CS(CHIPS)':
 'DDR6_SB_ECC7': CDS_PINID='DDR6_SB_ECC7';
NODE_NAME     J29 236
 '@S9S_MB_2U_LIB.S9S_MB_2U(SCH_1):PAGE110_I179@PURE_QUANTA.SCONN288_ADR50017P130CC(CHIPS)':
 'CB7_B': CDS_PINID='CB7_B';
NODE_NAME     J30 236
 '@S9S_MB_2U_LIB.S9S_MB_2U(SCH_1):PAGE111_I179@PURE_QUANTA.SCONN288_ADR50017P087CC(CHIPS)':
 'CB7_B': CDS_PINID='CB7_B';
NET_NAME
'M_G_CPU1_SB_CS_N<0>'
 '@S9S_MB_2U_LIB.S9S_MB_2U(SCH_1):M_G_CPU1_SB_CS_N'<0>:
 C_SIGNAL='@s9s_mb_2u_lib.s9s_mb_2u(sch_1):m_g_cpu1_sb_cs_n(0)';
NODE_NAME     U1 EA41
 '@S9S_MB_2U_LIB.S9S_MB_2U(SCH_1):PAGE57_I168@PURE_QUANTA.SOCKET4677_AZIF0045P001C01CS(CHIPS)':
 'DDR6_SB_CS_N0': CDS_PINID='DDR6_SB_CS_N0';
NODE_NAME     J29 84
 '@S9S_MB_2U_LIB.S9S_MB_2U(SCH_1):PAGE110_I179@PURE_QUANTA.SCONN288_ADR50017P130CC(CHIPS)':
 'CS0_B_N': CDS_PINID='CS0_B_N';
NET_NAME
'M_G_CPU1_SB_CS_N<1>'
 '@S9S_MB_2U_LIB.S9S_MB_2U(SCH_1):M_G_CPU1_SB_CS_N'<1>:
 C_SIGNAL='@s9s_mb_2u_lib.s9s_mb_2u(sch_1):m_g_cpu1_sb_cs_n(1)';
NODE_NAME     U1 DY40
 '@S9S_MB_2U_LIB.S9S_MB_2U(SCH_1):PAGE57_I168@PURE_QUANTA.SOCKET4677_AZIF0045P001C01CS(CHIPS)':
 'DDR6_SB_CS_N1': CDS_PINID='DDR6_SB_CS_N1';
NODE_NAME     J29 229
 '@S9S_MB_2U_LIB.S9S_MB_2U(SCH_1):PAGE110_I179@PURE_QUANTA.SCONN288_ADR50017P130CC(CHIPS)':
 'CS1_B_N': CDS_PINID='CS1_B_N';
NET_NAME
'M_G_CPU1_SB_CS_N<2>'
 '@S9S_MB_2U_LIB.S9S_MB_2U(SCH_1):M_G_CPU1_SB_CS_N'<2>:
 C_SIGNAL='@s9s_mb_2u_lib.s9s_mb_2u(sch_1):m_g_cpu1_sb_cs_n(2)';
NODE_NAME     U1 DU41
 '@S9S_MB_2U_LIB.S9S_MB_2U(SCH_1):PAGE57_I168@PURE_QUANTA.SOCKET4677_AZIF0045P001C01CS(CHIPS)':
 'DDR6_SB_CS_N2': CDS_PINID='DDR6_SB_CS_N2';
NODE_NAME     J30 84
 '@S9S_MB_2U_LIB.S9S_MB_2U(SCH_1):PAGE111_I179@PURE_QUANTA.SCONN288_ADR50017P087CC(CHIPS)':
 'CS0_B_N': CDS_PINID='CS0_B_N';
NET_NAME
'M_G_CPU1_SB_CS_N<3>'
 '@S9S_MB_2U_LIB.S9S_MB_2U(SCH_1):M_G_CPU1_SB_CS_N'<3>:
 C_SIGNAL='@s9s_mb_2u_lib.s9s_mb_2u(sch_1):m_g_cpu1_sb_cs_n(3)';
NODE_NAME     U1 DV40
 '@S9S_MB_2U_LIB.S9S_MB_2U(SCH_1):PAGE57_I168@PURE_QUANTA.SOCKET4677_AZIF0045P001C01CS(CHIPS)':
 'DDR6_SB_CS_N3': CDS_PINID='DDR6_SB_CS_N3';
NODE_NAME     J30 229
 '@S9S_MB_2U_LIB.S9S_MB_2U(SCH_1):PAGE111_I179@PURE_QUANTA.SCONN288_ADR50017P087CC(CHIPS)':
 'CS1_B_N': CDS_PINID='CS1_B_N';
NET_NAME
'M_G_CPU1_SB_DQ<0>'
 '@S9S_MB_2U_LIB.S9S_MB_2U(SCH_1):M_G_CPU1_SB_DQ'<0>:
 C_SIGNAL='@s9s_mb_2u_lib.s9s_mb_2u(sch_1):m_g_cpu1_sb_dq(0)';
NODE_NAME     U1 DL35
 '@S9S_MB_2U_LIB.S9S_MB_2U(SCH_1):PAGE57_I168@PURE_QUANTA.SOCKET4677_AZIF0045P001C01CS(CHIPS)':
 'DDR6_SB_DQ0': CDS_PINID='DDR6_SB_DQ0';
NODE_NAME     J29 100
 '@S9S_MB_2U_LIB.S9S_MB_2U(SCH_1):PAGE110_I179@PURE_QUANTA.SCONN288_ADR50017P130CC(CHIPS)':
 'DQ0_B': CDS_PINID='DQ0_B';
NODE_NAME     J30 100
 '@S9S_MB_2U_LIB.S9S_MB_2U(SCH_1):PAGE111_I179@PURE_QUANTA.SCONN288_ADR50017P087CC(CHIPS)':
 'DQ0_B': CDS_PINID='DQ0_B';
NET_NAME
'M_G_CPU1_SB_DQ<10>'
 '@S9S_MB_2U_LIB.S9S_MB_2U(SCH_1):M_G_CPU1_SB_DQ'<10>:
 C_SIGNAL='@s9s_mb_2u_lib.s9s_mb_2u(sch_1):m_g_cpu1_sb_dq(10)';
NODE_NAME     U1 DL29
 '@S9S_MB_2U_LIB.S9S_MB_2U(SCH_1):PAGE57_I168@PURE_QUANTA.SOCKET4677_AZIF0045P001C01CS(CHIPS)':
 'DDR6_SB_DQ10': CDS_PINID='DDR6_SB_DQ10';
NODE_NAME     J29 256
 '@S9S_MB_2U_LIB.S9S_MB_2U(SCH_1):PAGE110_I179@PURE_QUANTA.SCONN288_ADR50017P130CC(CHIPS)':
 'DQ10_B': CDS_PINID='DQ10_B';
NODE_NAME     J30 256
 '@S9S_MB_2U_LIB.S9S_MB_2U(SCH_1):PAGE111_I179@PURE_QUANTA.SCONN288_ADR50017P087CC(CHIPS)':
 'DQ10_B': CDS_PINID='DQ10_B';
NET_NAME
'M_G_CPU1_SB_DQ<11>'
 '@S9S_MB_2U_LIB.S9S_MB_2U(SCH_1):M_G_CPU1_SB_DQ'<11>:
 C_SIGNAL='@s9s_mb_2u_lib.s9s_mb_2u(sch_1):m_g_cpu1_sb_dq(11)';
NODE_NAME     U1 DP28
 '@S9S_MB_2U_LIB.S9S_MB_2U(SCH_1):PAGE57_I168@PURE_QUANTA.SOCKET4677_AZIF0045P001C01CS(CHIPS)':
 'DDR6_SB_DQ11': CDS_PINID='DDR6_SB_DQ11';
NODE_NAME     J29 258
 '@S9S_MB_2U_LIB.S9S_MB_2U(SCH_1):PAGE110_I179@PURE_QUANTA.SCONN288_ADR50017P130CC(CHIPS)':
 'DQ11_B': CDS_PINID='DQ11_B';
NODE_NAME     J30 258
 '@S9S_MB_2U_LIB.S9S_MB_2U(SCH_1):PAGE111_I179@PURE_QUANTA.SCONN288_ADR50017P087CC(CHIPS)':
 'DQ11_B': CDS_PINID='DQ11_B';
NET_NAME
'M_G_CPU1_SB_DQ<12>'
 '@S9S_MB_2U_LIB.S9S_MB_2U(SCH_1):M_G_CPU1_SB_DQ'<12>:
 C_SIGNAL='@s9s_mb_2u_lib.s9s_mb_2u(sch_1):m_g_cpu1_sb_dq(12)';
NODE_NAME     U1 DK26
 '@S9S_MB_2U_LIB.S9S_MB_2U(SCH_1):PAGE57_I168@PURE_QUANTA.SOCKET4677_AZIF0045P001C01CS(CHIPS)':
 'DDR6_SB_DQ12': CDS_PINID='DDR6_SB_DQ12';
NODE_NAME     J29 118
 '@S9S_MB_2U_LIB.S9S_MB_2U(SCH_1):PAGE110_I179@PURE_QUANTA.SCONN288_ADR50017P130CC(CHIPS)':
 'DQ12_B': CDS_PINID='DQ12_B';
NODE_NAME     J30 118
 '@S9S_MB_2U_LIB.S9S_MB_2U(SCH_1):PAGE111_I179@PURE_QUANTA.SCONN288_ADR50017P087CC(CHIPS)':
 'DQ12_B': CDS_PINID='DQ12_B';
NET_NAME
'M_G_CPU1_SB_DQ<13>'
 '@S9S_MB_2U_LIB.S9S_MB_2U(SCH_1):M_G_CPU1_SB_DQ'<13>:
 C_SIGNAL='@s9s_mb_2u_lib.s9s_mb_2u(sch_1):m_g_cpu1_sb_dq(13)';
NODE_NAME     U1 DL25
 '@S9S_MB_2U_LIB.S9S_MB_2U(SCH_1):PAGE57_I168@PURE_QUANTA.SOCKET4677_AZIF0045P001C01CS(CHIPS)':
 'DDR6_SB_DQ13': CDS_PINID='DDR6_SB_DQ13';
NODE_NAME     J29 120
 '@S9S_MB_2U_LIB.S9S_MB_2U(SCH_1):PAGE110_I179@PURE_QUANTA.SCONN288_ADR50017P130CC(CHIPS)':
 'DQ13_B': CDS_PINID='DQ13_B';
NODE_NAME     J30 120
 '@S9S_MB_2U_LIB.S9S_MB_2U(SCH_1):PAGE111_I179@PURE_QUANTA.SCONN288_ADR50017P087CC(CHIPS)':
 'DQ13_B': CDS_PINID='DQ13_B';
NET_NAME
'M_G_CPU1_SB_DQ<14>'
 '@S9S_MB_2U_LIB.S9S_MB_2U(SCH_1):M_G_CPU1_SB_DQ'<14>:
 C_SIGNAL='@s9s_mb_2u_lib.s9s_mb_2u(sch_1):m_g_cpu1_sb_dq(14)';
NODE_NAME     U1 DP26
 '@S9S_MB_2U_LIB.S9S_MB_2U(SCH_1):PAGE57_I168@PURE_QUANTA.SOCKET4677_AZIF0045P001C01CS(CHIPS)':
 'DDR6_SB_DQ14': CDS_PINID='DDR6_SB_DQ14';
NODE_NAME     J29 263
 '@S9S_MB_2U_LIB.S9S_MB_2U(SCH_1):PAGE110_I179@PURE_QUANTA.SCONN288_ADR50017P130CC(CHIPS)':
 'DQ14_B': CDS_PINID='DQ14_B';
NODE_NAME     J30 263
 '@S9S_MB_2U_LIB.S9S_MB_2U(SCH_1):PAGE111_I179@PURE_QUANTA.SCONN288_ADR50017P087CC(CHIPS)':
 'DQ14_B': CDS_PINID='DQ14_B';
NET_NAME
'M_G_CPU1_SB_DQ<15>'
 '@S9S_MB_2U_LIB.S9S_MB_2U(SCH_1):M_G_CPU1_SB_DQ'<15>:
 C_SIGNAL='@s9s_mb_2u_lib.s9s_mb_2u(sch_1):m_g_cpu1_sb_dq(15)';
NODE_NAME     U1 DN25
 '@S9S_MB_2U_LIB.S9S_MB_2U(SCH_1):PAGE57_I168@PURE_QUANTA.SOCKET4677_AZIF0045P001C01CS(CHIPS)':
 'DDR6_SB_DQ15': CDS_PINID='DDR6_SB_DQ15';
NODE_NAME     J29 265
 '@S9S_MB_2U_LIB.S9S_MB_2U(SCH_1):PAGE110_I179@PURE_QUANTA.SCONN288_ADR50017P130CC(CHIPS)':
 'DQ15_B': CDS_PINID='DQ15_B';
NODE_NAME     J30 265
 '@S9S_MB_2U_LIB.S9S_MB_2U(SCH_1):PAGE111_I179@PURE_QUANTA.SCONN288_ADR50017P087CC(CHIPS)':
 'DQ15_B': CDS_PINID='DQ15_B';
NET_NAME
'M_G_CPU1_SB_DQ<16>'
 '@S9S_MB_2U_LIB.S9S_MB_2U(SCH_1):M_G_CPU1_SB_DQ'<16>:
 C_SIGNAL='@s9s_mb_2u_lib.s9s_mb_2u(sch_1):m_g_cpu1_sb_dq(16)';
NODE_NAME     U1 DV26
 '@S9S_MB_2U_LIB.S9S_MB_2U(SCH_1):PAGE57_I168@PURE_QUANTA.SOCKET4677_AZIF0045P001C01CS(CHIPS)':
 'DDR6_SB_DQ16': CDS_PINID='DDR6_SB_DQ16';
NODE_NAME     J29 122
 '@S9S_MB_2U_LIB.S9S_MB_2U(SCH_1):PAGE110_I179@PURE_QUANTA.SCONN288_ADR50017P130CC(CHIPS)':
 'DQ16_B': CDS_PINID='DQ16_B';
NODE_NAME     J30 122
 '@S9S_MB_2U_LIB.S9S_MB_2U(SCH_1):PAGE111_I179@PURE_QUANTA.SCONN288_ADR50017P087CC(CHIPS)':
 'DQ16_B': CDS_PINID='DQ16_B';
NET_NAME
'M_G_CPU1_SB_DQ<17>'
 '@S9S_MB_2U_LIB.S9S_MB_2U(SCH_1):M_G_CPU1_SB_DQ'<17>:
 C_SIGNAL='@s9s_mb_2u_lib.s9s_mb_2u(sch_1):m_g_cpu1_sb_dq(17)';
NODE_NAME     U1 DU25
 '@S9S_MB_2U_LIB.S9S_MB_2U(SCH_1):PAGE57_I168@PURE_QUANTA.SOCKET4677_AZIF0045P001C01CS(CHIPS)':
 'DDR6_SB_DQ17': CDS_PINID='DDR6_SB_DQ17';
NODE_NAME     J29 124
 '@S9S_MB_2U_LIB.S9S_MB_2U(SCH_1):PAGE110_I179@PURE_QUANTA.SCONN288_ADR50017P130CC(CHIPS)':
 'DQ17_B': CDS_PINID='DQ17_B';
NODE_NAME     J30 124
 '@S9S_MB_2U_LIB.S9S_MB_2U(SCH_1):PAGE111_I179@PURE_QUANTA.SCONN288_ADR50017P087CC(CHIPS)':
 'DQ17_B': CDS_PINID='DQ17_B';
NET_NAME
'M_G_CPU1_SB_DQ<18>'
 '@S9S_MB_2U_LIB.S9S_MB_2U(SCH_1):M_G_CPU1_SB_DQ'<18>:
 C_SIGNAL='@s9s_mb_2u_lib.s9s_mb_2u(sch_1):m_g_cpu1_sb_dq(18)';
NODE_NAME     U1 DY26
 '@S9S_MB_2U_LIB.S9S_MB_2U(SCH_1):PAGE57_I168@PURE_QUANTA.SOCKET4677_AZIF0045P001C01CS(CHIPS)':
 'DDR6_SB_DQ18': CDS_PINID='DDR6_SB_DQ18';
NODE_NAME     J29 267
 '@S9S_MB_2U_LIB.S9S_MB_2U(SCH_1):PAGE110_I179@PURE_QUANTA.SCONN288_ADR50017P130CC(CHIPS)':
 'DQ18_B': CDS_PINID='DQ18_B';
NODE_NAME     J30 267
 '@S9S_MB_2U_LIB.S9S_MB_2U(SCH_1):PAGE111_I179@PURE_QUANTA.SCONN288_ADR50017P087CC(CHIPS)':
 'DQ18_B': CDS_PINID='DQ18_B';
NET_NAME
'M_G_CPU1_SB_DQ<19>'
 '@S9S_MB_2U_LIB.S9S_MB_2U(SCH_1):M_G_CPU1_SB_DQ'<19>:
 C_SIGNAL='@s9s_mb_2u_lib.s9s_mb_2u(sch_1):m_g_cpu1_sb_dq(19)';
NODE_NAME     U1 EA25
 '@S9S_MB_2U_LIB.S9S_MB_2U(SCH_1):PAGE57_I168@PURE_QUANTA.SOCKET4677_AZIF0045P001C01CS(CHIPS)':
 'DDR6_SB_DQ19': CDS_PINID='DDR6_SB_DQ19';
NODE_NAME     J29 269
 '@S9S_MB_2U_LIB.S9S_MB_2U(SCH_1):PAGE110_I179@PURE_QUANTA.SCONN288_ADR50017P130CC(CHIPS)':
 'DQ19_B': CDS_PINID='DQ19_B';
NODE_NAME     J30 269
 '@S9S_MB_2U_LIB.S9S_MB_2U(SCH_1):PAGE111_I179@PURE_QUANTA.SCONN288_ADR50017P087CC(CHIPS)':
 'DQ19_B': CDS_PINID='DQ19_B';
NET_NAME
'M_G_CPU1_SB_DQ<1>'
 '@S9S_MB_2U_LIB.S9S_MB_2U(SCH_1):M_G_CPU1_SB_DQ'<1>:
 C_SIGNAL='@s9s_mb_2u_lib.s9s_mb_2u(sch_1):m_g_cpu1_sb_dq(1)';
NODE_NAME     U1 DK34
 '@S9S_MB_2U_LIB.S9S_MB_2U(SCH_1):PAGE57_I168@PURE_QUANTA.SOCKET4677_AZIF0045P001C01CS(CHIPS)':
 'DDR6_SB_DQ1': CDS_PINID='DDR6_SB_DQ1';
NODE_NAME     J29 102
 '@S9S_MB_2U_LIB.S9S_MB_2U(SCH_1):PAGE110_I179@PURE_QUANTA.SCONN288_ADR50017P130CC(CHIPS)':
 'DQ1_B': CDS_PINID='DQ1_B';
NODE_NAME     J30 102
 '@S9S_MB_2U_LIB.S9S_MB_2U(SCH_1):PAGE111_I179@PURE_QUANTA.SCONN288_ADR50017P087CC(CHIPS)':
 'DQ1_B': CDS_PINID='DQ1_B';
NET_NAME
'M_G_CPU1_SB_DQ<20>'
 '@S9S_MB_2U_LIB.S9S_MB_2U(SCH_1):M_G_CPU1_SB_DQ'<20>:
 C_SIGNAL='@s9s_mb_2u_lib.s9s_mb_2u(sch_1):m_g_cpu1_sb_dq(20)';
NODE_NAME     U1 DU23
 '@S9S_MB_2U_LIB.S9S_MB_2U(SCH_1):PAGE57_I168@PURE_QUANTA.SOCKET4677_AZIF0045P001C01CS(CHIPS)':
 'DDR6_SB_DQ20': CDS_PINID='DDR6_SB_DQ20';
NODE_NAME     J29 129
 '@S9S_MB_2U_LIB.S9S_MB_2U(SCH_1):PAGE110_I179@PURE_QUANTA.SCONN288_ADR50017P130CC(CHIPS)':
 'DQ20_B': CDS_PINID='DQ20_B';
NODE_NAME     J30 129
 '@S9S_MB_2U_LIB.S9S_MB_2U(SCH_1):PAGE111_I179@PURE_QUANTA.SCONN288_ADR50017P087CC(CHIPS)':
 'DQ20_B': CDS_PINID='DQ20_B';
NET_NAME
'M_G_CPU1_SB_DQ<21>'
 '@S9S_MB_2U_LIB.S9S_MB_2U(SCH_1):M_G_CPU1_SB_DQ'<21>:
 C_SIGNAL='@s9s_mb_2u_lib.s9s_mb_2u(sch_1):m_g_cpu1_sb_dq(21)';
NODE_NAME     U1 DV22
 '@S9S_MB_2U_LIB.S9S_MB_2U(SCH_1):PAGE57_I168@PURE_QUANTA.SOCKET4677_AZIF0045P001C01CS(CHIPS)':
 'DDR6_SB_DQ21': CDS_PINID='DDR6_SB_DQ21';
NODE_NAME     J29 131
 '@S9S_MB_2U_LIB.S9S_MB_2U(SCH_1):PAGE110_I179@PURE_QUANTA.SCONN288_ADR50017P130CC(CHIPS)':
 'DQ21_B': CDS_PINID='DQ21_B';
NODE_NAME     J30 131
 '@S9S_MB_2U_LIB.S9S_MB_2U(SCH_1):PAGE111_I179@PURE_QUANTA.SCONN288_ADR50017P087CC(CHIPS)':
 'DQ21_B': CDS_PINID='DQ21_B';
NET_NAME
'M_G_CPU1_SB_DQ<22>'
 '@S9S_MB_2U_LIB.S9S_MB_2U(SCH_1):M_G_CPU1_SB_DQ'<22>:
 C_SIGNAL='@s9s_mb_2u_lib.s9s_mb_2u(sch_1):m_g_cpu1_sb_dq(22)';
NODE_NAME     U1 EA23
 '@S9S_MB_2U_LIB.S9S_MB_2U(SCH_1):PAGE57_I168@PURE_QUANTA.SOCKET4677_AZIF0045P001C01CS(CHIPS)':
 'DDR6_SB_DQ22': CDS_PINID='DDR6_SB_DQ22';
NODE_NAME     J29 274
 '@S9S_MB_2U_LIB.S9S_MB_2U(SCH_1):PAGE110_I179@PURE_QUANTA.SCONN288_ADR50017P130CC(CHIPS)':
 'DQ22_B': CDS_PINID='DQ22_B';
NODE_NAME     J30 274
 '@S9S_MB_2U_LIB.S9S_MB_2U(SCH_1):PAGE111_I179@PURE_QUANTA.SCONN288_ADR50017P087CC(CHIPS)':
 'DQ22_B': CDS_PINID='DQ22_B';
NET_NAME
'M_G_CPU1_SB_DQ<23>'
 '@S9S_MB_2U_LIB.S9S_MB_2U(SCH_1):M_G_CPU1_SB_DQ'<23>:
 C_SIGNAL='@s9s_mb_2u_lib.s9s_mb_2u(sch_1):m_g_cpu1_sb_dq(23)';
NODE_NAME     U1 DY22
 '@S9S_MB_2U_LIB.S9S_MB_2U(SCH_1):PAGE57_I168@PURE_QUANTA.SOCKET4677_AZIF0045P001C01CS(CHIPS)':
 'DDR6_SB_DQ23': CDS_PINID='DDR6_SB_DQ23';
NODE_NAME     J29 276
 '@S9S_MB_2U_LIB.S9S_MB_2U(SCH_1):PAGE110_I179@PURE_QUANTA.SCONN288_ADR50017P130CC(CHIPS)':
 'DQ23_B': CDS_PINID='DQ23_B';
NODE_NAME     J30 276
 '@S9S_MB_2U_LIB.S9S_MB_2U(SCH_1):PAGE111_I179@PURE_QUANTA.SCONN288_ADR50017P087CC(CHIPS)':
 'DQ23_B': CDS_PINID='DQ23_B';
NET_NAME
'M_G_CPU1_SB_DQ<24>'
 '@S9S_MB_2U_LIB.S9S_MB_2U(SCH_1):M_G_CPU1_SB_DQ'<24>:
 C_SIGNAL='@s9s_mb_2u_lib.s9s_mb_2u(sch_1):m_g_cpu1_sb_dq(24)';
NODE_NAME     U1 EK8
 '@S9S_MB_2U_LIB.S9S_MB_2U(SCH_1):PAGE57_I168@PURE_QUANTA.SOCKET4677_AZIF0045P001C01CS(CHIPS)':
 'DDR6_SB_DQ24': CDS_PINID='DDR6_SB_DQ24';
NODE_NAME     J29 133
 '@S9S_MB_2U_LIB.S9S_MB_2U(SCH_1):PAGE110_I179@PURE_QUANTA.SCONN288_ADR50017P130CC(CHIPS)':
 'DQ24_B': CDS_PINID='DQ24_B';
NODE_NAME     J30 133
 '@S9S_MB_2U_LIB.S9S_MB_2U(SCH_1):PAGE111_I179@PURE_QUANTA.SCONN288_ADR50017P087CC(CHIPS)':
 'DQ24_B': CDS_PINID='DQ24_B';
NET_NAME
'M_G_CPU1_SB_DQ<25>'
 '@S9S_MB_2U_LIB.S9S_MB_2U(SCH_1):M_G_CPU1_SB_DQ'<25>:
 C_SIGNAL='@s9s_mb_2u_lib.s9s_mb_2u(sch_1):m_g_cpu1_sb_dq(25)';
NODE_NAME     U1 EH8
 '@S9S_MB_2U_LIB.S9S_MB_2U(SCH_1):PAGE57_I168@PURE_QUANTA.SOCKET4677_AZIF0045P001C01CS(CHIPS)':
 'DDR6_SB_DQ25': CDS_PINID='DDR6_SB_DQ25';
NODE_NAME     J29 135
 '@S9S_MB_2U_LIB.S9S_MB_2U(SCH_1):PAGE110_I179@PURE_QUANTA.SCONN288_ADR50017P130CC(CHIPS)':
 'DQ25_B': CDS_PINID='DQ25_B';
NODE_NAME     J30 135
 '@S9S_MB_2U_LIB.S9S_MB_2U(SCH_1):PAGE111_I179@PURE_QUANTA.SCONN288_ADR50017P087CC(CHIPS)':
 'DQ25_B': CDS_PINID='DQ25_B';
NET_NAME
'M_G_CPU1_SB_DQ<26>'
 '@S9S_MB_2U_LIB.S9S_MB_2U(SCH_1):M_G_CPU1_SB_DQ'<26>:
 C_SIGNAL='@s9s_mb_2u_lib.s9s_mb_2u(sch_1):m_g_cpu1_sb_dq(26)';
NODE_NAME     U1 EP8
 '@S9S_MB_2U_LIB.S9S_MB_2U(SCH_1):PAGE57_I168@PURE_QUANTA.SOCKET4677_AZIF0045P001C01CS(CHIPS)':
 'DDR6_SB_DQ26': CDS_PINID='DDR6_SB_DQ26';
NODE_NAME     J29 278
 '@S9S_MB_2U_LIB.S9S_MB_2U(SCH_1):PAGE110_I179@PURE_QUANTA.SCONN288_ADR50017P130CC(CHIPS)':
 'DQ26_B': CDS_PINID='DQ26_B';
NODE_NAME     J30 278
 '@S9S_MB_2U_LIB.S9S_MB_2U(SCH_1):PAGE111_I179@PURE_QUANTA.SCONN288_ADR50017P087CC(CHIPS)':
 'DQ26_B': CDS_PINID='DQ26_B';
NET_NAME
'M_G_CPU1_SB_DQ<27>'
 '@S9S_MB_2U_LIB.S9S_MB_2U(SCH_1):M_G_CPU1_SB_DQ'<27>:
 C_SIGNAL='@s9s_mb_2u_lib.s9s_mb_2u(sch_1):m_g_cpu1_sb_dq(27)';
NODE_NAME     U1 ET8
 '@S9S_MB_2U_LIB.S9S_MB_2U(SCH_1):PAGE57_I168@PURE_QUANTA.SOCKET4677_AZIF0045P001C01CS(CHIPS)':
 'DDR6_SB_DQ27': CDS_PINID='DDR6_SB_DQ27';
NODE_NAME     J29 280
 '@S9S_MB_2U_LIB.S9S_MB_2U(SCH_1):PAGE110_I179@PURE_QUANTA.SCONN288_ADR50017P130CC(CHIPS)':
 'DQ27_B': CDS_PINID='DQ27_B';
NODE_NAME     J30 280
 '@S9S_MB_2U_LIB.S9S_MB_2U(SCH_1):PAGE111_I179@PURE_QUANTA.SCONN288_ADR50017P087CC(CHIPS)':
 'DQ27_B': CDS_PINID='DQ27_B';
NET_NAME
'M_G_CPU1_SB_DQ<28>'
 '@S9S_MB_2U_LIB.S9S_MB_2U(SCH_1):M_G_CPU1_SB_DQ'<28>:
 C_SIGNAL='@s9s_mb_2u_lib.s9s_mb_2u(sch_1):m_g_cpu1_sb_dq(28)';
NODE_NAME     U1 EK6
 '@S9S_MB_2U_LIB.S9S_MB_2U(SCH_1):PAGE57_I168@PURE_QUANTA.SOCKET4677_AZIF0045P001C01CS(CHIPS)':
 'DDR6_SB_DQ28': CDS_PINID='DDR6_SB_DQ28';
NODE_NAME     J29 140
 '@S9S_MB_2U_LIB.S9S_MB_2U(SCH_1):PAGE110_I179@PURE_QUANTA.SCONN288_ADR50017P130CC(CHIPS)':
 'DQ28_B': CDS_PINID='DQ28_B';
NODE_NAME     J30 140
 '@S9S_MB_2U_LIB.S9S_MB_2U(SCH_1):PAGE111_I179@PURE_QUANTA.SCONN288_ADR50017P087CC(CHIPS)':
 'DQ28_B': CDS_PINID='DQ28_B';
NET_NAME
'M_G_CPU1_SB_DQ<29>'
 '@S9S_MB_2U_LIB.S9S_MB_2U(SCH_1):M_G_CPU1_SB_DQ'<29>:
 C_SIGNAL='@s9s_mb_2u_lib.s9s_mb_2u(sch_1):m_g_cpu1_sb_dq(29)';
NODE_NAME     U1 EJ5
 '@S9S_MB_2U_LIB.S9S_MB_2U(SCH_1):PAGE57_I168@PURE_QUANTA.SOCKET4677_AZIF0045P001C01CS(CHIPS)':
 'DDR6_SB_DQ29': CDS_PINID='DDR6_SB_DQ29';
NODE_NAME     J29 142
 '@S9S_MB_2U_LIB.S9S_MB_2U(SCH_1):PAGE110_I179@PURE_QUANTA.SCONN288_ADR50017P130CC(CHIPS)':
 'DQ29_B': CDS_PINID='DQ29_B';
NODE_NAME     J30 142
 '@S9S_MB_2U_LIB.S9S_MB_2U(SCH_1):PAGE111_I179@PURE_QUANTA.SCONN288_ADR50017P087CC(CHIPS)':
 'DQ29_B': CDS_PINID='DQ29_B';
NET_NAME
'M_G_CPU1_SB_DQ<2>'
 '@S9S_MB_2U_LIB.S9S_MB_2U(SCH_1):M_G_CPU1_SB_DQ'<2>:
 C_SIGNAL='@s9s_mb_2u_lib.s9s_mb_2u(sch_1):m_g_cpu1_sb_dq(2)';
NODE_NAME     U1 DN35
 '@S9S_MB_2U_LIB.S9S_MB_2U(SCH_1):PAGE57_I168@PURE_QUANTA.SOCKET4677_AZIF0045P001C01CS(CHIPS)':
 'DDR6_SB_DQ2': CDS_PINID='DDR6_SB_DQ2';
NODE_NAME     J29 245
 '@S9S_MB_2U_LIB.S9S_MB_2U(SCH_1):PAGE110_I179@PURE_QUANTA.SCONN288_ADR50017P130CC(CHIPS)':
 'DQ2_B': CDS_PINID='DQ2_B';
NODE_NAME     J30 245
 '@S9S_MB_2U_LIB.S9S_MB_2U(SCH_1):PAGE111_I179@PURE_QUANTA.SCONN288_ADR50017P087CC(CHIPS)':
 'DQ2_B': CDS_PINID='DQ2_B';
NET_NAME
'M_G_CPU1_SB_DQ<30>'
 '@S9S_MB_2U_LIB.S9S_MB_2U(SCH_1):M_G_CPU1_SB_DQ'<30>:
 C_SIGNAL='@s9s_mb_2u_lib.s9s_mb_2u(sch_1):m_g_cpu1_sb_dq(30)';
NODE_NAME     U1 EP4
 '@S9S_MB_2U_LIB.S9S_MB_2U(SCH_1):PAGE57_I168@PURE_QUANTA.SOCKET4677_AZIF0045P001C01CS(CHIPS)':
 'DDR6_SB_DQ30': CDS_PINID='DDR6_SB_DQ30';
NODE_NAME     J29 285
 '@S9S_MB_2U_LIB.S9S_MB_2U(SCH_1):PAGE110_I179@PURE_QUANTA.SCONN288_ADR50017P130CC(CHIPS)':
 'DQ30_B': CDS_PINID='DQ30_B';
NODE_NAME     J30 285
 '@S9S_MB_2U_LIB.S9S_MB_2U(SCH_1):PAGE111_I179@PURE_QUANTA.SCONN288_ADR50017P087CC(CHIPS)':
 'DQ30_B': CDS_PINID='DQ30_B';
NET_NAME
'M_G_CPU1_SB_DQ<31>'
 '@S9S_MB_2U_LIB.S9S_MB_2U(SCH_1):M_G_CPU1_SB_DQ'<31>:
 C_SIGNAL='@s9s_mb_2u_lib.s9s_mb_2u(sch_1):m_g_cpu1_sb_dq(31)';
NODE_NAME     U1 EM4
 '@S9S_MB_2U_LIB.S9S_MB_2U(SCH_1):PAGE57_I168@PURE_QUANTA.SOCKET4677_AZIF0045P001C01CS(CHIPS)':
 'DDR6_SB_DQ31': CDS_PINID='DDR6_SB_DQ31';
NODE_NAME     J29 287
 '@S9S_MB_2U_LIB.S9S_MB_2U(SCH_1):PAGE110_I179@PURE_QUANTA.SCONN288_ADR50017P130CC(CHIPS)':
 'DQ31_B': CDS_PINID='DQ31_B';
NODE_NAME     J30 287
 '@S9S_MB_2U_LIB.S9S_MB_2U(SCH_1):PAGE111_I179@PURE_QUANTA.SCONN288_ADR50017P087CC(CHIPS)':
 'DQ31_B': CDS_PINID='DQ31_B';
NET_NAME
'M_G_CPU1_SB_DQ<3>'
 '@S9S_MB_2U_LIB.S9S_MB_2U(SCH_1):M_G_CPU1_SB_DQ'<3>:
 C_SIGNAL='@s9s_mb_2u_lib.s9s_mb_2u(sch_1):m_g_cpu1_sb_dq(3)';
NODE_NAME     U1 DP34
 '@S9S_MB_2U_LIB.S9S_MB_2U(SCH_1):PAGE57_I168@PURE_QUANTA.SOCKET4677_AZIF0045P001C01CS(CHIPS)':
 'DDR6_SB_DQ3': CDS_PINID='DDR6_SB_DQ3';
NODE_NAME     J29 247
 '@S9S_MB_2U_LIB.S9S_MB_2U(SCH_1):PAGE110_I179@PURE_QUANTA.SCONN288_ADR50017P130CC(CHIPS)':
 'DQ3_B': CDS_PINID='DQ3_B';
NODE_NAME     J30 247
 '@S9S_MB_2U_LIB.S9S_MB_2U(SCH_1):PAGE111_I179@PURE_QUANTA.SCONN288_ADR50017P087CC(CHIPS)':
 'DQ3_B': CDS_PINID='DQ3_B';
NET_NAME
'M_G_CPU1_SB_DQ<4>'
 '@S9S_MB_2U_LIB.S9S_MB_2U(SCH_1):M_G_CPU1_SB_DQ'<4>:
 C_SIGNAL='@s9s_mb_2u_lib.s9s_mb_2u(sch_1):m_g_cpu1_sb_dq(4)';
NODE_NAME     U1 DK32
 '@S9S_MB_2U_LIB.S9S_MB_2U(SCH_1):PAGE57_I168@PURE_QUANTA.SOCKET4677_AZIF0045P001C01CS(CHIPS)':
 'DDR6_SB_DQ4': CDS_PINID='DDR6_SB_DQ4';
NODE_NAME     J29 107
 '@S9S_MB_2U_LIB.S9S_MB_2U(SCH_1):PAGE110_I179@PURE_QUANTA.SCONN288_ADR50017P130CC(CHIPS)':
 'DQ4_B': CDS_PINID='DQ4_B';
NODE_NAME     J30 107
 '@S9S_MB_2U_LIB.S9S_MB_2U(SCH_1):PAGE111_I179@PURE_QUANTA.SCONN288_ADR50017P087CC(CHIPS)':
 'DQ4_B': CDS_PINID='DQ4_B';
NET_NAME
'M_G_CPU1_SB_DQ<5>'
 '@S9S_MB_2U_LIB.S9S_MB_2U(SCH_1):M_G_CPU1_SB_DQ'<5>:
 C_SIGNAL='@s9s_mb_2u_lib.s9s_mb_2u(sch_1):m_g_cpu1_sb_dq(5)';
NODE_NAME     U1 DL31
 '@S9S_MB_2U_LIB.S9S_MB_2U(SCH_1):PAGE57_I168@PURE_QUANTA.SOCKET4677_AZIF0045P001C01CS(CHIPS)':
 'DDR6_SB_DQ5': CDS_PINID='DDR6_SB_DQ5';
NODE_NAME     J29 109
 '@S9S_MB_2U_LIB.S9S_MB_2U(SCH_1):PAGE110_I179@PURE_QUANTA.SCONN288_ADR50017P130CC(CHIPS)':
 'DQ5_B': CDS_PINID='DQ5_B';
NODE_NAME     J30 109
 '@S9S_MB_2U_LIB.S9S_MB_2U(SCH_1):PAGE111_I179@PURE_QUANTA.SCONN288_ADR50017P087CC(CHIPS)':
 'DQ5_B': CDS_PINID='DQ5_B';
NET_NAME
'M_G_CPU1_SB_DQ<6>'
 '@S9S_MB_2U_LIB.S9S_MB_2U(SCH_1):M_G_CPU1_SB_DQ'<6>:
 C_SIGNAL='@s9s_mb_2u_lib.s9s_mb_2u(sch_1):m_g_cpu1_sb_dq(6)';
NODE_NAME     U1 DP32
 '@S9S_MB_2U_LIB.S9S_MB_2U(SCH_1):PAGE57_I168@PURE_QUANTA.SOCKET4677_AZIF0045P001C01CS(CHIPS)':
 'DDR6_SB_DQ6': CDS_PINID='DDR6_SB_DQ6';
NODE_NAME     J29 252
 '@S9S_MB_2U_LIB.S9S_MB_2U(SCH_1):PAGE110_I179@PURE_QUANTA.SCONN288_ADR50017P130CC(CHIPS)':
 'DQ6_B': CDS_PINID='DQ6_B';
NODE_NAME     J30 252
 '@S9S_MB_2U_LIB.S9S_MB_2U(SCH_1):PAGE111_I179@PURE_QUANTA.SCONN288_ADR50017P087CC(CHIPS)':
 'DQ6_B': CDS_PINID='DQ6_B';
NET_NAME
'M_G_CPU1_SB_DQ<7>'
 '@S9S_MB_2U_LIB.S9S_MB_2U(SCH_1):M_G_CPU1_SB_DQ'<7>:
 C_SIGNAL='@s9s_mb_2u_lib.s9s_mb_2u(sch_1):m_g_cpu1_sb_dq(7)';
NODE_NAME     U1 DN31
 '@S9S_MB_2U_LIB.S9S_MB_2U(SCH_1):PAGE57_I168@PURE_QUANTA.SOCKET4677_AZIF0045P001C01CS(CHIPS)':
 'DDR6_SB_DQ7': CDS_PINID='DDR6_SB_DQ7';
NODE_NAME     J29 254
 '@S9S_MB_2U_LIB.S9S_MB_2U(SCH_1):PAGE110_I179@PURE_QUANTA.SCONN288_ADR50017P130CC(CHIPS)':
 'DQ7_B': CDS_PINID='DQ7_B';
NODE_NAME     J30 254
 '@S9S_MB_2U_LIB.S9S_MB_2U(SCH_1):PAGE111_I179@PURE_QUANTA.SCONN288_ADR50017P087CC(CHIPS)':
 'DQ7_B': CDS_PINID='DQ7_B';
NET_NAME
'M_G_CPU1_SB_DQ<8>'
 '@S9S_MB_2U_LIB.S9S_MB_2U(SCH_1):M_G_CPU1_SB_DQ'<8>:
 C_SIGNAL='@s9s_mb_2u_lib.s9s_mb_2u(sch_1):m_g_cpu1_sb_dq(8)';
NODE_NAME     U1 DN29
 '@S9S_MB_2U_LIB.S9S_MB_2U(SCH_1):PAGE57_I168@PURE_QUANTA.SOCKET4677_AZIF0045P001C01CS(CHIPS)':
 'DDR6_SB_DQ8': CDS_PINID='DDR6_SB_DQ8';
NODE_NAME     J29 111
 '@S9S_MB_2U_LIB.S9S_MB_2U(SCH_1):PAGE110_I179@PURE_QUANTA.SCONN288_ADR50017P130CC(CHIPS)':
 'DQ8_B': CDS_PINID='DQ8_B';
NODE_NAME     J30 111
 '@S9S_MB_2U_LIB.S9S_MB_2U(SCH_1):PAGE111_I179@PURE_QUANTA.SCONN288_ADR50017P087CC(CHIPS)':
 'DQ8_B': CDS_PINID='DQ8_B';
NET_NAME
'M_G_CPU1_SB_DQ<9>'
 '@S9S_MB_2U_LIB.S9S_MB_2U(SCH_1):M_G_CPU1_SB_DQ'<9>:
 C_SIGNAL='@s9s_mb_2u_lib.s9s_mb_2u(sch_1):m_g_cpu1_sb_dq(9)';
NODE_NAME     U1 DK28
 '@S9S_MB_2U_LIB.S9S_MB_2U(SCH_1):PAGE57_I168@PURE_QUANTA.SOCKET4677_AZIF0045P001C01CS(CHIPS)':
 'DDR6_SB_DQ9': CDS_PINID='DDR6_SB_DQ9';
NODE_NAME     J29 113
 '@S9S_MB_2U_LIB.S9S_MB_2U(SCH_1):PAGE110_I179@PURE_QUANTA.SCONN288_ADR50017P130CC(CHIPS)':
 'DQ9_B': CDS_PINID='DQ9_B';
NODE_NAME     J30 113
 '@S9S_MB_2U_LIB.S9S_MB_2U(SCH_1):PAGE111_I179@PURE_QUANTA.SCONN288_ADR50017P087CC(CHIPS)':
 'DQ9_B': CDS_PINID='DQ9_B';
NET_NAME
'M_G_CPU1_SB_DQS_DN<0>'
 '@S9S_MB_2U_LIB.S9S_MB_2U(SCH_1):M_G_CPU1_SB_DQS_DN'<0>:
 C_SIGNAL='@s9s_mb_2u_lib.s9s_mb_2u(sch_1):m_g_cpu1_sb_dqs_dn(0)';
NODE_NAME     U1 DJ33
 '@S9S_MB_2U_LIB.S9S_MB_2U(SCH_1):PAGE57_I168@PURE_QUANTA.SOCKET4677_AZIF0045P001C01CS(CHIPS)':
 'DDR6_SB_DQS_DN0': CDS_PINID='DDR6_SB_DQS_DN0';
NODE_NAME     J29 105
 '@S9S_MB_2U_LIB.S9S_MB_2U(SCH_1):PAGE110_I180@PURE_QUANTA.SCONN288_ADR50017P130CC(CHIPS)':
 'DQS0_B_C': CDS_PINID='DQS0_B_C';
NODE_NAME     J30 105
 '@S9S_MB_2U_LIB.S9S_MB_2U(SCH_1):PAGE111_I180@PURE_QUANTA.SCONN288_ADR50017P087CC(CHIPS)':
 'DQS0_B_C': CDS_PINID='DQS0_B_C';
NET_NAME
'M_G_CPU1_SB_DQS_DN<1>'
 '@S9S_MB_2U_LIB.S9S_MB_2U(SCH_1):M_G_CPU1_SB_DQS_DN'<1>:
 C_SIGNAL='@s9s_mb_2u_lib.s9s_mb_2u(sch_1):m_g_cpu1_sb_dqs_dn(1)';
NODE_NAME     U1 DJ27
 '@S9S_MB_2U_LIB.S9S_MB_2U(SCH_1):PAGE57_I168@PURE_QUANTA.SOCKET4677_AZIF0045P001C01CS(CHIPS)':
 'DDR6_SB_DQS_DN1': CDS_PINID='DDR6_SB_DQS_DN1';
NODE_NAME     J29 116
 '@S9S_MB_2U_LIB.S9S_MB_2U(SCH_1):PAGE110_I180@PURE_QUANTA.SCONN288_ADR50017P130CC(CHIPS)':
 'DQS1_B_C': CDS_PINID='DQS1_B_C';
NODE_NAME     J30 116
 '@S9S_MB_2U_LIB.S9S_MB_2U(SCH_1):PAGE111_I180@PURE_QUANTA.SCONN288_ADR50017P087CC(CHIPS)':
 'DQS1_B_C': CDS_PINID='DQS1_B_C';
NET_NAME
'M_G_CPU1_SB_DQS_DN<2>'
 '@S9S_MB_2U_LIB.S9S_MB_2U(SCH_1):M_G_CPU1_SB_DQS_DN'<2>:
 C_SIGNAL='@s9s_mb_2u_lib.s9s_mb_2u(sch_1):m_g_cpu1_sb_dqs_dn(2)';
NODE_NAME     U1 DV24
 '@S9S_MB_2U_LIB.S9S_MB_2U(SCH_1):PAGE57_I168@PURE_QUANTA.SOCKET4677_AZIF0045P001C01CS(CHIPS)':
 'DDR6_SB_DQS_DN2': CDS_PINID='DDR6_SB_DQS_DN2';
NODE_NAME     J29 127
 '@S9S_MB_2U_LIB.S9S_MB_2U(SCH_1):PAGE110_I180@PURE_QUANTA.SCONN288_ADR50017P130CC(CHIPS)':
 'DQS2_B_C': CDS_PINID='DQS2_B_C';
NODE_NAME     J30 127
 '@S9S_MB_2U_LIB.S9S_MB_2U(SCH_1):PAGE111_I180@PURE_QUANTA.SCONN288_ADR50017P087CC(CHIPS)':
 'DQS2_B_C': CDS_PINID='DQS2_B_C';
NET_NAME
'M_G_CPU1_SB_DQS_DN<3>'
 '@S9S_MB_2U_LIB.S9S_MB_2U(SCH_1):M_G_CPU1_SB_DQS_DN'<3>:
 C_SIGNAL='@s9s_mb_2u_lib.s9s_mb_2u(sch_1):m_g_cpu1_sb_dqs_dn(3)';
NODE_NAME     U1 EP6
 '@S9S_MB_2U_LIB.S9S_MB_2U(SCH_1):PAGE57_I168@PURE_QUANTA.SOCKET4677_AZIF0045P001C01CS(CHIPS)':
 'DDR6_SB_DQS_DN3': CDS_PINID='DDR6_SB_DQS_DN3';
NODE_NAME     J29 138
 '@S9S_MB_2U_LIB.S9S_MB_2U(SCH_1):PAGE110_I180@PURE_QUANTA.SCONN288_ADR50017P130CC(CHIPS)':
 'DQS3_B_C': CDS_PINID='DQS3_B_C';
NODE_NAME     J30 138
 '@S9S_MB_2U_LIB.S9S_MB_2U(SCH_1):PAGE111_I180@PURE_QUANTA.SCONN288_ADR50017P087CC(CHIPS)':
 'DQS3_B_C': CDS_PINID='DQS3_B_C';
NET_NAME
'M_G_CPU1_SB_DQS_DN<4>'
 '@S9S_MB_2U_LIB.S9S_MB_2U(SCH_1):M_G_CPU1_SB_DQS_DN'<4>:
 C_SIGNAL='@s9s_mb_2u_lib.s9s_mb_2u(sch_1):m_g_cpu1_sb_dqs_dn(4)';
NODE_NAME     U1 EB36
 '@S9S_MB_2U_LIB.S9S_MB_2U(SCH_1):PAGE57_I168@PURE_QUANTA.SOCKET4677_AZIF0045P001C01CS(CHIPS)':
 'DDR6_SB_DQS_DN4': CDS_PINID='DDR6_SB_DQS_DN4';
NODE_NAME     J29 238
 '@S9S_MB_2U_LIB.S9S_MB_2U(SCH_1):PAGE110_I180@PURE_QUANTA.SCONN288_ADR50017P130CC(CHIPS)':
 'DQS4_B_C': CDS_PINID='DQS4_B_C';
NODE_NAME     J30 238
 '@S9S_MB_2U_LIB.S9S_MB_2U(SCH_1):PAGE111_I180@PURE_QUANTA.SCONN288_ADR50017P087CC(CHIPS)':
 'DQS4_B_C': CDS_PINID='DQS4_B_C';
NET_NAME
'M_G_CPU1_SB_DQS_DN<5>'
 '@S9S_MB_2U_LIB.S9S_MB_2U(SCH_1):M_G_CPU1_SB_DQS_DN'<5>:
 C_SIGNAL='@s9s_mb_2u_lib.s9s_mb_2u(sch_1):m_g_cpu1_sb_dqs_dn(5)';
NODE_NAME     U1 DR33
 '@S9S_MB_2U_LIB.S9S_MB_2U(SCH_1):PAGE57_I168@PURE_QUANTA.SOCKET4677_AZIF0045P001C01CS(CHIPS)':
 'DDR6_SB_DQS_DN5': CDS_PINID='DDR6_SB_DQS_DN5';
NODE_NAME     J29 249
 '@S9S_MB_2U_LIB.S9S_MB_2U(SCH_1):PAGE110_I180@PURE_QUANTA.SCONN288_ADR50017P130CC(CHIPS)':
 'DQS5_B_C||TDQS5_B_C': CDS_PINID='\dqs5_b_c||tdqs5_b_c\';
NODE_NAME     J30 249
 '@S9S_MB_2U_LIB.S9S_MB_2U(SCH_1):PAGE111_I180@PURE_QUANTA.SCONN288_ADR50017P087CC(CHIPS)':
 'DQS5_B_C||TDQS5_B_C': CDS_PINID='\dqs5_b_c||tdqs5_b_c\';
NET_NAME
'M_G_CPU1_SB_DQS_DN<6>'
 '@S9S_MB_2U_LIB.S9S_MB_2U(SCH_1):M_G_CPU1_SB_DQS_DN'<6>:
 C_SIGNAL='@s9s_mb_2u_lib.s9s_mb_2u(sch_1):m_g_cpu1_sb_dqs_dn(6)';
NODE_NAME     U1 DN27
 '@S9S_MB_2U_LIB.S9S_MB_2U(SCH_1):PAGE57_I168@PURE_QUANTA.SOCKET4677_AZIF0045P001C01CS(CHIPS)':
 'DDR6_SB_DQS_DN6': CDS_PINID='DDR6_SB_DQS_DN6';
NODE_NAME     J29 260
 '@S9S_MB_2U_LIB.S9S_MB_2U(SCH_1):PAGE110_I180@PURE_QUANTA.SCONN288_ADR50017P130CC(CHIPS)':
 'DQS6_B_C||TDQS6_B_C': CDS_PINID='\dqs6_b_c||tdqs6_b_c\';
NODE_NAME     J30 260
 '@S9S_MB_2U_LIB.S9S_MB_2U(SCH_1):PAGE111_I180@PURE_QUANTA.SCONN288_ADR50017P087CC(CHIPS)':
 'DQS6_B_C||TDQS6_B_C': CDS_PINID='\dqs6_b_c||tdqs6_b_c\';
NET_NAME
'M_G_CPU1_SB_DQS_DN<7>'
 '@S9S_MB_2U_LIB.S9S_MB_2U(SCH_1):M_G_CPU1_SB_DQS_DN'<7>:
 C_SIGNAL='@s9s_mb_2u_lib.s9s_mb_2u(sch_1):m_g_cpu1_sb_dqs_dn(7)';
NODE_NAME     U1 EB24
 '@S9S_MB_2U_LIB.S9S_MB_2U(SCH_1):PAGE57_I168@PURE_QUANTA.SOCKET4677_AZIF0045P001C01CS(CHIPS)':
 'DDR6_SB_DQS_DN7': CDS_PINID='DDR6_SB_DQS_DN7';
NODE_NAME     J29 271
 '@S9S_MB_2U_LIB.S9S_MB_2U(SCH_1):PAGE110_I180@PURE_QUANTA.SCONN288_ADR50017P130CC(CHIPS)':
 'DQS7_B_C||TDQS7_B_C': CDS_PINID='\dqs7_b_c||tdqs7_b_c\';
NODE_NAME     J30 271
 '@S9S_MB_2U_LIB.S9S_MB_2U(SCH_1):PAGE111_I180@PURE_QUANTA.SCONN288_ADR50017P087CC(CHIPS)':
 'DQS7_B_C||TDQS7_B_C': CDS_PINID='\dqs7_b_c||tdqs7_b_c\';
NET_NAME
'M_G_CPU1_SB_DQS_DN<8>'
 '@S9S_MB_2U_LIB.S9S_MB_2U(SCH_1):M_G_CPU1_SB_DQS_DN'<8>:
 C_SIGNAL='@s9s_mb_2u_lib.s9s_mb_2u(sch_1):m_g_cpu1_sb_dqs_dn(8)';
NODE_NAME     U1 EM6
 '@S9S_MB_2U_LIB.S9S_MB_2U(SCH_1):PAGE57_I168@PURE_QUANTA.SOCKET4677_AZIF0045P001C01CS(CHIPS)':
 'DDR6_SB_DQS_DN8': CDS_PINID='DDR6_SB_DQS_DN8';
NODE_NAME     J29 282
 '@S9S_MB_2U_LIB.S9S_MB_2U(SCH_1):PAGE110_I180@PURE_QUANTA.SCONN288_ADR50017P130CC(CHIPS)':
 'DQS8_B_C||TDQS8_B_C': CDS_PINID='\dqs8_b_c||tdqs8_b_c\';
NODE_NAME     J30 282
 '@S9S_MB_2U_LIB.S9S_MB_2U(SCH_1):PAGE111_I180@PURE_QUANTA.SCONN288_ADR50017P087CC(CHIPS)':
 'DQS8_B_C||TDQS8_B_C': CDS_PINID='\dqs8_b_c||tdqs8_b_c\';
NET_NAME
'M_G_CPU1_SB_DQS_DN<9>'
 '@S9S_MB_2U_LIB.S9S_MB_2U(SCH_1):M_G_CPU1_SB_DQS_DN'<9>:
 C_SIGNAL='@s9s_mb_2u_lib.s9s_mb_2u(sch_1):m_g_cpu1_sb_dqs_dn(9)';
NODE_NAME     U1 DV36
 '@S9S_MB_2U_LIB.S9S_MB_2U(SCH_1):PAGE57_I168@PURE_QUANTA.SOCKET4677_AZIF0045P001C01CS(CHIPS)':
 'DDR6_SB_DQS_DN9': CDS_PINID='DDR6_SB_DQS_DN9';
NODE_NAME     J29 94
 '@S9S_MB_2U_LIB.S9S_MB_2U(SCH_1):PAGE110_I180@PURE_QUANTA.SCONN288_ADR50017P130CC(CHIPS)':
 'DQS9_B_C||TDQS9_B_C': CDS_PINID='\dqs9_b_c||tdqs9_b_c\';
NODE_NAME     J30 94
 '@S9S_MB_2U_LIB.S9S_MB_2U(SCH_1):PAGE111_I180@PURE_QUANTA.SCONN288_ADR50017P087CC(CHIPS)':
 'DQS9_B_C||TDQS9_B_C': CDS_PINID='\dqs9_b_c||tdqs9_b_c\';
NET_NAME
'M_G_CPU1_SB_DQS_DP<0>'
 '@S9S_MB_2U_LIB.S9S_MB_2U(SCH_1):M_G_CPU1_SB_DQS_DP'<0>:
 C_SIGNAL='@s9s_mb_2u_lib.s9s_mb_2u(sch_1):m_g_cpu1_sb_dqs_dp(0)';
NODE_NAME     U1 DL33
 '@S9S_MB_2U_LIB.S9S_MB_2U(SCH_1):PAGE57_I168@PURE_QUANTA.SOCKET4677_AZIF0045P001C01CS(CHIPS)':
 'DDR6_SB_DQS_DP0': CDS_PINID='DDR6_SB_DQS_DP0';
NODE_NAME     J29 104
 '@S9S_MB_2U_LIB.S9S_MB_2U(SCH_1):PAGE110_I180@PURE_QUANTA.SCONN288_ADR50017P130CC(CHIPS)':
 'DQS0_B_T': CDS_PINID='DQS0_B_T';
NODE_NAME     J30 104
 '@S9S_MB_2U_LIB.S9S_MB_2U(SCH_1):PAGE111_I180@PURE_QUANTA.SCONN288_ADR50017P087CC(CHIPS)':
 'DQS0_B_T': CDS_PINID='DQS0_B_T';
NET_NAME
'M_G_CPU1_SB_DQS_DP<1>'
 '@S9S_MB_2U_LIB.S9S_MB_2U(SCH_1):M_G_CPU1_SB_DQS_DP'<1>:
 C_SIGNAL='@s9s_mb_2u_lib.s9s_mb_2u(sch_1):m_g_cpu1_sb_dqs_dp(1)';
NODE_NAME     U1 DL27
 '@S9S_MB_2U_LIB.S9S_MB_2U(SCH_1):PAGE57_I168@PURE_QUANTA.SOCKET4677_AZIF0045P001C01CS(CHIPS)':
 'DDR6_SB_DQS_DP1': CDS_PINID='DDR6_SB_DQS_DP1';
NODE_NAME     J29 115
 '@S9S_MB_2U_LIB.S9S_MB_2U(SCH_1):PAGE110_I180@PURE_QUANTA.SCONN288_ADR50017P130CC(CHIPS)':
 'DQS1_B_T': CDS_PINID='DQS1_B_T';
NODE_NAME     J30 115
 '@S9S_MB_2U_LIB.S9S_MB_2U(SCH_1):PAGE111_I180@PURE_QUANTA.SCONN288_ADR50017P087CC(CHIPS)':
 'DQS1_B_T': CDS_PINID='DQS1_B_T';
NET_NAME
'M_G_CPU1_SB_DQS_DP<2>'
 '@S9S_MB_2U_LIB.S9S_MB_2U(SCH_1):M_G_CPU1_SB_DQS_DP'<2>:
 C_SIGNAL='@s9s_mb_2u_lib.s9s_mb_2u(sch_1):m_g_cpu1_sb_dqs_dp(2)';
NODE_NAME     U1 DT24
 '@S9S_MB_2U_LIB.S9S_MB_2U(SCH_1):PAGE57_I168@PURE_QUANTA.SOCKET4677_AZIF0045P001C01CS(CHIPS)':
 'DDR6_SB_DQS_DP2': CDS_PINID='DDR6_SB_DQS_DP2';
NODE_NAME     J29 126
 '@S9S_MB_2U_LIB.S9S_MB_2U(SCH_1):PAGE110_I180@PURE_QUANTA.SCONN288_ADR50017P130CC(CHIPS)':
 'DQS2_B_T': CDS_PINID='DQS2_B_T';
NODE_NAME     J30 126
 '@S9S_MB_2U_LIB.S9S_MB_2U(SCH_1):PAGE111_I180@PURE_QUANTA.SCONN288_ADR50017P087CC(CHIPS)':
 'DQS2_B_T': CDS_PINID='DQS2_B_T';
NET_NAME
'M_G_CPU1_SB_DQS_DP<3>'
 '@S9S_MB_2U_LIB.S9S_MB_2U(SCH_1):M_G_CPU1_SB_DQS_DP'<3>:
 C_SIGNAL='@s9s_mb_2u_lib.s9s_mb_2u(sch_1):m_g_cpu1_sb_dqs_dp(3)';
NODE_NAME     U1 EN7
 '@S9S_MB_2U_LIB.S9S_MB_2U(SCH_1):PAGE57_I168@PURE_QUANTA.SOCKET4677_AZIF0045P001C01CS(CHIPS)':
 'DDR6_SB_DQS_DP3': CDS_PINID='DDR6_SB_DQS_DP3';
NODE_NAME     J29 137
 '@S9S_MB_2U_LIB.S9S_MB_2U(SCH_1):PAGE110_I180@PURE_QUANTA.SCONN288_ADR50017P130CC(CHIPS)':
 'DQS3_B_T': CDS_PINID='DQS3_B_T';
NODE_NAME     J30 137
 '@S9S_MB_2U_LIB.S9S_MB_2U(SCH_1):PAGE111_I180@PURE_QUANTA.SCONN288_ADR50017P087CC(CHIPS)':
 'DQS3_B_T': CDS_PINID='DQS3_B_T';
NET_NAME
'M_G_CPU1_SB_DQS_DP<4>'
 '@S9S_MB_2U_LIB.S9S_MB_2U(SCH_1):M_G_CPU1_SB_DQS_DP'<4>:
 C_SIGNAL='@s9s_mb_2u_lib.s9s_mb_2u(sch_1):m_g_cpu1_sb_dqs_dp(4)';
NODE_NAME     U1 DY36
 '@S9S_MB_2U_LIB.S9S_MB_2U(SCH_1):PAGE57_I168@PURE_QUANTA.SOCKET4677_AZIF0045P001C01CS(CHIPS)':
 'DDR6_SB_DQS_DP4': CDS_PINID='DDR6_SB_DQS_DP4';
NODE_NAME     J29 239
 '@S9S_MB_2U_LIB.S9S_MB_2U(SCH_1):PAGE110_I180@PURE_QUANTA.SCONN288_ADR50017P130CC(CHIPS)':
 'DQS4_B_T': CDS_PINID='DQS4_B_T';
NODE_NAME     J30 239
 '@S9S_MB_2U_LIB.S9S_MB_2U(SCH_1):PAGE111_I180@PURE_QUANTA.SCONN288_ADR50017P087CC(CHIPS)':
 'DQS4_B_T': CDS_PINID='DQS4_B_T';
NET_NAME
'M_G_CPU1_SB_DQS_DP<5>'
 '@S9S_MB_2U_LIB.S9S_MB_2U(SCH_1):M_G_CPU1_SB_DQS_DP'<5>:
 C_SIGNAL='@s9s_mb_2u_lib.s9s_mb_2u(sch_1):m_g_cpu1_sb_dqs_dp(5)';
NODE_NAME     U1 DN33
 '@S9S_MB_2U_LIB.S9S_MB_2U(SCH_1):PAGE57_I168@PURE_QUANTA.SOCKET4677_AZIF0045P001C01CS(CHIPS)':
 'DDR6_SB_DQS_DP5': CDS_PINID='DDR6_SB_DQS_DP5';
NODE_NAME     J29 250
 '@S9S_MB_2U_LIB.S9S_MB_2U(SCH_1):PAGE110_I180@PURE_QUANTA.SCONN288_ADR50017P130CC(CHIPS)':
 'DQS5_B_T||TDQS5_B_T': CDS_PINID='\dqs5_b_t||tdqs5_b_t\';
NODE_NAME     J30 250
 '@S9S_MB_2U_LIB.S9S_MB_2U(SCH_1):PAGE111_I180@PURE_QUANTA.SCONN288_ADR50017P087CC(CHIPS)':
 'DQS5_B_T||TDQS5_B_T': CDS_PINID='\dqs5_b_t||tdqs5_b_t\';
NET_NAME
'M_G_CPU1_SB_DQS_DP<6>'
 '@S9S_MB_2U_LIB.S9S_MB_2U(SCH_1):M_G_CPU1_SB_DQS_DP'<6>:
 C_SIGNAL='@s9s_mb_2u_lib.s9s_mb_2u(sch_1):m_g_cpu1_sb_dqs_dp(6)';
NODE_NAME     U1 DR27
 '@S9S_MB_2U_LIB.S9S_MB_2U(SCH_1):PAGE57_I168@PURE_QUANTA.SOCKET4677_AZIF0045P001C01CS(CHIPS)':
 'DDR6_SB_DQS_DP6': CDS_PINID='DDR6_SB_DQS_DP6';
NODE_NAME     J29 261
 '@S9S_MB_2U_LIB.S9S_MB_2U(SCH_1):PAGE110_I180@PURE_QUANTA.SCONN288_ADR50017P130CC(CHIPS)':
 'DQS6_B_T||TDQS6_B_T': CDS_PINID='\dqs6_b_t||tdqs6_b_t\';
NODE_NAME     J30 261
 '@S9S_MB_2U_LIB.S9S_MB_2U(SCH_1):PAGE111_I180@PURE_QUANTA.SCONN288_ADR50017P087CC(CHIPS)':
 'DQS6_B_T||TDQS6_B_T': CDS_PINID='\dqs6_b_t||tdqs6_b_t\';
NET_NAME
'M_G_CPU1_SB_DQS_DP<7>'
 '@S9S_MB_2U_LIB.S9S_MB_2U(SCH_1):M_G_CPU1_SB_DQS_DP'<7>:
 C_SIGNAL='@s9s_mb_2u_lib.s9s_mb_2u(sch_1):m_g_cpu1_sb_dqs_dp(7)';
NODE_NAME     U1 DY24
 '@S9S_MB_2U_LIB.S9S_MB_2U(SCH_1):PAGE57_I168@PURE_QUANTA.SOCKET4677_AZIF0045P001C01CS(CHIPS)':
 'DDR6_SB_DQS_DP7': CDS_PINID='DDR6_SB_DQS_DP7';
NODE_NAME     J29 272
 '@S9S_MB_2U_LIB.S9S_MB_2U(SCH_1):PAGE110_I180@PURE_QUANTA.SCONN288_ADR50017P130CC(CHIPS)':
 'DQS7_B_T||TDQS7_B_T': CDS_PINID='\dqs7_b_t||tdqs7_b_t\';
NODE_NAME     J30 272
 '@S9S_MB_2U_LIB.S9S_MB_2U(SCH_1):PAGE111_I180@PURE_QUANTA.SCONN288_ADR50017P087CC(CHIPS)':
 'DQS7_B_T||TDQS7_B_T': CDS_PINID='\dqs7_b_t||tdqs7_b_t\';
NET_NAME
'M_G_CPU1_SB_DQS_DP<8>'
 '@S9S_MB_2U_LIB.S9S_MB_2U(SCH_1):M_G_CPU1_SB_DQS_DP'<8>:
 C_SIGNAL='@s9s_mb_2u_lib.s9s_mb_2u(sch_1):m_g_cpu1_sb_dqs_dp(8)';
NODE_NAME     U1 EN5
 '@S9S_MB_2U_LIB.S9S_MB_2U(SCH_1):PAGE57_I168@PURE_QUANTA.SOCKET4677_AZIF0045P001C01CS(CHIPS)':
 'DDR6_SB_DQS_DP8': CDS_PINID='DDR6_SB_DQS_DP8';
NODE_NAME     J29 283
 '@S9S_MB_2U_LIB.S9S_MB_2U(SCH_1):PAGE110_I180@PURE_QUANTA.SCONN288_ADR50017P130CC(CHIPS)':
 'DQS8_B_T||TDQS8_B_T': CDS_PINID='\dqs8_b_t||tdqs8_b_t\';
NODE_NAME     J30 283
 '@S9S_MB_2U_LIB.S9S_MB_2U(SCH_1):PAGE111_I180@PURE_QUANTA.SCONN288_ADR50017P087CC(CHIPS)':
 'DQS8_B_T||TDQS8_B_T': CDS_PINID='\dqs8_b_t||tdqs8_b_t\';
NET_NAME
'M_G_CPU1_SB_DQS_DP<9>'
 '@S9S_MB_2U_LIB.S9S_MB_2U(SCH_1):M_G_CPU1_SB_DQS_DP'<9>:
 C_SIGNAL='@s9s_mb_2u_lib.s9s_mb_2u(sch_1):m_g_cpu1_sb_dqs_dp(9)';
NODE_NAME     U1 DT36
 '@S9S_MB_2U_LIB.S9S_MB_2U(SCH_1):PAGE57_I168@PURE_QUANTA.SOCKET4677_AZIF0045P001C01CS(CHIPS)':
 'DDR6_SB_DQS_DP9': CDS_PINID='DDR6_SB_DQS_DP9';
NODE_NAME     J29 93
 '@S9S_MB_2U_LIB.S9S_MB_2U(SCH_1):PAGE110_I180@PURE_QUANTA.SCONN288_ADR50017P130CC(CHIPS)':
 'DQS9_B_T||TDQS9_B_T||DBI4_B_N': CDS_PINID='\dqs9_b_t||tdqs9_b_t||dbi4_b_n\';
NODE_NAME     J30 93
 '@S9S_MB_2U_LIB.S9S_MB_2U(SCH_1):PAGE111_I180@PURE_QUANTA.SCONN288_ADR50017P087CC(CHIPS)':
 'DQS9_B_T||TDQS9_B_T||DBI4_B_N': CDS_PINID='\dqs9_b_t||tdqs9_b_t||dbi4_b_n\';
NET_NAME
'M_G_CPU1_SB_PAR'
 '@S9S_MB_2U_LIB.S9S_MB_2U(SCH_1):M_G_CPU1_SB_PAR':
 C_SIGNAL='@s9s_mb_2u_lib.s9s_mb_2u(sch_1):m_g_cpu1_sb_par';
NODE_NAME     U1 EB42
 '@S9S_MB_2U_LIB.S9S_MB_2U(SCH_1):PAGE57_I168@PURE_QUANTA.SOCKET4677_AZIF0045P001C01CS(CHIPS)':
 'DDR6_SB_PAR': CDS_PINID='DDR6_SB_PAR';
NODE_NAME     J29 227
 '@S9S_MB_2U_LIB.S9S_MB_2U(SCH_1):PAGE110_I179@PURE_QUANTA.SCONN288_ADR50017P130CC(CHIPS)':
 'PAR_B': CDS_PINID='PAR_B';
NODE_NAME     J30 227
 '@S9S_MB_2U_LIB.S9S_MB_2U(SCH_1):PAGE111_I179@PURE_QUANTA.SCONN288_ADR50017P087CC(CHIPS)':
 'PAR_B': CDS_PINID='PAR_B';
NET_NAME
'M_G_CPU1_SB_RSP<0>'
 '@S9S_MB_2U_LIB.S9S_MB_2U(SCH_1):M_G_CPU1_SB_RSP'<0>:
 C_SIGNAL='@s9s_mb_2u_lib.s9s_mb_2u(sch_1):m_g_cpu1_sb_rsp(0)';
NODE_NAME     U1 DU48
 '@S9S_MB_2U_LIB.S9S_MB_2U(SCH_1):PAGE57_I168@PURE_QUANTA.SOCKET4677_AZIF0045P001C01CS(CHIPS)':
 'DDR6_B_RSP0': CDS_PINID='DDR6_B_RSP0';
NODE_NAME     J29 87
 '@S9S_MB_2U_LIB.S9S_MB_2U(SCH_1):PAGE110_I179@PURE_QUANTA.SCONN288_ADR50017P130CC(CHIPS)':
 'LBS||RSP_B_N': CDS_PINID='\lbs||rsp_b_n\';
NET_NAME
'M_G_CPU1_SB_RSP<1>'
 '@S9S_MB_2U_LIB.S9S_MB_2U(SCH_1):M_G_CPU1_SB_RSP'<1>:
 C_SIGNAL='@s9s_mb_2u_lib.s9s_mb_2u(sch_1):m_g_cpu1_sb_rsp(1)';
NODE_NAME     U1 DV47
 '@S9S_MB_2U_LIB.S9S_MB_2U(SCH_1):PAGE57_I168@PURE_QUANTA.SOCKET4677_AZIF0045P001C01CS(CHIPS)':
 'DDR6_B_RSP1': CDS_PINID='DDR6_B_RSP1';
NODE_NAME     J30 87
 '@S9S_MB_2U_LIB.S9S_MB_2U(SCH_1):PAGE111_I179@PURE_QUANTA.SCONN288_ADR50017P087CC(CHIPS)':
 'LBS||RSP_B_N': CDS_PINID='\lbs||rsp_b_n\';
NET_NAME
'M_H_CPU0_ALERT_N'
 '@S9S_MB_2U_LIB.S9S_MB_2U(SCH_1):M_H_CPU0_ALERT_N':
 C_SIGNAL='@s9s_mb_2u_lib.s9s_mb_2u(sch_1):m_h_cpu0_alert_n';
NODE_NAME     U2 CY51
 '@S9S_MB_2U_LIB.S9S_MB_2U(SCH_1):PAGE27_I169@PURE_QUANTA.SOCKET4677_AZIF0045P001C01CS(CHIPS)':
 'DDR7_ALERT_N': CDS_PINID='DDR7_ALERT_N';
NODE_NAME     J15 62
 '@S9S_MB_2U_LIB.S9S_MB_2U(SCH_1):PAGE96_I48@PURE_QUANTA.SCONN288_ADR50017P130CC(CHIPS)':
 'ALERT_N': CDS_PINID='ALERT_N';
NODE_NAME     J16 62
 '@S9S_MB_2U_LIB.S9S_MB_2U(SCH_1):PAGE97_I6@PURE_QUANTA.SCONN288_ADR50017P087CC(CHIPS)':
 'ALERT_N': CDS_PINID='ALERT_N';
NET_NAME
'M_H_CPU0_CLK_DN<0>'
 '@S9S_MB_2U_LIB.S9S_MB_2U(SCH_1):M_H_CPU0_CLK_DN'<0>:
 C_SIGNAL='@s9s_mb_2u_lib.s9s_mb_2u(sch_1):m_h_cpu0_clk_dn(0)';
NODE_NAME     U2 DH42
 '@S9S_MB_2U_LIB.S9S_MB_2U(SCH_1):PAGE27_I169@PURE_QUANTA.SOCKET4677_AZIF0045P001C01CS(CHIPS)':
 'DDR7_CLK_DN0': CDS_PINID='DDR7_CLK_DN0';
NODE_NAME     J15 218
 '@S9S_MB_2U_LIB.S9S_MB_2U(SCH_1):PAGE96_I48@PURE_QUANTA.SCONN288_ADR50017P130CC(CHIPS)':
 'CK_C': CDS_PINID='CK_C';
NET_NAME
'M_H_CPU0_CLK_DN<1>'
 '@S9S_MB_2U_LIB.S9S_MB_2U(SCH_1):M_H_CPU0_CLK_DN'<1>:
 C_SIGNAL='@s9s_mb_2u_lib.s9s_mb_2u(sch_1):m_h_cpu0_clk_dn(1)';
NODE_NAME     U2 DD42
 '@S9S_MB_2U_LIB.S9S_MB_2U(SCH_1):PAGE27_I169@PURE_QUANTA.SOCKET4677_AZIF0045P001C01CS(CHIPS)':
 'DDR7_CLK_DN1': CDS_PINID='DDR7_CLK_DN1';
NODE_NAME     J16 218
 '@S9S_MB_2U_LIB.S9S_MB_2U(SCH_1):PAGE97_I6@PURE_QUANTA.SCONN288_ADR50017P087CC(CHIPS)':
 'CK_C': CDS_PINID='CK_C';
NET_NAME
'M_H_CPU0_CLK_DP<0>'
 '@S9S_MB_2U_LIB.S9S_MB_2U(SCH_1):M_H_CPU0_CLK_DP'<0>:
 C_SIGNAL='@s9s_mb_2u_lib.s9s_mb_2u(sch_1):m_h_cpu0_clk_dp(0)';
NODE_NAME     U2 DF42
 '@S9S_MB_2U_LIB.S9S_MB_2U(SCH_1):PAGE27_I169@PURE_QUANTA.SOCKET4677_AZIF0045P001C01CS(CHIPS)':
 'DDR7_CLK_DP0': CDS_PINID='DDR7_CLK_DP0';
NODE_NAME     J15 217
 '@S9S_MB_2U_LIB.S9S_MB_2U(SCH_1):PAGE96_I48@PURE_QUANTA.SCONN288_ADR50017P130CC(CHIPS)':
 'CK_T': CDS_PINID='CK_T';
NET_NAME
'M_H_CPU0_CLK_DP<1>'
 '@S9S_MB_2U_LIB.S9S_MB_2U(SCH_1):M_H_CPU0_CLK_DP'<1>:
 C_SIGNAL='@s9s_mb_2u_lib.s9s_mb_2u(sch_1):m_h_cpu0_clk_dp(1)';
NODE_NAME     U2 DB42
 '@S9S_MB_2U_LIB.S9S_MB_2U(SCH_1):PAGE27_I169@PURE_QUANTA.SOCKET4677_AZIF0045P001C01CS(CHIPS)':
 'DDR7_CLK_DP1': CDS_PINID='DDR7_CLK_DP1';
NODE_NAME     J16 217
 '@S9S_MB_2U_LIB.S9S_MB_2U(SCH_1):PAGE97_I6@PURE_QUANTA.SCONN288_ADR50017P087CC(CHIPS)':
 'CK_T': CDS_PINID='CK_T';
NET_NAME
'M_H_CPU0_SA_CA<0>'
 '@S9S_MB_2U_LIB.S9S_MB_2U(SCH_1):M_H_CPU0_SA_CA'<0>:
 C_SIGNAL='@s9s_mb_2u_lib.s9s_mb_2u(sch_1):m_h_cpu0_sa_ca(0)';
NODE_NAME     U2 DB49
 '@S9S_MB_2U_LIB.S9S_MB_2U(SCH_1):PAGE27_I169@PURE_QUANTA.SOCKET4677_AZIF0045P001C01CS(CHIPS)':
 'DDR7_SA_CA0': CDS_PINID='DDR7_SA_CA0';
NODE_NAME     J15 66
 '@S9S_MB_2U_LIB.S9S_MB_2U(SCH_1):PAGE96_I48@PURE_QUANTA.SCONN288_ADR50017P130CC(CHIPS)':
 'CA0_A': CDS_PINID='CA0_A';
NODE_NAME     J16 66
 '@S9S_MB_2U_LIB.S9S_MB_2U(SCH_1):PAGE97_I6@PURE_QUANTA.SCONN288_ADR50017P087CC(CHIPS)':
 'CA0_A': CDS_PINID='CA0_A';
NET_NAME
'M_H_CPU0_SA_CA<1>'
 '@S9S_MB_2U_LIB.S9S_MB_2U(SCH_1):M_H_CPU0_SA_CA'<1>:
 C_SIGNAL='@s9s_mb_2u_lib.s9s_mb_2u(sch_1):m_h_cpu0_sa_ca(1)';
NODE_NAME     U2 DH49
 '@S9S_MB_2U_LIB.S9S_MB_2U(SCH_1):PAGE27_I169@PURE_QUANTA.SOCKET4677_AZIF0045P001C01CS(CHIPS)':
 'DDR7_SA_CA1': CDS_PINID='DDR7_SA_CA1';
NODE_NAME     J15 211
 '@S9S_MB_2U_LIB.S9S_MB_2U(SCH_1):PAGE96_I48@PURE_QUANTA.SCONN288_ADR50017P130CC(CHIPS)':
 'CA1_A': CDS_PINID='CA1_A';
NODE_NAME     J16 211
 '@S9S_MB_2U_LIB.S9S_MB_2U(SCH_1):PAGE97_I6@PURE_QUANTA.SCONN288_ADR50017P087CC(CHIPS)':
 'CA1_A': CDS_PINID='CA1_A';
NET_NAME
'M_H_CPU0_SA_CA<2>'
 '@S9S_MB_2U_LIB.S9S_MB_2U(SCH_1):M_H_CPU0_SA_CA'<2>:
 C_SIGNAL='@s9s_mb_2u_lib.s9s_mb_2u(sch_1):m_h_cpu0_sa_ca(2)';
NODE_NAME     U2 DC48
 '@S9S_MB_2U_LIB.S9S_MB_2U(SCH_1):PAGE27_I169@PURE_QUANTA.SOCKET4677_AZIF0045P001C01CS(CHIPS)':
 'DDR7_SA_CA2': CDS_PINID='DDR7_SA_CA2';
NODE_NAME     J15 68
 '@S9S_MB_2U_LIB.S9S_MB_2U(SCH_1):PAGE96_I48@PURE_QUANTA.SCONN288_ADR50017P130CC(CHIPS)':
 'CA2_A': CDS_PINID='CA2_A';
NODE_NAME     J16 68
 '@S9S_MB_2U_LIB.S9S_MB_2U(SCH_1):PAGE97_I6@PURE_QUANTA.SCONN288_ADR50017P087CC(CHIPS)':
 'CA2_A': CDS_PINID='CA2_A';
NET_NAME
'M_H_CPU0_SA_CA<3>'
 '@S9S_MB_2U_LIB.S9S_MB_2U(SCH_1):M_H_CPU0_SA_CA'<3>:
 C_SIGNAL='@s9s_mb_2u_lib.s9s_mb_2u(sch_1):m_h_cpu0_sa_ca(3)';
NODE_NAME     U2 DG48
 '@S9S_MB_2U_LIB.S9S_MB_2U(SCH_1):PAGE27_I169@PURE_QUANTA.SOCKET4677_AZIF0045P001C01CS(CHIPS)':
 'DDR7_SA_CA3': CDS_PINID='DDR7_SA_CA3';
NODE_NAME     J15 213
 '@S9S_MB_2U_LIB.S9S_MB_2U(SCH_1):PAGE96_I48@PURE_QUANTA.SCONN288_ADR50017P130CC(CHIPS)':
 'CA3_A': CDS_PINID='CA3_A';
NODE_NAME     J16 213
 '@S9S_MB_2U_LIB.S9S_MB_2U(SCH_1):PAGE97_I6@PURE_QUANTA.SCONN288_ADR50017P087CC(CHIPS)':
 'CA3_A': CDS_PINID='CA3_A';
NET_NAME
'M_H_CPU0_SA_CA<4>'
 '@S9S_MB_2U_LIB.S9S_MB_2U(SCH_1):M_H_CPU0_SA_CA'<4>:
 C_SIGNAL='@s9s_mb_2u_lib.s9s_mb_2u(sch_1):m_h_cpu0_sa_ca(4)';
NODE_NAME     U2 DD47
 '@S9S_MB_2U_LIB.S9S_MB_2U(SCH_1):PAGE27_I169@PURE_QUANTA.SOCKET4677_AZIF0045P001C01CS(CHIPS)':
 'DDR7_SA_CA4': CDS_PINID='DDR7_SA_CA4';
NODE_NAME     J15 70
 '@S9S_MB_2U_LIB.S9S_MB_2U(SCH_1):PAGE96_I48@PURE_QUANTA.SCONN288_ADR50017P130CC(CHIPS)':
 'CA4_A': CDS_PINID='CA4_A';
NODE_NAME     J16 70
 '@S9S_MB_2U_LIB.S9S_MB_2U(SCH_1):PAGE97_I6@PURE_QUANTA.SCONN288_ADR50017P087CC(CHIPS)':
 'CA4_A': CDS_PINID='CA4_A';
NET_NAME
'M_H_CPU0_SA_CA<5>'
 '@S9S_MB_2U_LIB.S9S_MB_2U(SCH_1):M_H_CPU0_SA_CA'<5>:
 C_SIGNAL='@s9s_mb_2u_lib.s9s_mb_2u(sch_1):m_h_cpu0_sa_ca(5)';
NODE_NAME     U2 DF47
 '@S9S_MB_2U_LIB.S9S_MB_2U(SCH_1):PAGE27_I169@PURE_QUANTA.SOCKET4677_AZIF0045P001C01CS(CHIPS)':
 'DDR7_SA_CA5': CDS_PINID='DDR7_SA_CA5';
NODE_NAME     J15 215
 '@S9S_MB_2U_LIB.S9S_MB_2U(SCH_1):PAGE96_I48@PURE_QUANTA.SCONN288_ADR50017P130CC(CHIPS)':
 'CA5_A': CDS_PINID='CA5_A';
NODE_NAME     J16 215
 '@S9S_MB_2U_LIB.S9S_MB_2U(SCH_1):PAGE97_I6@PURE_QUANTA.SCONN288_ADR50017P087CC(CHIPS)':
 'CA5_A': CDS_PINID='CA5_A';
NET_NAME
'M_H_CPU0_SA_CA<6>'
 '@S9S_MB_2U_LIB.S9S_MB_2U(SCH_1):M_H_CPU0_SA_CA'<6>:
 C_SIGNAL='@s9s_mb_2u_lib.s9s_mb_2u(sch_1):m_h_cpu0_sa_ca(6)';
NODE_NAME     U2 DC41
 '@S9S_MB_2U_LIB.S9S_MB_2U(SCH_1):PAGE27_I169@PURE_QUANTA.SOCKET4677_AZIF0045P001C01CS(CHIPS)':
 'DDR7_SA_CA6': CDS_PINID='DDR7_SA_CA6';
NODE_NAME     J15 72
 '@S9S_MB_2U_LIB.S9S_MB_2U(SCH_1):PAGE96_I48@PURE_QUANTA.SCONN288_ADR50017P130CC(CHIPS)':
 'CA6_A': CDS_PINID='CA6_A';
NODE_NAME     J16 72
 '@S9S_MB_2U_LIB.S9S_MB_2U(SCH_1):PAGE97_I6@PURE_QUANTA.SCONN288_ADR50017P087CC(CHIPS)':
 'CA6_A': CDS_PINID='CA6_A';
NET_NAME
'M_H_CPU0_SA_CB<0>'
 '@S9S_MB_2U_LIB.S9S_MB_2U(SCH_1):M_H_CPU0_SA_CB'<0>:
 C_SIGNAL='@s9s_mb_2u_lib.s9s_mb_2u(sch_1):m_h_cpu0_sa_cb(0)';
NODE_NAME     U2 DD57
 '@S9S_MB_2U_LIB.S9S_MB_2U(SCH_1):PAGE27_I169@PURE_QUANTA.SOCKET4677_AZIF0045P001C01CS(CHIPS)':
 'DDR7_SA_ECC0': CDS_PINID='DDR7_SA_ECC0';
NODE_NAME     J15 51
 '@S9S_MB_2U_LIB.S9S_MB_2U(SCH_1):PAGE96_I48@PURE_QUANTA.SCONN288_ADR50017P130CC(CHIPS)':
 'CB0_A': CDS_PINID='CB0_A';
NODE_NAME     J16 51
 '@S9S_MB_2U_LIB.S9S_MB_2U(SCH_1):PAGE97_I6@PURE_QUANTA.SCONN288_ADR50017P087CC(CHIPS)':
 'CB0_A': CDS_PINID='CB0_A';
NET_NAME
'M_H_CPU0_SA_CB<1>'
 '@S9S_MB_2U_LIB.S9S_MB_2U(SCH_1):M_H_CPU0_SA_CB'<1>:
 C_SIGNAL='@s9s_mb_2u_lib.s9s_mb_2u(sch_1):m_h_cpu0_sa_cb(1)';
NODE_NAME     U2 DC56
 '@S9S_MB_2U_LIB.S9S_MB_2U(SCH_1):PAGE27_I169@PURE_QUANTA.SOCKET4677_AZIF0045P001C01CS(CHIPS)':
 'DDR7_SA_ECC1': CDS_PINID='DDR7_SA_ECC1';
NODE_NAME     J15 53
 '@S9S_MB_2U_LIB.S9S_MB_2U(SCH_1):PAGE96_I48@PURE_QUANTA.SCONN288_ADR50017P130CC(CHIPS)':
 'CB1_A': CDS_PINID='CB1_A';
NODE_NAME     J16 53
 '@S9S_MB_2U_LIB.S9S_MB_2U(SCH_1):PAGE97_I6@PURE_QUANTA.SCONN288_ADR50017P087CC(CHIPS)':
 'CB1_A': CDS_PINID='CB1_A';
NET_NAME
'M_H_CPU0_SA_CB<2>'
 '@S9S_MB_2U_LIB.S9S_MB_2U(SCH_1):M_H_CPU0_SA_CB'<2>:
 C_SIGNAL='@s9s_mb_2u_lib.s9s_mb_2u(sch_1):m_h_cpu0_sa_cb(2)';
NODE_NAME     U2 DF57
 '@S9S_MB_2U_LIB.S9S_MB_2U(SCH_1):PAGE27_I169@PURE_QUANTA.SOCKET4677_AZIF0045P001C01CS(CHIPS)':
 'DDR7_SA_ECC2': CDS_PINID='DDR7_SA_ECC2';
NODE_NAME     J15 196
 '@S9S_MB_2U_LIB.S9S_MB_2U(SCH_1):PAGE96_I48@PURE_QUANTA.SCONN288_ADR50017P130CC(CHIPS)':
 'CB2_A': CDS_PINID='CB2_A';
NODE_NAME     J16 196
 '@S9S_MB_2U_LIB.S9S_MB_2U(SCH_1):PAGE97_I6@PURE_QUANTA.SCONN288_ADR50017P087CC(CHIPS)':
 'CB2_A': CDS_PINID='CB2_A';
NET_NAME
'M_H_CPU0_SA_CB<3>'
 '@S9S_MB_2U_LIB.S9S_MB_2U(SCH_1):M_H_CPU0_SA_CB'<3>:
 C_SIGNAL='@s9s_mb_2u_lib.s9s_mb_2u(sch_1):m_h_cpu0_sa_cb(3)';
NODE_NAME     U2 DG56
 '@S9S_MB_2U_LIB.S9S_MB_2U(SCH_1):PAGE27_I169@PURE_QUANTA.SOCKET4677_AZIF0045P001C01CS(CHIPS)':
 'DDR7_SA_ECC3': CDS_PINID='DDR7_SA_ECC3';
NODE_NAME     J15 198
 '@S9S_MB_2U_LIB.S9S_MB_2U(SCH_1):PAGE96_I48@PURE_QUANTA.SCONN288_ADR50017P130CC(CHIPS)':
 'CB3_A': CDS_PINID='CB3_A';
NODE_NAME     J16 198
 '@S9S_MB_2U_LIB.S9S_MB_2U(SCH_1):PAGE97_I6@PURE_QUANTA.SCONN288_ADR50017P087CC(CHIPS)':
 'CB3_A': CDS_PINID='CB3_A';
NET_NAME
'M_H_CPU0_SA_CB<4>'
 '@S9S_MB_2U_LIB.S9S_MB_2U(SCH_1):M_H_CPU0_SA_CB'<4>:
 C_SIGNAL='@s9s_mb_2u_lib.s9s_mb_2u(sch_1):m_h_cpu0_sa_cb(4)';
NODE_NAME     U2 DC54
 '@S9S_MB_2U_LIB.S9S_MB_2U(SCH_1):PAGE27_I169@PURE_QUANTA.SOCKET4677_AZIF0045P001C01CS(CHIPS)':
 'DDR7_SA_ECC4': CDS_PINID='DDR7_SA_ECC4';
NODE_NAME     J15 58
 '@S9S_MB_2U_LIB.S9S_MB_2U(SCH_1):PAGE96_I48@PURE_QUANTA.SCONN288_ADR50017P130CC(CHIPS)':
 'CB4_A': CDS_PINID='CB4_A';
NODE_NAME     J16 58
 '@S9S_MB_2U_LIB.S9S_MB_2U(SCH_1):PAGE97_I6@PURE_QUANTA.SCONN288_ADR50017P087CC(CHIPS)':
 'CB4_A': CDS_PINID='CB4_A';
NET_NAME
'M_H_CPU0_SA_CB<5>'
 '@S9S_MB_2U_LIB.S9S_MB_2U(SCH_1):M_H_CPU0_SA_CB'<5>:
 C_SIGNAL='@s9s_mb_2u_lib.s9s_mb_2u(sch_1):m_h_cpu0_sa_cb(5)';
NODE_NAME     U2 DD53
 '@S9S_MB_2U_LIB.S9S_MB_2U(SCH_1):PAGE27_I169@PURE_QUANTA.SOCKET4677_AZIF0045P001C01CS(CHIPS)':
 'DDR7_SA_ECC5': CDS_PINID='DDR7_SA_ECC5';
NODE_NAME     J15 60
 '@S9S_MB_2U_LIB.S9S_MB_2U(SCH_1):PAGE96_I48@PURE_QUANTA.SCONN288_ADR50017P130CC(CHIPS)':
 'CB5_A': CDS_PINID='CB5_A';
NODE_NAME     J16 60
 '@S9S_MB_2U_LIB.S9S_MB_2U(SCH_1):PAGE97_I6@PURE_QUANTA.SCONN288_ADR50017P087CC(CHIPS)':
 'CB5_A': CDS_PINID='CB5_A';
NET_NAME
'M_H_CPU0_SA_CB<6>'
 '@S9S_MB_2U_LIB.S9S_MB_2U(SCH_1):M_H_CPU0_SA_CB'<6>:
 C_SIGNAL='@s9s_mb_2u_lib.s9s_mb_2u(sch_1):m_h_cpu0_sa_cb(6)';
NODE_NAME     U2 DG54
 '@S9S_MB_2U_LIB.S9S_MB_2U(SCH_1):PAGE27_I169@PURE_QUANTA.SOCKET4677_AZIF0045P001C01CS(CHIPS)':
 'DDR7_SA_ECC6': CDS_PINID='DDR7_SA_ECC6';
NODE_NAME     J15 203
 '@S9S_MB_2U_LIB.S9S_MB_2U(SCH_1):PAGE96_I48@PURE_QUANTA.SCONN288_ADR50017P130CC(CHIPS)':
 'CB6_A': CDS_PINID='CB6_A';
NODE_NAME     J16 203
 '@S9S_MB_2U_LIB.S9S_MB_2U(SCH_1):PAGE97_I6@PURE_QUANTA.SCONN288_ADR50017P087CC(CHIPS)':
 'CB6_A': CDS_PINID='CB6_A';
NET_NAME
'M_H_CPU0_SA_CB<7>'
 '@S9S_MB_2U_LIB.S9S_MB_2U(SCH_1):M_H_CPU0_SA_CB'<7>:
 C_SIGNAL='@s9s_mb_2u_lib.s9s_mb_2u(sch_1):m_h_cpu0_sa_cb(7)';
NODE_NAME     U2 DF53
 '@S9S_MB_2U_LIB.S9S_MB_2U(SCH_1):PAGE27_I169@PURE_QUANTA.SOCKET4677_AZIF0045P001C01CS(CHIPS)':
 'DDR7_SA_ECC7': CDS_PINID='DDR7_SA_ECC7';
NODE_NAME     J15 205
 '@S9S_MB_2U_LIB.S9S_MB_2U(SCH_1):PAGE96_I48@PURE_QUANTA.SCONN288_ADR50017P130CC(CHIPS)':
 'CB7_A': CDS_PINID='CB7_A';
NODE_NAME     J16 205
 '@S9S_MB_2U_LIB.S9S_MB_2U(SCH_1):PAGE97_I6@PURE_QUANTA.SCONN288_ADR50017P087CC(CHIPS)':
 'CB7_A': CDS_PINID='CB7_A';
NET_NAME
'M_H_CPU0_SA_CS_N<0>'
 '@S9S_MB_2U_LIB.S9S_MB_2U(SCH_1):M_H_CPU0_SA_CS_N'<0>:
 C_SIGNAL='@s9s_mb_2u_lib.s9s_mb_2u(sch_1):m_h_cpu0_sa_cs_n(0)';
NODE_NAME     U2 DF51
 '@S9S_MB_2U_LIB.S9S_MB_2U(SCH_1):PAGE27_I169@PURE_QUANTA.SOCKET4677_AZIF0045P001C01CS(CHIPS)':
 'DDR7_SA_CS_N0': CDS_PINID='DDR7_SA_CS_N0';
NODE_NAME     J15 64
 '@S9S_MB_2U_LIB.S9S_MB_2U(SCH_1):PAGE96_I48@PURE_QUANTA.SCONN288_ADR50017P130CC(CHIPS)':
 'CS0_A_N': CDS_PINID='CS0_A_N';
NET_NAME
'M_H_CPU0_SA_CS_N<1>'
 '@S9S_MB_2U_LIB.S9S_MB_2U(SCH_1):M_H_CPU0_SA_CS_N'<1>:
 C_SIGNAL='@s9s_mb_2u_lib.s9s_mb_2u(sch_1):m_h_cpu0_sa_cs_n(1)';
NODE_NAME     U2 DG50
 '@S9S_MB_2U_LIB.S9S_MB_2U(SCH_1):PAGE27_I169@PURE_QUANTA.SOCKET4677_AZIF0045P001C01CS(CHIPS)':
 'DDR7_SA_CS_N1': CDS_PINID='DDR7_SA_CS_N1';
NODE_NAME     J15 209
 '@S9S_MB_2U_LIB.S9S_MB_2U(SCH_1):PAGE96_I48@PURE_QUANTA.SCONN288_ADR50017P130CC(CHIPS)':
 'CS1_A_N': CDS_PINID='CS1_A_N';
NET_NAME
'M_H_CPU0_SA_CS_N<2>'
 '@S9S_MB_2U_LIB.S9S_MB_2U(SCH_1):M_H_CPU0_SA_CS_N'<2>:
 C_SIGNAL='@s9s_mb_2u_lib.s9s_mb_2u(sch_1):m_h_cpu0_sa_cs_n(2)';
NODE_NAME     U2 DD51
 '@S9S_MB_2U_LIB.S9S_MB_2U(SCH_1):PAGE27_I169@PURE_QUANTA.SOCKET4677_AZIF0045P001C01CS(CHIPS)':
 'DDR7_SA_CS_N2': CDS_PINID='DDR7_SA_CS_N2';
NODE_NAME     J16 64
 '@S9S_MB_2U_LIB.S9S_MB_2U(SCH_1):PAGE97_I6@PURE_QUANTA.SCONN288_ADR50017P087CC(CHIPS)':
 'CS0_A_N': CDS_PINID='CS0_A_N';
NET_NAME
'M_H_CPU0_SA_CS_N<3>'
 '@S9S_MB_2U_LIB.S9S_MB_2U(SCH_1):M_H_CPU0_SA_CS_N'<3>:
 C_SIGNAL='@s9s_mb_2u_lib.s9s_mb_2u(sch_1):m_h_cpu0_sa_cs_n(3)';
NODE_NAME     U2 DC50
 '@S9S_MB_2U_LIB.S9S_MB_2U(SCH_1):PAGE27_I169@PURE_QUANTA.SOCKET4677_AZIF0045P001C01CS(CHIPS)':
 'DDR7_SA_CS_N3': CDS_PINID='DDR7_SA_CS_N3';
NODE_NAME     J16 209
 '@S9S_MB_2U_LIB.S9S_MB_2U(SCH_1):PAGE97_I6@PURE_QUANTA.SCONN288_ADR50017P087CC(CHIPS)':
 'CS1_A_N': CDS_PINID='CS1_A_N';
NET_NAME
'M_H_CPU0_SA_DQ<0>'
 '@S9S_MB_2U_LIB.S9S_MB_2U(SCH_1):M_H_CPU0_SA_DQ'<0>:
 C_SIGNAL='@s9s_mb_2u_lib.s9s_mb_2u(sch_1):m_h_cpu0_sa_dq(0)';
NODE_NAME     U2 DY79
 '@S9S_MB_2U_LIB.S9S_MB_2U(SCH_1):PAGE27_I169@PURE_QUANTA.SOCKET4677_AZIF0045P001C01CS(CHIPS)':
 'DDR7_SA_DQ0': CDS_PINID='DDR7_SA_DQ0';
NODE_NAME     J15 7
 '@S9S_MB_2U_LIB.S9S_MB_2U(SCH_1):PAGE96_I48@PURE_QUANTA.SCONN288_ADR50017P130CC(CHIPS)':
 'DQ0_A': CDS_PINID='DQ0_A';
NODE_NAME     J16 7
 '@S9S_MB_2U_LIB.S9S_MB_2U(SCH_1):PAGE97_I6@PURE_QUANTA.SCONN288_ADR50017P087CC(CHIPS)':
 'DQ0_A': CDS_PINID='DQ0_A';
NET_NAME
'M_H_CPU0_SA_DQ<10>'
 '@S9S_MB_2U_LIB.S9S_MB_2U(SCH_1):M_H_CPU0_SA_DQ'<10>:
 C_SIGNAL='@s9s_mb_2u_lib.s9s_mb_2u(sch_1):m_h_cpu0_sa_dq(10)';
NODE_NAME     U2 DF75
 '@S9S_MB_2U_LIB.S9S_MB_2U(SCH_1):PAGE27_I169@PURE_QUANTA.SOCKET4677_AZIF0045P001C01CS(CHIPS)':
 'DDR7_SA_DQ10': CDS_PINID='DDR7_SA_DQ10';
NODE_NAME     J15 163
 '@S9S_MB_2U_LIB.S9S_MB_2U(SCH_1):PAGE96_I48@PURE_QUANTA.SCONN288_ADR50017P130CC(CHIPS)':
 'DQ10_A': CDS_PINID='DQ10_A';
NODE_NAME     J16 163
 '@S9S_MB_2U_LIB.S9S_MB_2U(SCH_1):PAGE97_I6@PURE_QUANTA.SCONN288_ADR50017P087CC(CHIPS)':
 'DQ10_A': CDS_PINID='DQ10_A';
NET_NAME
'M_H_CPU0_SA_DQ<11>'
 '@S9S_MB_2U_LIB.S9S_MB_2U(SCH_1):M_H_CPU0_SA_DQ'<11>:
 C_SIGNAL='@s9s_mb_2u_lib.s9s_mb_2u(sch_1):m_h_cpu0_sa_dq(11)';
NODE_NAME     U2 DG74
 '@S9S_MB_2U_LIB.S9S_MB_2U(SCH_1):PAGE27_I169@PURE_QUANTA.SOCKET4677_AZIF0045P001C01CS(CHIPS)':
 'DDR7_SA_DQ11': CDS_PINID='DDR7_SA_DQ11';
NODE_NAME     J15 165
 '@S9S_MB_2U_LIB.S9S_MB_2U(SCH_1):PAGE96_I48@PURE_QUANTA.SCONN288_ADR50017P130CC(CHIPS)':
 'DQ11_A': CDS_PINID='DQ11_A';
NODE_NAME     J16 165
 '@S9S_MB_2U_LIB.S9S_MB_2U(SCH_1):PAGE97_I6@PURE_QUANTA.SCONN288_ADR50017P087CC(CHIPS)':
 'DQ11_A': CDS_PINID='DQ11_A';
NET_NAME
'M_H_CPU0_SA_DQ<12>'
 '@S9S_MB_2U_LIB.S9S_MB_2U(SCH_1):M_H_CPU0_SA_DQ'<12>:
 C_SIGNAL='@s9s_mb_2u_lib.s9s_mb_2u(sch_1):m_h_cpu0_sa_dq(12)';
NODE_NAME     U2 DC72
 '@S9S_MB_2U_LIB.S9S_MB_2U(SCH_1):PAGE27_I169@PURE_QUANTA.SOCKET4677_AZIF0045P001C01CS(CHIPS)':
 'DDR7_SA_DQ12': CDS_PINID='DDR7_SA_DQ12';
NODE_NAME     J15 25
 '@S9S_MB_2U_LIB.S9S_MB_2U(SCH_1):PAGE96_I48@PURE_QUANTA.SCONN288_ADR50017P130CC(CHIPS)':
 'DQ12_A': CDS_PINID='DQ12_A';
NODE_NAME     J16 25
 '@S9S_MB_2U_LIB.S9S_MB_2U(SCH_1):PAGE97_I6@PURE_QUANTA.SCONN288_ADR50017P087CC(CHIPS)':
 'DQ12_A': CDS_PINID='DQ12_A';
NET_NAME
'M_H_CPU0_SA_DQ<13>'
 '@S9S_MB_2U_LIB.S9S_MB_2U(SCH_1):M_H_CPU0_SA_DQ'<13>:
 C_SIGNAL='@s9s_mb_2u_lib.s9s_mb_2u(sch_1):m_h_cpu0_sa_dq(13)';
NODE_NAME     U2 DD71
 '@S9S_MB_2U_LIB.S9S_MB_2U(SCH_1):PAGE27_I169@PURE_QUANTA.SOCKET4677_AZIF0045P001C01CS(CHIPS)':
 'DDR7_SA_DQ13': CDS_PINID='DDR7_SA_DQ13';
NODE_NAME     J15 27
 '@S9S_MB_2U_LIB.S9S_MB_2U(SCH_1):PAGE96_I48@PURE_QUANTA.SCONN288_ADR50017P130CC(CHIPS)':
 'DQ13_A': CDS_PINID='DQ13_A';
NODE_NAME     J16 27
 '@S9S_MB_2U_LIB.S9S_MB_2U(SCH_1):PAGE97_I6@PURE_QUANTA.SCONN288_ADR50017P087CC(CHIPS)':
 'DQ13_A': CDS_PINID='DQ13_A';
NET_NAME
'M_H_CPU0_SA_DQ<14>'
 '@S9S_MB_2U_LIB.S9S_MB_2U(SCH_1):M_H_CPU0_SA_DQ'<14>:
 C_SIGNAL='@s9s_mb_2u_lib.s9s_mb_2u(sch_1):m_h_cpu0_sa_dq(14)';
NODE_NAME     U2 DG72
 '@S9S_MB_2U_LIB.S9S_MB_2U(SCH_1):PAGE27_I169@PURE_QUANTA.SOCKET4677_AZIF0045P001C01CS(CHIPS)':
 'DDR7_SA_DQ14': CDS_PINID='DDR7_SA_DQ14';
NODE_NAME     J15 170
 '@S9S_MB_2U_LIB.S9S_MB_2U(SCH_1):PAGE96_I48@PURE_QUANTA.SCONN288_ADR50017P130CC(CHIPS)':
 'DQ14_A': CDS_PINID='DQ14_A';
NODE_NAME     J16 170
 '@S9S_MB_2U_LIB.S9S_MB_2U(SCH_1):PAGE97_I6@PURE_QUANTA.SCONN288_ADR50017P087CC(CHIPS)':
 'DQ14_A': CDS_PINID='DQ14_A';
NET_NAME
'M_H_CPU0_SA_DQ<15>'
 '@S9S_MB_2U_LIB.S9S_MB_2U(SCH_1):M_H_CPU0_SA_DQ'<15>:
 C_SIGNAL='@s9s_mb_2u_lib.s9s_mb_2u(sch_1):m_h_cpu0_sa_dq(15)';
NODE_NAME     U2 DF71
 '@S9S_MB_2U_LIB.S9S_MB_2U(SCH_1):PAGE27_I169@PURE_QUANTA.SOCKET4677_AZIF0045P001C01CS(CHIPS)':
 'DDR7_SA_DQ15': CDS_PINID='DDR7_SA_DQ15';
NODE_NAME     J15 172
 '@S9S_MB_2U_LIB.S9S_MB_2U(SCH_1):PAGE96_I48@PURE_QUANTA.SCONN288_ADR50017P130CC(CHIPS)':
 'DQ15_A': CDS_PINID='DQ15_A';
NODE_NAME     J16 172
 '@S9S_MB_2U_LIB.S9S_MB_2U(SCH_1):PAGE97_I6@PURE_QUANTA.SCONN288_ADR50017P087CC(CHIPS)':
 'DQ15_A': CDS_PINID='DQ15_A';
NET_NAME
'M_H_CPU0_SA_DQ<16>'
 '@S9S_MB_2U_LIB.S9S_MB_2U(SCH_1):M_H_CPU0_SA_DQ'<16>:
 C_SIGNAL='@s9s_mb_2u_lib.s9s_mb_2u(sch_1):m_h_cpu0_sa_dq(16)';
NODE_NAME     U2 DD69
 '@S9S_MB_2U_LIB.S9S_MB_2U(SCH_1):PAGE27_I169@PURE_QUANTA.SOCKET4677_AZIF0045P001C01CS(CHIPS)':
 'DDR7_SA_DQ16': CDS_PINID='DDR7_SA_DQ16';
NODE_NAME     J15 29
 '@S9S_MB_2U_LIB.S9S_MB_2U(SCH_1):PAGE96_I48@PURE_QUANTA.SCONN288_ADR50017P130CC(CHIPS)':
 'DQ16_A': CDS_PINID='DQ16_A';
NODE_NAME     J16 29
 '@S9S_MB_2U_LIB.S9S_MB_2U(SCH_1):PAGE97_I6@PURE_QUANTA.SCONN288_ADR50017P087CC(CHIPS)':
 'DQ16_A': CDS_PINID='DQ16_A';
NET_NAME
'M_H_CPU0_SA_DQ<17>'
 '@S9S_MB_2U_LIB.S9S_MB_2U(SCH_1):M_H_CPU0_SA_DQ'<17>:
 C_SIGNAL='@s9s_mb_2u_lib.s9s_mb_2u(sch_1):m_h_cpu0_sa_dq(17)';
NODE_NAME     U2 DC68
 '@S9S_MB_2U_LIB.S9S_MB_2U(SCH_1):PAGE27_I169@PURE_QUANTA.SOCKET4677_AZIF0045P001C01CS(CHIPS)':
 'DDR7_SA_DQ17': CDS_PINID='DDR7_SA_DQ17';
NODE_NAME     J15 31
 '@S9S_MB_2U_LIB.S9S_MB_2U(SCH_1):PAGE96_I48@PURE_QUANTA.SCONN288_ADR50017P130CC(CHIPS)':
 'DQ17_A': CDS_PINID='DQ17_A';
NODE_NAME     J16 31
 '@S9S_MB_2U_LIB.S9S_MB_2U(SCH_1):PAGE97_I6@PURE_QUANTA.SCONN288_ADR50017P087CC(CHIPS)':
 'DQ17_A': CDS_PINID='DQ17_A';
NET_NAME
'M_H_CPU0_SA_DQ<18>'
 '@S9S_MB_2U_LIB.S9S_MB_2U(SCH_1):M_H_CPU0_SA_DQ'<18>:
 C_SIGNAL='@s9s_mb_2u_lib.s9s_mb_2u(sch_1):m_h_cpu0_sa_dq(18)';
NODE_NAME     U2 DF69
 '@S9S_MB_2U_LIB.S9S_MB_2U(SCH_1):PAGE27_I169@PURE_QUANTA.SOCKET4677_AZIF0045P001C01CS(CHIPS)':
 'DDR7_SA_DQ18': CDS_PINID='DDR7_SA_DQ18';
NODE_NAME     J15 174
 '@S9S_MB_2U_LIB.S9S_MB_2U(SCH_1):PAGE96_I48@PURE_QUANTA.SCONN288_ADR50017P130CC(CHIPS)':
 'DQ18_A': CDS_PINID='DQ18_A';
NODE_NAME     J16 174
 '@S9S_MB_2U_LIB.S9S_MB_2U(SCH_1):PAGE97_I6@PURE_QUANTA.SCONN288_ADR50017P087CC(CHIPS)':
 'DQ18_A': CDS_PINID='DQ18_A';
NET_NAME
'M_H_CPU0_SA_DQ<19>'
 '@S9S_MB_2U_LIB.S9S_MB_2U(SCH_1):M_H_CPU0_SA_DQ'<19>:
 C_SIGNAL='@s9s_mb_2u_lib.s9s_mb_2u(sch_1):m_h_cpu0_sa_dq(19)';
NODE_NAME     U2 DG68
 '@S9S_MB_2U_LIB.S9S_MB_2U(SCH_1):PAGE27_I169@PURE_QUANTA.SOCKET4677_AZIF0045P001C01CS(CHIPS)':
 'DDR7_SA_DQ19': CDS_PINID='DDR7_SA_DQ19';
NODE_NAME     J15 176
 '@S9S_MB_2U_LIB.S9S_MB_2U(SCH_1):PAGE96_I48@PURE_QUANTA.SCONN288_ADR50017P130CC(CHIPS)':
 'DQ19_A': CDS_PINID='DQ19_A';
NODE_NAME     J16 176
 '@S9S_MB_2U_LIB.S9S_MB_2U(SCH_1):PAGE97_I6@PURE_QUANTA.SCONN288_ADR50017P087CC(CHIPS)':
 'DQ19_A': CDS_PINID='DQ19_A';
NET_NAME
'M_H_CPU0_SA_DQ<1>'
 '@S9S_MB_2U_LIB.S9S_MB_2U(SCH_1):M_H_CPU0_SA_DQ'<1>:
 C_SIGNAL='@s9s_mb_2u_lib.s9s_mb_2u(sch_1):m_h_cpu0_sa_dq(1)';
NODE_NAME     U2 DT77
 '@S9S_MB_2U_LIB.S9S_MB_2U(SCH_1):PAGE27_I169@PURE_QUANTA.SOCKET4677_AZIF0045P001C01CS(CHIPS)':
 'DDR7_SA_DQ1': CDS_PINID='DDR7_SA_DQ1';
NODE_NAME     J15 9
 '@S9S_MB_2U_LIB.S9S_MB_2U(SCH_1):PAGE96_I48@PURE_QUANTA.SCONN288_ADR50017P130CC(CHIPS)':
 'DQ1_A': CDS_PINID='DQ1_A';
NODE_NAME     J16 9
 '@S9S_MB_2U_LIB.S9S_MB_2U(SCH_1):PAGE97_I6@PURE_QUANTA.SCONN288_ADR50017P087CC(CHIPS)':
 'DQ1_A': CDS_PINID='DQ1_A';
NET_NAME
'M_H_CPU0_SA_DQ<20>'
 '@S9S_MB_2U_LIB.S9S_MB_2U(SCH_1):M_H_CPU0_SA_DQ'<20>:
 C_SIGNAL='@s9s_mb_2u_lib.s9s_mb_2u(sch_1):m_h_cpu0_sa_dq(20)';
NODE_NAME     U2 DC66
 '@S9S_MB_2U_LIB.S9S_MB_2U(SCH_1):PAGE27_I169@PURE_QUANTA.SOCKET4677_AZIF0045P001C01CS(CHIPS)':
 'DDR7_SA_DQ20': CDS_PINID='DDR7_SA_DQ20';
NODE_NAME     J15 36
 '@S9S_MB_2U_LIB.S9S_MB_2U(SCH_1):PAGE96_I48@PURE_QUANTA.SCONN288_ADR50017P130CC(CHIPS)':
 'DQ20_A': CDS_PINID='DQ20_A';
NODE_NAME     J16 36
 '@S9S_MB_2U_LIB.S9S_MB_2U(SCH_1):PAGE97_I6@PURE_QUANTA.SCONN288_ADR50017P087CC(CHIPS)':
 'DQ20_A': CDS_PINID='DQ20_A';
NET_NAME
'M_H_CPU0_SA_DQ<21>'
 '@S9S_MB_2U_LIB.S9S_MB_2U(SCH_1):M_H_CPU0_SA_DQ'<21>:
 C_SIGNAL='@s9s_mb_2u_lib.s9s_mb_2u(sch_1):m_h_cpu0_sa_dq(21)';
NODE_NAME     U2 DD65
 '@S9S_MB_2U_LIB.S9S_MB_2U(SCH_1):PAGE27_I169@PURE_QUANTA.SOCKET4677_AZIF0045P001C01CS(CHIPS)':
 'DDR7_SA_DQ21': CDS_PINID='DDR7_SA_DQ21';
NODE_NAME     J15 38
 '@S9S_MB_2U_LIB.S9S_MB_2U(SCH_1):PAGE96_I48@PURE_QUANTA.SCONN288_ADR50017P130CC(CHIPS)':
 'DQ21_A': CDS_PINID='DQ21_A';
NODE_NAME     J16 38
 '@S9S_MB_2U_LIB.S9S_MB_2U(SCH_1):PAGE97_I6@PURE_QUANTA.SCONN288_ADR50017P087CC(CHIPS)':
 'DQ21_A': CDS_PINID='DQ21_A';
NET_NAME
'M_H_CPU0_SA_DQ<22>'
 '@S9S_MB_2U_LIB.S9S_MB_2U(SCH_1):M_H_CPU0_SA_DQ'<22>:
 C_SIGNAL='@s9s_mb_2u_lib.s9s_mb_2u(sch_1):m_h_cpu0_sa_dq(22)';
NODE_NAME     U2 DG66
 '@S9S_MB_2U_LIB.S9S_MB_2U(SCH_1):PAGE27_I169@PURE_QUANTA.SOCKET4677_AZIF0045P001C01CS(CHIPS)':
 'DDR7_SA_DQ22': CDS_PINID='DDR7_SA_DQ22';
NODE_NAME     J15 181
 '@S9S_MB_2U_LIB.S9S_MB_2U(SCH_1):PAGE96_I48@PURE_QUANTA.SCONN288_ADR50017P130CC(CHIPS)':
 'DQ22_A': CDS_PINID='DQ22_A';
NODE_NAME     J16 181
 '@S9S_MB_2U_LIB.S9S_MB_2U(SCH_1):PAGE97_I6@PURE_QUANTA.SCONN288_ADR50017P087CC(CHIPS)':
 'DQ22_A': CDS_PINID='DQ22_A';
NET_NAME
'M_H_CPU0_SA_DQ<23>'
 '@S9S_MB_2U_LIB.S9S_MB_2U(SCH_1):M_H_CPU0_SA_DQ'<23>:
 C_SIGNAL='@s9s_mb_2u_lib.s9s_mb_2u(sch_1):m_h_cpu0_sa_dq(23)';
NODE_NAME     U2 DF65
 '@S9S_MB_2U_LIB.S9S_MB_2U(SCH_1):PAGE27_I169@PURE_QUANTA.SOCKET4677_AZIF0045P001C01CS(CHIPS)':
 'DDR7_SA_DQ23': CDS_PINID='DDR7_SA_DQ23';
NODE_NAME     J15 183
 '@S9S_MB_2U_LIB.S9S_MB_2U(SCH_1):PAGE96_I48@PURE_QUANTA.SCONN288_ADR50017P130CC(CHIPS)':
 'DQ23_A': CDS_PINID='DQ23_A';
NODE_NAME     J16 183
 '@S9S_MB_2U_LIB.S9S_MB_2U(SCH_1):PAGE97_I6@PURE_QUANTA.SCONN288_ADR50017P087CC(CHIPS)':
 'DQ23_A': CDS_PINID='DQ23_A';
NET_NAME
'M_H_CPU0_SA_DQ<24>'
 '@S9S_MB_2U_LIB.S9S_MB_2U(SCH_1):M_H_CPU0_SA_DQ'<24>:
 C_SIGNAL='@s9s_mb_2u_lib.s9s_mb_2u(sch_1):m_h_cpu0_sa_dq(24)';
NODE_NAME     U2 DD63
 '@S9S_MB_2U_LIB.S9S_MB_2U(SCH_1):PAGE27_I169@PURE_QUANTA.SOCKET4677_AZIF0045P001C01CS(CHIPS)':
 'DDR7_SA_DQ24': CDS_PINID='DDR7_SA_DQ24';
NODE_NAME     J15 40
 '@S9S_MB_2U_LIB.S9S_MB_2U(SCH_1):PAGE96_I48@PURE_QUANTA.SCONN288_ADR50017P130CC(CHIPS)':
 'DQ24_A': CDS_PINID='DQ24_A';
NODE_NAME     J16 40
 '@S9S_MB_2U_LIB.S9S_MB_2U(SCH_1):PAGE97_I6@PURE_QUANTA.SCONN288_ADR50017P087CC(CHIPS)':
 'DQ24_A': CDS_PINID='DQ24_A';
NET_NAME
'M_H_CPU0_SA_DQ<25>'
 '@S9S_MB_2U_LIB.S9S_MB_2U(SCH_1):M_H_CPU0_SA_DQ'<25>:
 C_SIGNAL='@s9s_mb_2u_lib.s9s_mb_2u(sch_1):m_h_cpu0_sa_dq(25)';
NODE_NAME     U2 DC62
 '@S9S_MB_2U_LIB.S9S_MB_2U(SCH_1):PAGE27_I169@PURE_QUANTA.SOCKET4677_AZIF0045P001C01CS(CHIPS)':
 'DDR7_SA_DQ25': CDS_PINID='DDR7_SA_DQ25';
NODE_NAME     J15 42
 '@S9S_MB_2U_LIB.S9S_MB_2U(SCH_1):PAGE96_I48@PURE_QUANTA.SCONN288_ADR50017P130CC(CHIPS)':
 'DQ25_A': CDS_PINID='DQ25_A';
NODE_NAME     J16 42
 '@S9S_MB_2U_LIB.S9S_MB_2U(SCH_1):PAGE97_I6@PURE_QUANTA.SCONN288_ADR50017P087CC(CHIPS)':
 'DQ25_A': CDS_PINID='DQ25_A';
NET_NAME
'M_H_CPU0_SA_DQ<26>'
 '@S9S_MB_2U_LIB.S9S_MB_2U(SCH_1):M_H_CPU0_SA_DQ'<26>:
 C_SIGNAL='@s9s_mb_2u_lib.s9s_mb_2u(sch_1):m_h_cpu0_sa_dq(26)';
NODE_NAME     U2 DF63
 '@S9S_MB_2U_LIB.S9S_MB_2U(SCH_1):PAGE27_I169@PURE_QUANTA.SOCKET4677_AZIF0045P001C01CS(CHIPS)':
 'DDR7_SA_DQ26': CDS_PINID='DDR7_SA_DQ26';
NODE_NAME     J15 185
 '@S9S_MB_2U_LIB.S9S_MB_2U(SCH_1):PAGE96_I48@PURE_QUANTA.SCONN288_ADR50017P130CC(CHIPS)':
 'DQ26_A': CDS_PINID='DQ26_A';
NODE_NAME     J16 185
 '@S9S_MB_2U_LIB.S9S_MB_2U(SCH_1):PAGE97_I6@PURE_QUANTA.SCONN288_ADR50017P087CC(CHIPS)':
 'DQ26_A': CDS_PINID='DQ26_A';
NET_NAME
'M_H_CPU0_SA_DQ<27>'
 '@S9S_MB_2U_LIB.S9S_MB_2U(SCH_1):M_H_CPU0_SA_DQ'<27>:
 C_SIGNAL='@s9s_mb_2u_lib.s9s_mb_2u(sch_1):m_h_cpu0_sa_dq(27)';
NODE_NAME     U2 DG62
 '@S9S_MB_2U_LIB.S9S_MB_2U(SCH_1):PAGE27_I169@PURE_QUANTA.SOCKET4677_AZIF0045P001C01CS(CHIPS)':
 'DDR7_SA_DQ27': CDS_PINID='DDR7_SA_DQ27';
NODE_NAME     J15 187
 '@S9S_MB_2U_LIB.S9S_MB_2U(SCH_1):PAGE96_I48@PURE_QUANTA.SCONN288_ADR50017P130CC(CHIPS)':
 'DQ27_A': CDS_PINID='DQ27_A';
NODE_NAME     J16 187
 '@S9S_MB_2U_LIB.S9S_MB_2U(SCH_1):PAGE97_I6@PURE_QUANTA.SCONN288_ADR50017P087CC(CHIPS)':
 'DQ27_A': CDS_PINID='DQ27_A';
NET_NAME
'M_H_CPU0_SA_DQ<28>'
 '@S9S_MB_2U_LIB.S9S_MB_2U(SCH_1):M_H_CPU0_SA_DQ'<28>:
 C_SIGNAL='@s9s_mb_2u_lib.s9s_mb_2u(sch_1):m_h_cpu0_sa_dq(28)';
NODE_NAME     U2 DC60
 '@S9S_MB_2U_LIB.S9S_MB_2U(SCH_1):PAGE27_I169@PURE_QUANTA.SOCKET4677_AZIF0045P001C01CS(CHIPS)':
 'DDR7_SA_DQ28': CDS_PINID='DDR7_SA_DQ28';
NODE_NAME     J15 47
 '@S9S_MB_2U_LIB.S9S_MB_2U(SCH_1):PAGE96_I48@PURE_QUANTA.SCONN288_ADR50017P130CC(CHIPS)':
 'DQ28_A': CDS_PINID='DQ28_A';
NODE_NAME     J16 47
 '@S9S_MB_2U_LIB.S9S_MB_2U(SCH_1):PAGE97_I6@PURE_QUANTA.SCONN288_ADR50017P087CC(CHIPS)':
 'DQ28_A': CDS_PINID='DQ28_A';
NET_NAME
'M_H_CPU0_SA_DQ<29>'
 '@S9S_MB_2U_LIB.S9S_MB_2U(SCH_1):M_H_CPU0_SA_DQ'<29>:
 C_SIGNAL='@s9s_mb_2u_lib.s9s_mb_2u(sch_1):m_h_cpu0_sa_dq(29)';
NODE_NAME     U2 DD59
 '@S9S_MB_2U_LIB.S9S_MB_2U(SCH_1):PAGE27_I169@PURE_QUANTA.SOCKET4677_AZIF0045P001C01CS(CHIPS)':
 'DDR7_SA_DQ29': CDS_PINID='DDR7_SA_DQ29';
NODE_NAME     J15 49
 '@S9S_MB_2U_LIB.S9S_MB_2U(SCH_1):PAGE96_I48@PURE_QUANTA.SCONN288_ADR50017P130CC(CHIPS)':
 'DQ29_A': CDS_PINID='DQ29_A';
NODE_NAME     J16 49
 '@S9S_MB_2U_LIB.S9S_MB_2U(SCH_1):PAGE97_I6@PURE_QUANTA.SCONN288_ADR50017P087CC(CHIPS)':
 'DQ29_A': CDS_PINID='DQ29_A';
NET_NAME
'M_H_CPU0_SA_DQ<2>'
 '@S9S_MB_2U_LIB.S9S_MB_2U(SCH_1):M_H_CPU0_SA_DQ'<2>:
 C_SIGNAL='@s9s_mb_2u_lib.s9s_mb_2u(sch_1):m_h_cpu0_sa_dq(2)';
NODE_NAME     U2 DW78
 '@S9S_MB_2U_LIB.S9S_MB_2U(SCH_1):PAGE27_I169@PURE_QUANTA.SOCKET4677_AZIF0045P001C01CS(CHIPS)':
 'DDR7_SA_DQ2': CDS_PINID='DDR7_SA_DQ2';
NODE_NAME     J15 152
 '@S9S_MB_2U_LIB.S9S_MB_2U(SCH_1):PAGE96_I48@PURE_QUANTA.SCONN288_ADR50017P130CC(CHIPS)':
 'DQ2_A': CDS_PINID='DQ2_A';
NODE_NAME     J16 152
 '@S9S_MB_2U_LIB.S9S_MB_2U(SCH_1):PAGE97_I6@PURE_QUANTA.SCONN288_ADR50017P087CC(CHIPS)':
 'DQ2_A': CDS_PINID='DQ2_A';
NET_NAME
'M_H_CPU0_SA_DQ<30>'
 '@S9S_MB_2U_LIB.S9S_MB_2U(SCH_1):M_H_CPU0_SA_DQ'<30>:
 C_SIGNAL='@s9s_mb_2u_lib.s9s_mb_2u(sch_1):m_h_cpu0_sa_dq(30)';
NODE_NAME     U2 DG60
 '@S9S_MB_2U_LIB.S9S_MB_2U(SCH_1):PAGE27_I169@PURE_QUANTA.SOCKET4677_AZIF0045P001C01CS(CHIPS)':
 'DDR7_SA_DQ30': CDS_PINID='DDR7_SA_DQ30';
NODE_NAME     J15 192
 '@S9S_MB_2U_LIB.S9S_MB_2U(SCH_1):PAGE96_I48@PURE_QUANTA.SCONN288_ADR50017P130CC(CHIPS)':
 'DQ30_A': CDS_PINID='DQ30_A';
NODE_NAME     J16 192
 '@S9S_MB_2U_LIB.S9S_MB_2U(SCH_1):PAGE97_I6@PURE_QUANTA.SCONN288_ADR50017P087CC(CHIPS)':
 'DQ30_A': CDS_PINID='DQ30_A';
NET_NAME
'M_H_CPU0_SA_DQ<31>'
 '@S9S_MB_2U_LIB.S9S_MB_2U(SCH_1):M_H_CPU0_SA_DQ'<31>:
 C_SIGNAL='@s9s_mb_2u_lib.s9s_mb_2u(sch_1):m_h_cpu0_sa_dq(31)';
NODE_NAME     U2 DF59
 '@S9S_MB_2U_LIB.S9S_MB_2U(SCH_1):PAGE27_I169@PURE_QUANTA.SOCKET4677_AZIF0045P001C01CS(CHIPS)':
 'DDR7_SA_DQ31': CDS_PINID='DDR7_SA_DQ31';
NODE_NAME     J15 194
 '@S9S_MB_2U_LIB.S9S_MB_2U(SCH_1):PAGE96_I48@PURE_QUANTA.SCONN288_ADR50017P130CC(CHIPS)':
 'DQ31_A': CDS_PINID='DQ31_A';
NODE_NAME     J16 194
 '@S9S_MB_2U_LIB.S9S_MB_2U(SCH_1):PAGE97_I6@PURE_QUANTA.SCONN288_ADR50017P087CC(CHIPS)':
 'DQ31_A': CDS_PINID='DQ31_A';
NET_NAME
'M_H_CPU0_SA_DQ<3>'
 '@S9S_MB_2U_LIB.S9S_MB_2U(SCH_1):M_H_CPU0_SA_DQ'<3>:
 C_SIGNAL='@s9s_mb_2u_lib.s9s_mb_2u(sch_1):m_h_cpu0_sa_dq(3)';
NODE_NAME     U2 DP77
 '@S9S_MB_2U_LIB.S9S_MB_2U(SCH_1):PAGE27_I169@PURE_QUANTA.SOCKET4677_AZIF0045P001C01CS(CHIPS)':
 'DDR7_SA_DQ3': CDS_PINID='DDR7_SA_DQ3';
NODE_NAME     J15 154
 '@S9S_MB_2U_LIB.S9S_MB_2U(SCH_1):PAGE96_I48@PURE_QUANTA.SCONN288_ADR50017P130CC(CHIPS)':
 'DQ3_A': CDS_PINID='DQ3_A';
NODE_NAME     J16 154
 '@S9S_MB_2U_LIB.S9S_MB_2U(SCH_1):PAGE97_I6@PURE_QUANTA.SCONN288_ADR50017P087CC(CHIPS)':
 'DQ3_A': CDS_PINID='DQ3_A';
NET_NAME
'M_H_CPU0_SA_DQ<4>'
 '@S9S_MB_2U_LIB.S9S_MB_2U(SCH_1):M_H_CPU0_SA_DQ'<4>:
 C_SIGNAL='@s9s_mb_2u_lib.s9s_mb_2u(sch_1):m_h_cpu0_sa_dq(4)';
NODE_NAME     U2 DK75
 '@S9S_MB_2U_LIB.S9S_MB_2U(SCH_1):PAGE27_I169@PURE_QUANTA.SOCKET4677_AZIF0045P001C01CS(CHIPS)':
 'DDR7_SA_DQ4': CDS_PINID='DDR7_SA_DQ4';
NODE_NAME     J15 14
 '@S9S_MB_2U_LIB.S9S_MB_2U(SCH_1):PAGE96_I48@PURE_QUANTA.SCONN288_ADR50017P130CC(CHIPS)':
 'DQ4_A': CDS_PINID='DQ4_A';
NODE_NAME     J16 14
 '@S9S_MB_2U_LIB.S9S_MB_2U(SCH_1):PAGE97_I6@PURE_QUANTA.SCONN288_ADR50017P087CC(CHIPS)':
 'DQ4_A': CDS_PINID='DQ4_A';
NET_NAME
'M_H_CPU0_SA_DQ<5>'
 '@S9S_MB_2U_LIB.S9S_MB_2U(SCH_1):M_H_CPU0_SA_DQ'<5>:
 C_SIGNAL='@s9s_mb_2u_lib.s9s_mb_2u(sch_1):m_h_cpu0_sa_dq(5)';
NODE_NAME     U2 DL74
 '@S9S_MB_2U_LIB.S9S_MB_2U(SCH_1):PAGE27_I169@PURE_QUANTA.SOCKET4677_AZIF0045P001C01CS(CHIPS)':
 'DDR7_SA_DQ5': CDS_PINID='DDR7_SA_DQ5';
NODE_NAME     J15 16
 '@S9S_MB_2U_LIB.S9S_MB_2U(SCH_1):PAGE96_I48@PURE_QUANTA.SCONN288_ADR50017P130CC(CHIPS)':
 'DQ5_A': CDS_PINID='DQ5_A';
NODE_NAME     J16 16
 '@S9S_MB_2U_LIB.S9S_MB_2U(SCH_1):PAGE97_I6@PURE_QUANTA.SCONN288_ADR50017P087CC(CHIPS)':
 'DQ5_A': CDS_PINID='DQ5_A';
NET_NAME
'M_H_CPU0_SA_DQ<6>'
 '@S9S_MB_2U_LIB.S9S_MB_2U(SCH_1):M_H_CPU0_SA_DQ'<6>:
 C_SIGNAL='@s9s_mb_2u_lib.s9s_mb_2u(sch_1):m_h_cpu0_sa_dq(6)';
NODE_NAME     U2 DP75
 '@S9S_MB_2U_LIB.S9S_MB_2U(SCH_1):PAGE27_I169@PURE_QUANTA.SOCKET4677_AZIF0045P001C01CS(CHIPS)':
 'DDR7_SA_DQ6': CDS_PINID='DDR7_SA_DQ6';
NODE_NAME     J15 159
 '@S9S_MB_2U_LIB.S9S_MB_2U(SCH_1):PAGE96_I48@PURE_QUANTA.SCONN288_ADR50017P130CC(CHIPS)':
 'DQ6_A': CDS_PINID='DQ6_A';
NODE_NAME     J16 159
 '@S9S_MB_2U_LIB.S9S_MB_2U(SCH_1):PAGE97_I6@PURE_QUANTA.SCONN288_ADR50017P087CC(CHIPS)':
 'DQ6_A': CDS_PINID='DQ6_A';
NET_NAME
'M_H_CPU0_SA_DQ<7>'
 '@S9S_MB_2U_LIB.S9S_MB_2U(SCH_1):M_H_CPU0_SA_DQ'<7>:
 C_SIGNAL='@s9s_mb_2u_lib.s9s_mb_2u(sch_1):m_h_cpu0_sa_dq(7)';
NODE_NAME     U2 DN74
 '@S9S_MB_2U_LIB.S9S_MB_2U(SCH_1):PAGE27_I169@PURE_QUANTA.SOCKET4677_AZIF0045P001C01CS(CHIPS)':
 'DDR7_SA_DQ7': CDS_PINID='DDR7_SA_DQ7';
NODE_NAME     J15 161
 '@S9S_MB_2U_LIB.S9S_MB_2U(SCH_1):PAGE96_I48@PURE_QUANTA.SCONN288_ADR50017P130CC(CHIPS)':
 'DQ7_A': CDS_PINID='DQ7_A';
NODE_NAME     J16 161
 '@S9S_MB_2U_LIB.S9S_MB_2U(SCH_1):PAGE97_I6@PURE_QUANTA.SCONN288_ADR50017P087CC(CHIPS)':
 'DQ7_A': CDS_PINID='DQ7_A';
NET_NAME
'M_H_CPU0_SA_DQ<8>'
 '@S9S_MB_2U_LIB.S9S_MB_2U(SCH_1):M_H_CPU0_SA_DQ'<8>:
 C_SIGNAL='@s9s_mb_2u_lib.s9s_mb_2u(sch_1):m_h_cpu0_sa_dq(8)';
NODE_NAME     U2 DD75
 '@S9S_MB_2U_LIB.S9S_MB_2U(SCH_1):PAGE27_I169@PURE_QUANTA.SOCKET4677_AZIF0045P001C01CS(CHIPS)':
 'DDR7_SA_DQ8': CDS_PINID='DDR7_SA_DQ8';
NODE_NAME     J15 18
 '@S9S_MB_2U_LIB.S9S_MB_2U(SCH_1):PAGE96_I48@PURE_QUANTA.SCONN288_ADR50017P130CC(CHIPS)':
 'DQ8_A': CDS_PINID='DQ8_A';
NODE_NAME     J16 18
 '@S9S_MB_2U_LIB.S9S_MB_2U(SCH_1):PAGE97_I6@PURE_QUANTA.SCONN288_ADR50017P087CC(CHIPS)':
 'DQ8_A': CDS_PINID='DQ8_A';
NET_NAME
'M_H_CPU0_SA_DQ<9>'
 '@S9S_MB_2U_LIB.S9S_MB_2U(SCH_1):M_H_CPU0_SA_DQ'<9>:
 C_SIGNAL='@s9s_mb_2u_lib.s9s_mb_2u(sch_1):m_h_cpu0_sa_dq(9)';
NODE_NAME     U2 DC74
 '@S9S_MB_2U_LIB.S9S_MB_2U(SCH_1):PAGE27_I169@PURE_QUANTA.SOCKET4677_AZIF0045P001C01CS(CHIPS)':
 'DDR7_SA_DQ9': CDS_PINID='DDR7_SA_DQ9';
NODE_NAME     J15 20
 '@S9S_MB_2U_LIB.S9S_MB_2U(SCH_1):PAGE96_I48@PURE_QUANTA.SCONN288_ADR50017P130CC(CHIPS)':
 'DQ9_A': CDS_PINID='DQ9_A';
NODE_NAME     J16 20
 '@S9S_MB_2U_LIB.S9S_MB_2U(SCH_1):PAGE97_I6@PURE_QUANTA.SCONN288_ADR50017P087CC(CHIPS)':
 'DQ9_A': CDS_PINID='DQ9_A';
NET_NAME
'M_H_CPU0_SA_DQS_DN<0>'
 '@S9S_MB_2U_LIB.S9S_MB_2U(SCH_1):M_H_CPU0_SA_DQS_DN'<0>:
 C_SIGNAL='@s9s_mb_2u_lib.s9s_mb_2u(sch_1):m_h_cpu0_sa_dqs_dn(0)';
NODE_NAME     U2 DJ76
 '@S9S_MB_2U_LIB.S9S_MB_2U(SCH_1):PAGE27_I169@PURE_QUANTA.SOCKET4677_AZIF0045P001C01CS(CHIPS)':
 'DDR7_SA_DQS_DN0': CDS_PINID='DDR7_SA_DQS_DN0';
NODE_NAME     J15 12
 '@S9S_MB_2U_LIB.S9S_MB_2U(SCH_1):PAGE96_I178@PURE_QUANTA.SCONN288_ADR50017P130CC(CHIPS)':
 'DQS0_A_C': CDS_PINID='DQS0_A_C';
NODE_NAME     J16 12
 '@S9S_MB_2U_LIB.S9S_MB_2U(SCH_1):PAGE97_I178@PURE_QUANTA.SCONN288_ADR50017P087CC(CHIPS)':
 'DQS0_A_C': CDS_PINID='DQS0_A_C';
NET_NAME
'M_H_CPU0_SA_DQS_DN<1>'
 '@S9S_MB_2U_LIB.S9S_MB_2U(SCH_1):M_H_CPU0_SA_DQS_DN'<1>:
 C_SIGNAL='@s9s_mb_2u_lib.s9s_mb_2u(sch_1):m_h_cpu0_sa_dqs_dn(1)';
NODE_NAME     U2 DB73
 '@S9S_MB_2U_LIB.S9S_MB_2U(SCH_1):PAGE27_I169@PURE_QUANTA.SOCKET4677_AZIF0045P001C01CS(CHIPS)':
 'DDR7_SA_DQS_DN1': CDS_PINID='DDR7_SA_DQS_DN1';
NODE_NAME     J15 23
 '@S9S_MB_2U_LIB.S9S_MB_2U(SCH_1):PAGE96_I178@PURE_QUANTA.SCONN288_ADR50017P130CC(CHIPS)':
 'DQS1_A_C': CDS_PINID='DQS1_A_C';
NODE_NAME     J16 23
 '@S9S_MB_2U_LIB.S9S_MB_2U(SCH_1):PAGE97_I178@PURE_QUANTA.SCONN288_ADR50017P087CC(CHIPS)':
 'DQS1_A_C': CDS_PINID='DQS1_A_C';
NET_NAME
'M_H_CPU0_SA_DQS_DN<2>'
 '@S9S_MB_2U_LIB.S9S_MB_2U(SCH_1):M_H_CPU0_SA_DQS_DN'<2>:
 C_SIGNAL='@s9s_mb_2u_lib.s9s_mb_2u(sch_1):m_h_cpu0_sa_dqs_dn(2)';
NODE_NAME     U2 DD67
 '@S9S_MB_2U_LIB.S9S_MB_2U(SCH_1):PAGE27_I169@PURE_QUANTA.SOCKET4677_AZIF0045P001C01CS(CHIPS)':
 'DDR7_SA_DQS_DN2': CDS_PINID='DDR7_SA_DQS_DN2';
NODE_NAME     J15 34
 '@S9S_MB_2U_LIB.S9S_MB_2U(SCH_1):PAGE96_I178@PURE_QUANTA.SCONN288_ADR50017P130CC(CHIPS)':
 'DQS2_A_C': CDS_PINID='DQS2_A_C';
NODE_NAME     J16 34
 '@S9S_MB_2U_LIB.S9S_MB_2U(SCH_1):PAGE97_I178@PURE_QUANTA.SCONN288_ADR50017P087CC(CHIPS)':
 'DQS2_A_C': CDS_PINID='DQS2_A_C';
NET_NAME
'M_H_CPU0_SA_DQS_DN<3>'
 '@S9S_MB_2U_LIB.S9S_MB_2U(SCH_1):M_H_CPU0_SA_DQS_DN'<3>:
 C_SIGNAL='@s9s_mb_2u_lib.s9s_mb_2u(sch_1):m_h_cpu0_sa_dqs_dn(3)';
NODE_NAME     U2 DD61
 '@S9S_MB_2U_LIB.S9S_MB_2U(SCH_1):PAGE27_I169@PURE_QUANTA.SOCKET4677_AZIF0045P001C01CS(CHIPS)':
 'DDR7_SA_DQS_DN3': CDS_PINID='DDR7_SA_DQS_DN3';
NODE_NAME     J15 45
 '@S9S_MB_2U_LIB.S9S_MB_2U(SCH_1):PAGE96_I178@PURE_QUANTA.SCONN288_ADR50017P130CC(CHIPS)':
 'DQS3_A_C': CDS_PINID='DQS3_A_C';
NODE_NAME     J16 45
 '@S9S_MB_2U_LIB.S9S_MB_2U(SCH_1):PAGE97_I178@PURE_QUANTA.SCONN288_ADR50017P087CC(CHIPS)':
 'DQS3_A_C': CDS_PINID='DQS3_A_C';
NET_NAME
'M_H_CPU0_SA_DQS_DN<4>'
 '@S9S_MB_2U_LIB.S9S_MB_2U(SCH_1):M_H_CPU0_SA_DQS_DN'<4>:
 C_SIGNAL='@s9s_mb_2u_lib.s9s_mb_2u(sch_1):m_h_cpu0_sa_dqs_dn(4)';
NODE_NAME     U2 DD55
 '@S9S_MB_2U_LIB.S9S_MB_2U(SCH_1):PAGE27_I169@PURE_QUANTA.SOCKET4677_AZIF0045P001C01CS(CHIPS)':
 'DDR7_SA_DQS_DN4': CDS_PINID='DDR7_SA_DQS_DN4';
NODE_NAME     J15 56
 '@S9S_MB_2U_LIB.S9S_MB_2U(SCH_1):PAGE96_I178@PURE_QUANTA.SCONN288_ADR50017P130CC(CHIPS)':
 'DQS4_A_C': CDS_PINID='DQS4_A_C';
NODE_NAME     J16 56
 '@S9S_MB_2U_LIB.S9S_MB_2U(SCH_1):PAGE97_I178@PURE_QUANTA.SCONN288_ADR50017P087CC(CHIPS)':
 'DQS4_A_C': CDS_PINID='DQS4_A_C';
NET_NAME
'M_H_CPU0_SA_DQS_DN<5>'
 '@S9S_MB_2U_LIB.S9S_MB_2U(SCH_1):M_H_CPU0_SA_DQS_DN'<5>:
 C_SIGNAL='@s9s_mb_2u_lib.s9s_mb_2u(sch_1):m_h_cpu0_sa_dqs_dn(5)';
NODE_NAME     U2 DR76
 '@S9S_MB_2U_LIB.S9S_MB_2U(SCH_1):PAGE27_I169@PURE_QUANTA.SOCKET4677_AZIF0045P001C01CS(CHIPS)':
 'DDR7_SA_DQS_DN5': CDS_PINID='DDR7_SA_DQS_DN5';
NODE_NAME     J15 156
 '@S9S_MB_2U_LIB.S9S_MB_2U(SCH_1):PAGE96_I178@PURE_QUANTA.SCONN288_ADR50017P130CC(CHIPS)':
 'DQS5_A_C||TDQS5_A_C||DQS5_A_T||TDQS5_A_T': CDS_PINID='\dqs5_a_c||tdqs5_a_c||dqs5_a_t||tdqs5_a_t\';
NODE_NAME     J16 156
 '@S9S_MB_2U_LIB.S9S_MB_2U(SCH_1):PAGE97_I178@PURE_QUANTA.SCONN288_ADR50017P087CC(CHIPS)':
 'DQS5_A_C||TDQS5_A_C||DQS5_A_T||TDQS5_A_T': CDS_PINID='\dqs5_a_c||tdqs5_a_c||dqs5_a_t||tdqs5_a_t\';
NET_NAME
'M_H_CPU0_SA_DQS_DN<6>'
 '@S9S_MB_2U_LIB.S9S_MB_2U(SCH_1):M_H_CPU0_SA_DQS_DN'<6>:
 C_SIGNAL='@s9s_mb_2u_lib.s9s_mb_2u(sch_1):m_h_cpu0_sa_dqs_dn(6)';
NODE_NAME     U2 DH73
 '@S9S_MB_2U_LIB.S9S_MB_2U(SCH_1):PAGE27_I169@PURE_QUANTA.SOCKET4677_AZIF0045P001C01CS(CHIPS)':
 'DDR7_SA_DQS_DN6': CDS_PINID='DDR7_SA_DQS_DN6';
NODE_NAME     J15 167
 '@S9S_MB_2U_LIB.S9S_MB_2U(SCH_1):PAGE96_I178@PURE_QUANTA.SCONN288_ADR50017P130CC(CHIPS)':
 'DQS6_A_C||TDQS6_A_C||DQS6_A_T||TDQS6_A_T': CDS_PINID='\dqs6_a_c||tdqs6_a_c||dqs6_a_t||tdqs6_a_t\';
NODE_NAME     J16 167
 '@S9S_MB_2U_LIB.S9S_MB_2U(SCH_1):PAGE97_I178@PURE_QUANTA.SCONN288_ADR50017P087CC(CHIPS)':
 'DQS6_A_C||TDQS6_A_C||DQS6_A_T||TDQS6_A_T': CDS_PINID='\dqs6_a_c||tdqs6_a_c||dqs6_a_t||tdqs6_a_t\';
NET_NAME
'M_H_CPU0_SA_DQS_DN<7>'
 '@S9S_MB_2U_LIB.S9S_MB_2U(SCH_1):M_H_CPU0_SA_DQS_DN'<7>:
 C_SIGNAL='@s9s_mb_2u_lib.s9s_mb_2u(sch_1):m_h_cpu0_sa_dqs_dn(7)';
NODE_NAME     U2 DH67
 '@S9S_MB_2U_LIB.S9S_MB_2U(SCH_1):PAGE27_I169@PURE_QUANTA.SOCKET4677_AZIF0045P001C01CS(CHIPS)':
 'DDR7_SA_DQS_DN7': CDS_PINID='DDR7_SA_DQS_DN7';
NODE_NAME     J15 178
 '@S9S_MB_2U_LIB.S9S_MB_2U(SCH_1):PAGE96_I178@PURE_QUANTA.SCONN288_ADR50017P130CC(CHIPS)':
 'DQS7_A_C||TDQS7_A_C': CDS_PINID='\dqs7_a_c||tdqs7_a_c\';
NODE_NAME     J16 178
 '@S9S_MB_2U_LIB.S9S_MB_2U(SCH_1):PAGE97_I178@PURE_QUANTA.SCONN288_ADR50017P087CC(CHIPS)':
 'DQS7_A_C||TDQS7_A_C': CDS_PINID='\dqs7_a_c||tdqs7_a_c\';
NET_NAME
'M_H_CPU0_SA_DQS_DN<8>'
 '@S9S_MB_2U_LIB.S9S_MB_2U(SCH_1):M_H_CPU0_SA_DQS_DN'<8>:
 C_SIGNAL='@s9s_mb_2u_lib.s9s_mb_2u(sch_1):m_h_cpu0_sa_dqs_dn(8)';
NODE_NAME     U2 DH61
 '@S9S_MB_2U_LIB.S9S_MB_2U(SCH_1):PAGE27_I169@PURE_QUANTA.SOCKET4677_AZIF0045P001C01CS(CHIPS)':
 'DDR7_SA_DQS_DN8': CDS_PINID='DDR7_SA_DQS_DN8';
NODE_NAME     J15 189
 '@S9S_MB_2U_LIB.S9S_MB_2U(SCH_1):PAGE96_I178@PURE_QUANTA.SCONN288_ADR50017P130CC(CHIPS)':
 'DQS8_A_C||TDQS8_A_C': CDS_PINID='\dqs8_a_c||tdqs8_a_c\';
NODE_NAME     J16 189
 '@S9S_MB_2U_LIB.S9S_MB_2U(SCH_1):PAGE97_I178@PURE_QUANTA.SCONN288_ADR50017P087CC(CHIPS)':
 'DQS8_A_C||TDQS8_A_C': CDS_PINID='\dqs8_a_c||tdqs8_a_c\';
NET_NAME
'M_H_CPU0_SA_DQS_DN<9>'
 '@S9S_MB_2U_LIB.S9S_MB_2U(SCH_1):M_H_CPU0_SA_DQS_DN'<9>:
 C_SIGNAL='@s9s_mb_2u_lib.s9s_mb_2u(sch_1):m_h_cpu0_sa_dqs_dn(9)';
NODE_NAME     U2 DH55
 '@S9S_MB_2U_LIB.S9S_MB_2U(SCH_1):PAGE27_I169@PURE_QUANTA.SOCKET4677_AZIF0045P001C01CS(CHIPS)':
 'DDR7_SA_DQS_DN9': CDS_PINID='DDR7_SA_DQS_DN9';
NODE_NAME     J15 200
 '@S9S_MB_2U_LIB.S9S_MB_2U(SCH_1):PAGE96_I178@PURE_QUANTA.SCONN288_ADR50017P130CC(CHIPS)':
 'DQS9_A_C||TDQS9_A_C': CDS_PINID='\dqs9_a_c||tdqs9_a_c\';
NODE_NAME     J16 200
 '@S9S_MB_2U_LIB.S9S_MB_2U(SCH_1):PAGE97_I178@PURE_QUANTA.SCONN288_ADR50017P087CC(CHIPS)':
 'DQS9_A_C||TDQS9_A_C': CDS_PINID='\dqs9_a_c||tdqs9_a_c\';
NET_NAME
'M_H_CPU0_SA_DQS_DP<0>'
 '@S9S_MB_2U_LIB.S9S_MB_2U(SCH_1):M_H_CPU0_SA_DQS_DP'<0>:
 C_SIGNAL='@s9s_mb_2u_lib.s9s_mb_2u(sch_1):m_h_cpu0_sa_dqs_dp(0)';
NODE_NAME     U2 DL76
 '@S9S_MB_2U_LIB.S9S_MB_2U(SCH_1):PAGE27_I169@PURE_QUANTA.SOCKET4677_AZIF0045P001C01CS(CHIPS)':
 'DDR7_SA_DQS_DP0': CDS_PINID='DDR7_SA_DQS_DP0';
NODE_NAME     J15 11
 '@S9S_MB_2U_LIB.S9S_MB_2U(SCH_1):PAGE96_I178@PURE_QUANTA.SCONN288_ADR50017P130CC(CHIPS)':
 'DQS0_A_T': CDS_PINID='DQS0_A_T';
NODE_NAME     J16 11
 '@S9S_MB_2U_LIB.S9S_MB_2U(SCH_1):PAGE97_I178@PURE_QUANTA.SCONN288_ADR50017P087CC(CHIPS)':
 'DQS0_A_T': CDS_PINID='DQS0_A_T';
NET_NAME
'M_H_CPU0_SA_DQS_DP<1>'
 '@S9S_MB_2U_LIB.S9S_MB_2U(SCH_1):M_H_CPU0_SA_DQS_DP'<1>:
 C_SIGNAL='@s9s_mb_2u_lib.s9s_mb_2u(sch_1):m_h_cpu0_sa_dqs_dp(1)';
NODE_NAME     U2 DD73
 '@S9S_MB_2U_LIB.S9S_MB_2U(SCH_1):PAGE27_I169@PURE_QUANTA.SOCKET4677_AZIF0045P001C01CS(CHIPS)':
 'DDR7_SA_DQS_DP1': CDS_PINID='DDR7_SA_DQS_DP1';
NODE_NAME     J15 22
 '@S9S_MB_2U_LIB.S9S_MB_2U(SCH_1):PAGE96_I178@PURE_QUANTA.SCONN288_ADR50017P130CC(CHIPS)':
 'DQS1_A_T': CDS_PINID='DQS1_A_T';
NODE_NAME     J16 22
 '@S9S_MB_2U_LIB.S9S_MB_2U(SCH_1):PAGE97_I178@PURE_QUANTA.SCONN288_ADR50017P087CC(CHIPS)':
 'DQS1_A_T': CDS_PINID='DQS1_A_T';
NET_NAME
'M_H_CPU0_SA_DQS_DP<2>'
 '@S9S_MB_2U_LIB.S9S_MB_2U(SCH_1):M_H_CPU0_SA_DQS_DP'<2>:
 C_SIGNAL='@s9s_mb_2u_lib.s9s_mb_2u(sch_1):m_h_cpu0_sa_dqs_dp(2)';
NODE_NAME     U2 DB67
 '@S9S_MB_2U_LIB.S9S_MB_2U(SCH_1):PAGE27_I169@PURE_QUANTA.SOCKET4677_AZIF0045P001C01CS(CHIPS)':
 'DDR7_SA_DQS_DP2': CDS_PINID='DDR7_SA_DQS_DP2';
NODE_NAME     J15 33
 '@S9S_MB_2U_LIB.S9S_MB_2U(SCH_1):PAGE96_I178@PURE_QUANTA.SCONN288_ADR50017P130CC(CHIPS)':
 'DQS2_A_T': CDS_PINID='DQS2_A_T';
NODE_NAME     J16 33
 '@S9S_MB_2U_LIB.S9S_MB_2U(SCH_1):PAGE97_I178@PURE_QUANTA.SCONN288_ADR50017P087CC(CHIPS)':
 'DQS2_A_T': CDS_PINID='DQS2_A_T';
NET_NAME
'M_H_CPU0_SA_DQS_DP<3>'
 '@S9S_MB_2U_LIB.S9S_MB_2U(SCH_1):M_H_CPU0_SA_DQS_DP'<3>:
 C_SIGNAL='@s9s_mb_2u_lib.s9s_mb_2u(sch_1):m_h_cpu0_sa_dqs_dp(3)';
NODE_NAME     U2 DB61
 '@S9S_MB_2U_LIB.S9S_MB_2U(SCH_1):PAGE27_I169@PURE_QUANTA.SOCKET4677_AZIF0045P001C01CS(CHIPS)':
 'DDR7_SA_DQS_DP3': CDS_PINID='DDR7_SA_DQS_DP3';
NODE_NAME     J15 44
 '@S9S_MB_2U_LIB.S9S_MB_2U(SCH_1):PAGE96_I178@PURE_QUANTA.SCONN288_ADR50017P130CC(CHIPS)':
 'DQS3_A_T': CDS_PINID='DQS3_A_T';
NODE_NAME     J16 44
 '@S9S_MB_2U_LIB.S9S_MB_2U(SCH_1):PAGE97_I178@PURE_QUANTA.SCONN288_ADR50017P087CC(CHIPS)':
 'DQS3_A_T': CDS_PINID='DQS3_A_T';
NET_NAME
'M_H_CPU0_SA_DQS_DP<4>'
 '@S9S_MB_2U_LIB.S9S_MB_2U(SCH_1):M_H_CPU0_SA_DQS_DP'<4>:
 C_SIGNAL='@s9s_mb_2u_lib.s9s_mb_2u(sch_1):m_h_cpu0_sa_dqs_dp(4)';
NODE_NAME     U2 DB55
 '@S9S_MB_2U_LIB.S9S_MB_2U(SCH_1):PAGE27_I169@PURE_QUANTA.SOCKET4677_AZIF0045P001C01CS(CHIPS)':
 'DDR7_SA_DQS_DP4': CDS_PINID='DDR7_SA_DQS_DP4';
NODE_NAME     J15 55
 '@S9S_MB_2U_LIB.S9S_MB_2U(SCH_1):PAGE96_I178@PURE_QUANTA.SCONN288_ADR50017P130CC(CHIPS)':
 'DQS4_A_T': CDS_PINID='DQS4_A_T';
NODE_NAME     J16 55
 '@S9S_MB_2U_LIB.S9S_MB_2U(SCH_1):PAGE97_I178@PURE_QUANTA.SCONN288_ADR50017P087CC(CHIPS)':
 'DQS4_A_T': CDS_PINID='DQS4_A_T';
NET_NAME
'M_H_CPU0_SA_DQS_DP<5>'
 '@S9S_MB_2U_LIB.S9S_MB_2U(SCH_1):M_H_CPU0_SA_DQS_DP'<5>:
 C_SIGNAL='@s9s_mb_2u_lib.s9s_mb_2u(sch_1):m_h_cpu0_sa_dqs_dp(5)';
NODE_NAME     U2 DN76
 '@S9S_MB_2U_LIB.S9S_MB_2U(SCH_1):PAGE27_I169@PURE_QUANTA.SOCKET4677_AZIF0045P001C01CS(CHIPS)':
 'DDR7_SA_DQS_DP5': CDS_PINID='DDR7_SA_DQS_DP5';
NODE_NAME     J15 157
 '@S9S_MB_2U_LIB.S9S_MB_2U(SCH_1):PAGE96_I178@PURE_QUANTA.SCONN288_ADR50017P130CC(CHIPS)':
 'DQS5_A_T||TDQS5_A_T': CDS_PINID='\dqs5_a_t||tdqs5_a_t\';
NODE_NAME     J16 157
 '@S9S_MB_2U_LIB.S9S_MB_2U(SCH_1):PAGE97_I178@PURE_QUANTA.SCONN288_ADR50017P087CC(CHIPS)':
 'DQS5_A_T||TDQS5_A_T': CDS_PINID='\dqs5_a_t||tdqs5_a_t\';
NET_NAME
'M_H_CPU0_SA_DQS_DP<6>'
 '@S9S_MB_2U_LIB.S9S_MB_2U(SCH_1):M_H_CPU0_SA_DQS_DP'<6>:
 C_SIGNAL='@s9s_mb_2u_lib.s9s_mb_2u(sch_1):m_h_cpu0_sa_dqs_dp(6)';
NODE_NAME     U2 DF73
 '@S9S_MB_2U_LIB.S9S_MB_2U(SCH_1):PAGE27_I169@PURE_QUANTA.SOCKET4677_AZIF0045P001C01CS(CHIPS)':
 'DDR7_SA_DQS_DP6': CDS_PINID='DDR7_SA_DQS_DP6';
NODE_NAME     J15 168
 '@S9S_MB_2U_LIB.S9S_MB_2U(SCH_1):PAGE96_I178@PURE_QUANTA.SCONN288_ADR50017P130CC(CHIPS)':
 'DQS6_A_T||TDQS6_A_T': CDS_PINID='\dqs6_a_t||tdqs6_a_t\';
NODE_NAME     J16 168
 '@S9S_MB_2U_LIB.S9S_MB_2U(SCH_1):PAGE97_I178@PURE_QUANTA.SCONN288_ADR50017P087CC(CHIPS)':
 'DQS6_A_T||TDQS6_A_T': CDS_PINID='\dqs6_a_t||tdqs6_a_t\';
NET_NAME
'M_H_CPU0_SA_DQS_DP<7>'
 '@S9S_MB_2U_LIB.S9S_MB_2U(SCH_1):M_H_CPU0_SA_DQS_DP'<7>:
 C_SIGNAL='@s9s_mb_2u_lib.s9s_mb_2u(sch_1):m_h_cpu0_sa_dqs_dp(7)';
NODE_NAME     U2 DF67
 '@S9S_MB_2U_LIB.S9S_MB_2U(SCH_1):PAGE27_I169@PURE_QUANTA.SOCKET4677_AZIF0045P001C01CS(CHIPS)':
 'DDR7_SA_DQS_DP7': CDS_PINID='DDR7_SA_DQS_DP7';
NODE_NAME     J15 179
 '@S9S_MB_2U_LIB.S9S_MB_2U(SCH_1):PAGE96_I178@PURE_QUANTA.SCONN288_ADR50017P130CC(CHIPS)':
 'DQS7_A_T||TDQS7_A_T': CDS_PINID='\dqs7_a_t||tdqs7_a_t\';
NODE_NAME     J16 179
 '@S9S_MB_2U_LIB.S9S_MB_2U(SCH_1):PAGE97_I178@PURE_QUANTA.SCONN288_ADR50017P087CC(CHIPS)':
 'DQS7_A_T||TDQS7_A_T': CDS_PINID='\dqs7_a_t||tdqs7_a_t\';
NET_NAME
'M_H_CPU0_SA_DQS_DP<8>'
 '@S9S_MB_2U_LIB.S9S_MB_2U(SCH_1):M_H_CPU0_SA_DQS_DP'<8>:
 C_SIGNAL='@s9s_mb_2u_lib.s9s_mb_2u(sch_1):m_h_cpu0_sa_dqs_dp(8)';
NODE_NAME     U2 DF61
 '@S9S_MB_2U_LIB.S9S_MB_2U(SCH_1):PAGE27_I169@PURE_QUANTA.SOCKET4677_AZIF0045P001C01CS(CHIPS)':
 'DDR7_SA_DQS_DP8': CDS_PINID='DDR7_SA_DQS_DP8';
NODE_NAME     J15 190
 '@S9S_MB_2U_LIB.S9S_MB_2U(SCH_1):PAGE96_I178@PURE_QUANTA.SCONN288_ADR50017P130CC(CHIPS)':
 'DQS8_A_T||TDQS8_A_T': CDS_PINID='\dqs8_a_t||tdqs8_a_t\';
NODE_NAME     J16 190
 '@S9S_MB_2U_LIB.S9S_MB_2U(SCH_1):PAGE97_I178@PURE_QUANTA.SCONN288_ADR50017P087CC(CHIPS)':
 'DQS8_A_T||TDQS8_A_T': CDS_PINID='\dqs8_a_t||tdqs8_a_t\';
NET_NAME
'M_H_CPU0_SA_DQS_DP<9>'
 '@S9S_MB_2U_LIB.S9S_MB_2U(SCH_1):M_H_CPU0_SA_DQS_DP'<9>:
 C_SIGNAL='@s9s_mb_2u_lib.s9s_mb_2u(sch_1):m_h_cpu0_sa_dqs_dp(9)';
NODE_NAME     U2 DF55
 '@S9S_MB_2U_LIB.S9S_MB_2U(SCH_1):PAGE27_I169@PURE_QUANTA.SOCKET4677_AZIF0045P001C01CS(CHIPS)':
 'DDR7_SA_DQS_DP9': CDS_PINID='DDR7_SA_DQS_DP9';
NODE_NAME     J15 201
 '@S9S_MB_2U_LIB.S9S_MB_2U(SCH_1):PAGE96_I178@PURE_QUANTA.SCONN288_ADR50017P130CC(CHIPS)':
 'DQS9_A_T||TDQS9_A_T': CDS_PINID='\dqs9_a_t||tdqs9_a_t\';
NODE_NAME     J16 201
 '@S9S_MB_2U_LIB.S9S_MB_2U(SCH_1):PAGE97_I178@PURE_QUANTA.SCONN288_ADR50017P087CC(CHIPS)':
 'DQS9_A_T||TDQS9_A_T': CDS_PINID='\dqs9_a_t||tdqs9_a_t\';
NET_NAME
'M_H_CPU0_SA_PAR'
 '@S9S_MB_2U_LIB.S9S_MB_2U(SCH_1):M_H_CPU0_SA_PAR':
 C_SIGNAL='@s9s_mb_2u_lib.s9s_mb_2u(sch_1):m_h_cpu0_sa_par';
NODE_NAME     U2 DD40
 '@S9S_MB_2U_LIB.S9S_MB_2U(SCH_1):PAGE27_I169@PURE_QUANTA.SOCKET4677_AZIF0045P001C01CS(CHIPS)':
 'DDR7_SA_PAR': CDS_PINID='DDR7_SA_PAR';
NODE_NAME     J15 74
 '@S9S_MB_2U_LIB.S9S_MB_2U(SCH_1):PAGE96_I48@PURE_QUANTA.SCONN288_ADR50017P130CC(CHIPS)':
 'PAR_A': CDS_PINID='PAR_A';
NODE_NAME     J16 74
 '@S9S_MB_2U_LIB.S9S_MB_2U(SCH_1):PAGE97_I6@PURE_QUANTA.SCONN288_ADR50017P087CC(CHIPS)':
 'PAR_A': CDS_PINID='PAR_A';
NET_NAME
'M_H_CPU0_SA_RSP<0>'
 '@S9S_MB_2U_LIB.S9S_MB_2U(SCH_1):M_H_CPU0_SA_RSP'<0>:
 C_SIGNAL='@s9s_mb_2u_lib.s9s_mb_2u(sch_1):m_h_cpu0_sa_rsp(0)';
NODE_NAME     U2 EG48
 '@S9S_MB_2U_LIB.S9S_MB_2U(SCH_1):PAGE27_I169@PURE_QUANTA.SOCKET4677_AZIF0045P001C01CS(CHIPS)':
 'DDR7_A_RSP0': CDS_PINID='DDR7_A_RSP0';
NODE_NAME     J15 86
 '@S9S_MB_2U_LIB.S9S_MB_2U(SCH_1):PAGE96_I48@PURE_QUANTA.SCONN288_ADR50017P130CC(CHIPS)':
 'LBD||RSP_A_N': CDS_PINID='\lbd||rsp_a_n\';
NET_NAME
'M_H_CPU0_SA_RSP<1>'
 '@S9S_MB_2U_LIB.S9S_MB_2U(SCH_1):M_H_CPU0_SA_RSP'<1>:
 C_SIGNAL='@s9s_mb_2u_lib.s9s_mb_2u(sch_1):m_h_cpu0_sa_rsp(1)';
NODE_NAME     U2 EH47
 '@S9S_MB_2U_LIB.S9S_MB_2U(SCH_1):PAGE27_I169@PURE_QUANTA.SOCKET4677_AZIF0045P001C01CS(CHIPS)':
 'DDR7_A_RSP1': CDS_PINID='DDR7_A_RSP1';
NODE_NAME     J16 86
 '@S9S_MB_2U_LIB.S9S_MB_2U(SCH_1):PAGE97_I6@PURE_QUANTA.SCONN288_ADR50017P087CC(CHIPS)':
 'LBD||RSP_A_N': CDS_PINID='\lbd||rsp_a_n\';
NET_NAME
'M_H_CPU0_SB_CA<0>'
 '@S9S_MB_2U_LIB.S9S_MB_2U(SCH_1):M_H_CPU0_SB_CA'<0>:
 C_SIGNAL='@s9s_mb_2u_lib.s9s_mb_2u(sch_1):m_h_cpu0_sb_ca(0)';
NODE_NAME     U2 DF40
 '@S9S_MB_2U_LIB.S9S_MB_2U(SCH_1):PAGE27_I169@PURE_QUANTA.SOCKET4677_AZIF0045P001C01CS(CHIPS)':
 'DDR7_SB_CA0': CDS_PINID='DDR7_SB_CA0';
NODE_NAME     J15 76
 '@S9S_MB_2U_LIB.S9S_MB_2U(SCH_1):PAGE96_I48@PURE_QUANTA.SCONN288_ADR50017P130CC(CHIPS)':
 'CA0_B': CDS_PINID='CA0_B';
NODE_NAME     J16 76
 '@S9S_MB_2U_LIB.S9S_MB_2U(SCH_1):PAGE97_I6@PURE_QUANTA.SCONN288_ADR50017P087CC(CHIPS)':
 'CA0_B': CDS_PINID='CA0_B';
NET_NAME
'M_H_CPU0_SB_CA<1>'
 '@S9S_MB_2U_LIB.S9S_MB_2U(SCH_1):M_H_CPU0_SB_CA'<1>:
 C_SIGNAL='@s9s_mb_2u_lib.s9s_mb_2u(sch_1):m_h_cpu0_sb_ca(1)';
NODE_NAME     U2 DG41
 '@S9S_MB_2U_LIB.S9S_MB_2U(SCH_1):PAGE27_I169@PURE_QUANTA.SOCKET4677_AZIF0045P001C01CS(CHIPS)':
 'DDR7_SB_CA1': CDS_PINID='DDR7_SB_CA1';
NODE_NAME     J15 221
 '@S9S_MB_2U_LIB.S9S_MB_2U(SCH_1):PAGE96_I48@PURE_QUANTA.SCONN288_ADR50017P130CC(CHIPS)':
 'CA1_B': CDS_PINID='CA1_B';
NODE_NAME     J16 221
 '@S9S_MB_2U_LIB.S9S_MB_2U(SCH_1):PAGE97_I6@PURE_QUANTA.SCONN288_ADR50017P087CC(CHIPS)':
 'CA1_B': CDS_PINID='CA1_B';
NET_NAME
'M_H_CPU0_SB_CA<2>'
 '@S9S_MB_2U_LIB.S9S_MB_2U(SCH_1):M_H_CPU0_SB_CA'<2>:
 C_SIGNAL='@s9s_mb_2u_lib.s9s_mb_2u(sch_1):m_h_cpu0_sb_ca(2)';
NODE_NAME     U2 DL41
 '@S9S_MB_2U_LIB.S9S_MB_2U(SCH_1):PAGE27_I169@PURE_QUANTA.SOCKET4677_AZIF0045P001C01CS(CHIPS)':
 'DDR7_SB_CA2': CDS_PINID='DDR7_SB_CA2';
NODE_NAME     J15 78
 '@S9S_MB_2U_LIB.S9S_MB_2U(SCH_1):PAGE96_I48@PURE_QUANTA.SCONN288_ADR50017P130CC(CHIPS)':
 'CA2_B': CDS_PINID='CA2_B';
NODE_NAME     J16 78
 '@S9S_MB_2U_LIB.S9S_MB_2U(SCH_1):PAGE97_I6@PURE_QUANTA.SCONN288_ADR50017P087CC(CHIPS)':
 'CA2_B': CDS_PINID='CA2_B';
NET_NAME
'M_H_CPU0_SB_CA<3>'
 '@S9S_MB_2U_LIB.S9S_MB_2U(SCH_1):M_H_CPU0_SB_CA'<3>:
 C_SIGNAL='@s9s_mb_2u_lib.s9s_mb_2u(sch_1):m_h_cpu0_sb_ca(3)';
NODE_NAME     U2 DN41
 '@S9S_MB_2U_LIB.S9S_MB_2U(SCH_1):PAGE27_I169@PURE_QUANTA.SOCKET4677_AZIF0045P001C01CS(CHIPS)':
 'DDR7_SB_CA3': CDS_PINID='DDR7_SB_CA3';
NODE_NAME     J15 223
 '@S9S_MB_2U_LIB.S9S_MB_2U(SCH_1):PAGE96_I48@PURE_QUANTA.SCONN288_ADR50017P130CC(CHIPS)':
 'CA3_B': CDS_PINID='CA3_B';
NODE_NAME     J16 223
 '@S9S_MB_2U_LIB.S9S_MB_2U(SCH_1):PAGE97_I6@PURE_QUANTA.SCONN288_ADR50017P087CC(CHIPS)':
 'CA3_B': CDS_PINID='CA3_B';
NET_NAME
'M_H_CPU0_SB_CA<4>'
 '@S9S_MB_2U_LIB.S9S_MB_2U(SCH_1):M_H_CPU0_SB_CA'<4>:
 C_SIGNAL='@s9s_mb_2u_lib.s9s_mb_2u(sch_1):m_h_cpu0_sb_ca(4)';
NODE_NAME     U2 DK40
 '@S9S_MB_2U_LIB.S9S_MB_2U(SCH_1):PAGE27_I169@PURE_QUANTA.SOCKET4677_AZIF0045P001C01CS(CHIPS)':
 'DDR7_SB_CA4': CDS_PINID='DDR7_SB_CA4';
NODE_NAME     J15 80
 '@S9S_MB_2U_LIB.S9S_MB_2U(SCH_1):PAGE96_I48@PURE_QUANTA.SCONN288_ADR50017P130CC(CHIPS)':
 'CA4_B': CDS_PINID='CA4_B';
NODE_NAME     J16 80
 '@S9S_MB_2U_LIB.S9S_MB_2U(SCH_1):PAGE97_I6@PURE_QUANTA.SCONN288_ADR50017P087CC(CHIPS)':
 'CA4_B': CDS_PINID='CA4_B';
NET_NAME
'M_H_CPU0_SB_CA<5>'
 '@S9S_MB_2U_LIB.S9S_MB_2U(SCH_1):M_H_CPU0_SB_CA'<5>:
 C_SIGNAL='@s9s_mb_2u_lib.s9s_mb_2u(sch_1):m_h_cpu0_sb_ca(5)';
NODE_NAME     U2 DP40
 '@S9S_MB_2U_LIB.S9S_MB_2U(SCH_1):PAGE27_I169@PURE_QUANTA.SOCKET4677_AZIF0045P001C01CS(CHIPS)':
 'DDR7_SB_CA5': CDS_PINID='DDR7_SB_CA5';
NODE_NAME     J15 225
 '@S9S_MB_2U_LIB.S9S_MB_2U(SCH_1):PAGE96_I48@PURE_QUANTA.SCONN288_ADR50017P130CC(CHIPS)':
 'CA5_B': CDS_PINID='CA5_B';
NODE_NAME     J16 225
 '@S9S_MB_2U_LIB.S9S_MB_2U(SCH_1):PAGE97_I6@PURE_QUANTA.SCONN288_ADR50017P087CC(CHIPS)':
 'CA5_B': CDS_PINID='CA5_B';
NET_NAME
'M_H_CPU0_SB_CA<6>'
 '@S9S_MB_2U_LIB.S9S_MB_2U(SCH_1):M_H_CPU0_SB_CA'<6>:
 C_SIGNAL='@s9s_mb_2u_lib.s9s_mb_2u(sch_1):m_h_cpu0_sb_ca(6)';
NODE_NAME     U2 DJ39
 '@S9S_MB_2U_LIB.S9S_MB_2U(SCH_1):PAGE27_I169@PURE_QUANTA.SOCKET4677_AZIF0045P001C01CS(CHIPS)':
 'DDR7_SB_CA6': CDS_PINID='DDR7_SB_CA6';
NODE_NAME     J15 82
 '@S9S_MB_2U_LIB.S9S_MB_2U(SCH_1):PAGE96_I48@PURE_QUANTA.SCONN288_ADR50017P130CC(CHIPS)':
 'CA6_B': CDS_PINID='CA6_B';
NODE_NAME     J16 82
 '@S9S_MB_2U_LIB.S9S_MB_2U(SCH_1):PAGE97_I6@PURE_QUANTA.SCONN288_ADR50017P087CC(CHIPS)':
 'CA6_B': CDS_PINID='CA6_B';
NET_NAME
'M_H_CPU0_SB_CB<0>'
 '@S9S_MB_2U_LIB.S9S_MB_2U(SCH_1):M_H_CPU0_SB_CB'<0>:
 C_SIGNAL='@s9s_mb_2u_lib.s9s_mb_2u(sch_1):m_h_cpu0_sb_cb(0)';
NODE_NAME     U2 DC35
 '@S9S_MB_2U_LIB.S9S_MB_2U(SCH_1):PAGE27_I169@PURE_QUANTA.SOCKET4677_AZIF0045P001C01CS(CHIPS)':
 'DDR7_SB_ECC0': CDS_PINID='DDR7_SB_ECC0';
NODE_NAME     J15 96
 '@S9S_MB_2U_LIB.S9S_MB_2U(SCH_1):PAGE96_I48@PURE_QUANTA.SCONN288_ADR50017P130CC(CHIPS)':
 'CB0_B': CDS_PINID='CB0_B';
NODE_NAME     J16 96
 '@S9S_MB_2U_LIB.S9S_MB_2U(SCH_1):PAGE97_I6@PURE_QUANTA.SCONN288_ADR50017P087CC(CHIPS)':
 'CB0_B': CDS_PINID='CB0_B';
NET_NAME
'M_H_CPU0_SB_CB<1>'
 '@S9S_MB_2U_LIB.S9S_MB_2U(SCH_1):M_H_CPU0_SB_CB'<1>:
 C_SIGNAL='@s9s_mb_2u_lib.s9s_mb_2u(sch_1):m_h_cpu0_sb_cb(1)';
NODE_NAME     U2 DD34
 '@S9S_MB_2U_LIB.S9S_MB_2U(SCH_1):PAGE27_I169@PURE_QUANTA.SOCKET4677_AZIF0045P001C01CS(CHIPS)':
 'DDR7_SB_ECC1': CDS_PINID='DDR7_SB_ECC1';
NODE_NAME     J15 98
 '@S9S_MB_2U_LIB.S9S_MB_2U(SCH_1):PAGE96_I48@PURE_QUANTA.SCONN288_ADR50017P130CC(CHIPS)':
 'CB1_B': CDS_PINID='CB1_B';
NODE_NAME     J16 98
 '@S9S_MB_2U_LIB.S9S_MB_2U(SCH_1):PAGE97_I6@PURE_QUANTA.SCONN288_ADR50017P087CC(CHIPS)':
 'CB1_B': CDS_PINID='CB1_B';
NET_NAME
'M_H_CPU0_SB_CB<2>'
 '@S9S_MB_2U_LIB.S9S_MB_2U(SCH_1):M_H_CPU0_SB_CB'<2>:
 C_SIGNAL='@s9s_mb_2u_lib.s9s_mb_2u(sch_1):m_h_cpu0_sb_cb(2)';
NODE_NAME     U2 DG35
 '@S9S_MB_2U_LIB.S9S_MB_2U(SCH_1):PAGE27_I169@PURE_QUANTA.SOCKET4677_AZIF0045P001C01CS(CHIPS)':
 'DDR7_SB_ECC2': CDS_PINID='DDR7_SB_ECC2';
NODE_NAME     J15 241
 '@S9S_MB_2U_LIB.S9S_MB_2U(SCH_1):PAGE96_I48@PURE_QUANTA.SCONN288_ADR50017P130CC(CHIPS)':
 'CB2_B': CDS_PINID='CB2_B';
NODE_NAME     J16 241
 '@S9S_MB_2U_LIB.S9S_MB_2U(SCH_1):PAGE97_I6@PURE_QUANTA.SCONN288_ADR50017P087CC(CHIPS)':
 'CB2_B': CDS_PINID='CB2_B';
NET_NAME
'M_H_CPU0_SB_CB<3>'
 '@S9S_MB_2U_LIB.S9S_MB_2U(SCH_1):M_H_CPU0_SB_CB'<3>:
 C_SIGNAL='@s9s_mb_2u_lib.s9s_mb_2u(sch_1):m_h_cpu0_sb_cb(3)';
NODE_NAME     U2 DF34
 '@S9S_MB_2U_LIB.S9S_MB_2U(SCH_1):PAGE27_I169@PURE_QUANTA.SOCKET4677_AZIF0045P001C01CS(CHIPS)':
 'DDR7_SB_ECC3': CDS_PINID='DDR7_SB_ECC3';
NODE_NAME     J15 243
 '@S9S_MB_2U_LIB.S9S_MB_2U(SCH_1):PAGE96_I48@PURE_QUANTA.SCONN288_ADR50017P130CC(CHIPS)':
 'CB3_B': CDS_PINID='CB3_B';
NODE_NAME     J16 243
 '@S9S_MB_2U_LIB.S9S_MB_2U(SCH_1):PAGE97_I6@PURE_QUANTA.SCONN288_ADR50017P087CC(CHIPS)':
 'CB3_B': CDS_PINID='CB3_B';
NET_NAME
'M_H_CPU0_SB_CB<4>'
 '@S9S_MB_2U_LIB.S9S_MB_2U(SCH_1):M_H_CPU0_SB_CB'<4>:
 C_SIGNAL='@s9s_mb_2u_lib.s9s_mb_2u(sch_1):m_h_cpu0_sb_cb(4)';
NODE_NAME     U2 DF38
 '@S9S_MB_2U_LIB.S9S_MB_2U(SCH_1):PAGE27_I169@PURE_QUANTA.SOCKET4677_AZIF0045P001C01CS(CHIPS)':
 'DDR7_SB_ECC4': CDS_PINID='DDR7_SB_ECC4';
NODE_NAME     J15 89
 '@S9S_MB_2U_LIB.S9S_MB_2U(SCH_1):PAGE96_I48@PURE_QUANTA.SCONN288_ADR50017P130CC(CHIPS)':
 'CB4_B': CDS_PINID='CB4_B';
NODE_NAME     J16 89
 '@S9S_MB_2U_LIB.S9S_MB_2U(SCH_1):PAGE97_I6@PURE_QUANTA.SCONN288_ADR50017P087CC(CHIPS)':
 'CB4_B': CDS_PINID='CB4_B';
NET_NAME
'M_H_CPU0_SB_CB<5>'
 '@S9S_MB_2U_LIB.S9S_MB_2U(SCH_1):M_H_CPU0_SB_CB'<5>:
 C_SIGNAL='@s9s_mb_2u_lib.s9s_mb_2u(sch_1):m_h_cpu0_sb_cb(5)';
NODE_NAME     U2 DG37
 '@S9S_MB_2U_LIB.S9S_MB_2U(SCH_1):PAGE27_I169@PURE_QUANTA.SOCKET4677_AZIF0045P001C01CS(CHIPS)':
 'DDR7_SB_ECC5': CDS_PINID='DDR7_SB_ECC5';
NODE_NAME     J15 91
 '@S9S_MB_2U_LIB.S9S_MB_2U(SCH_1):PAGE96_I48@PURE_QUANTA.SCONN288_ADR50017P130CC(CHIPS)':
 'CB5_B': CDS_PINID='CB5_B';
NODE_NAME     J16 91
 '@S9S_MB_2U_LIB.S9S_MB_2U(SCH_1):PAGE97_I6@PURE_QUANTA.SCONN288_ADR50017P087CC(CHIPS)':
 'CB5_B': CDS_PINID='CB5_B';
NET_NAME
'M_H_CPU0_SB_CB<6>'
 '@S9S_MB_2U_LIB.S9S_MB_2U(SCH_1):M_H_CPU0_SB_CB'<6>:
 C_SIGNAL='@s9s_mb_2u_lib.s9s_mb_2u(sch_1):m_h_cpu0_sb_cb(6)';
NODE_NAME     U2 DD38
 '@S9S_MB_2U_LIB.S9S_MB_2U(SCH_1):PAGE27_I169@PURE_QUANTA.SOCKET4677_AZIF0045P001C01CS(CHIPS)':
 'DDR7_SB_ECC6': CDS_PINID='DDR7_SB_ECC6';
NODE_NAME     J15 234
 '@S9S_MB_2U_LIB.S9S_MB_2U(SCH_1):PAGE96_I48@PURE_QUANTA.SCONN288_ADR50017P130CC(CHIPS)':
 'CB6_B': CDS_PINID='CB6_B';
NODE_NAME     J16 234
 '@S9S_MB_2U_LIB.S9S_MB_2U(SCH_1):PAGE97_I6@PURE_QUANTA.SCONN288_ADR50017P087CC(CHIPS)':
 'CB6_B': CDS_PINID='CB6_B';
NET_NAME
'M_H_CPU0_SB_CB<7>'
 '@S9S_MB_2U_LIB.S9S_MB_2U(SCH_1):M_H_CPU0_SB_CB'<7>:
 C_SIGNAL='@s9s_mb_2u_lib.s9s_mb_2u(sch_1):m_h_cpu0_sb_cb(7)';
NODE_NAME     U2 DC37
 '@S9S_MB_2U_LIB.S9S_MB_2U(SCH_1):PAGE27_I169@PURE_QUANTA.SOCKET4677_AZIF0045P001C01CS(CHIPS)':
 'DDR7_SB_ECC7': CDS_PINID='DDR7_SB_ECC7';
NODE_NAME     J15 236
 '@S9S_MB_2U_LIB.S9S_MB_2U(SCH_1):PAGE96_I48@PURE_QUANTA.SCONN288_ADR50017P130CC(CHIPS)':
 'CB7_B': CDS_PINID='CB7_B';
NODE_NAME     J16 236
 '@S9S_MB_2U_LIB.S9S_MB_2U(SCH_1):PAGE97_I6@PURE_QUANTA.SCONN288_ADR50017P087CC(CHIPS)':
 'CB7_B': CDS_PINID='CB7_B';
NET_NAME
'M_H_CPU0_SB_CS_N<0>'
 '@S9S_MB_2U_LIB.S9S_MB_2U(SCH_1):M_H_CPU0_SB_CS_N'<0>:
 C_SIGNAL='@s9s_mb_2u_lib.s9s_mb_2u(sch_1):m_h_cpu0_sb_cs_n(0)';
NODE_NAME     U2 DL37
 '@S9S_MB_2U_LIB.S9S_MB_2U(SCH_1):PAGE27_I169@PURE_QUANTA.SOCKET4677_AZIF0045P001C01CS(CHIPS)':
 'DDR7_SB_CS_N0': CDS_PINID='DDR7_SB_CS_N0';
NODE_NAME     J15 84
 '@S9S_MB_2U_LIB.S9S_MB_2U(SCH_1):PAGE96_I48@PURE_QUANTA.SCONN288_ADR50017P130CC(CHIPS)':
 'CS0_B_N': CDS_PINID='CS0_B_N';
NET_NAME
'M_H_CPU0_SB_CS_N<1>'
 '@S9S_MB_2U_LIB.S9S_MB_2U(SCH_1):M_H_CPU0_SB_CS_N'<1>:
 C_SIGNAL='@s9s_mb_2u_lib.s9s_mb_2u(sch_1):m_h_cpu0_sb_cs_n(1)';
NODE_NAME     U2 DN37
 '@S9S_MB_2U_LIB.S9S_MB_2U(SCH_1):PAGE27_I169@PURE_QUANTA.SOCKET4677_AZIF0045P001C01CS(CHIPS)':
 'DDR7_SB_CS_N1': CDS_PINID='DDR7_SB_CS_N1';
NODE_NAME     J15 229
 '@S9S_MB_2U_LIB.S9S_MB_2U(SCH_1):PAGE96_I48@PURE_QUANTA.SCONN288_ADR50017P130CC(CHIPS)':
 'CS1_B_N': CDS_PINID='CS1_B_N';
NET_NAME
'M_H_CPU0_SB_CS_N<2>'
 '@S9S_MB_2U_LIB.S9S_MB_2U(SCH_1):M_H_CPU0_SB_CS_N'<2>:
 C_SIGNAL='@s9s_mb_2u_lib.s9s_mb_2u(sch_1):m_h_cpu0_sb_cs_n(2)';
NODE_NAME     U2 DK38
 '@S9S_MB_2U_LIB.S9S_MB_2U(SCH_1):PAGE27_I169@PURE_QUANTA.SOCKET4677_AZIF0045P001C01CS(CHIPS)':
 'DDR7_SB_CS_N2': CDS_PINID='DDR7_SB_CS_N2';
NODE_NAME     J16 84
 '@S9S_MB_2U_LIB.S9S_MB_2U(SCH_1):PAGE97_I6@PURE_QUANTA.SCONN288_ADR50017P087CC(CHIPS)':
 'CS0_B_N': CDS_PINID='CS0_B_N';
NET_NAME
'M_H_CPU0_SB_CS_N<3>'
 '@S9S_MB_2U_LIB.S9S_MB_2U(SCH_1):M_H_CPU0_SB_CS_N'<3>:
 C_SIGNAL='@s9s_mb_2u_lib.s9s_mb_2u(sch_1):m_h_cpu0_sb_cs_n(3)';
NODE_NAME     U2 DP38
 '@S9S_MB_2U_LIB.S9S_MB_2U(SCH_1):PAGE27_I169@PURE_QUANTA.SOCKET4677_AZIF0045P001C01CS(CHIPS)':
 'DDR7_SB_CS_N3': CDS_PINID='DDR7_SB_CS_N3';
NODE_NAME     J16 229
 '@S9S_MB_2U_LIB.S9S_MB_2U(SCH_1):PAGE97_I6@PURE_QUANTA.SCONN288_ADR50017P087CC(CHIPS)':
 'CS1_B_N': CDS_PINID='CS1_B_N';
NET_NAME
'M_H_CPU0_SB_DQ<0>'
 '@S9S_MB_2U_LIB.S9S_MB_2U(SCH_1):M_H_CPU0_SB_DQ'<0>:
 C_SIGNAL='@s9s_mb_2u_lib.s9s_mb_2u(sch_1):m_h_cpu0_sb_dq(0)';
NODE_NAME     U2 DD32
 '@S9S_MB_2U_LIB.S9S_MB_2U(SCH_1):PAGE27_I169@PURE_QUANTA.SOCKET4677_AZIF0045P001C01CS(CHIPS)':
 'DDR7_SB_DQ0': CDS_PINID='DDR7_SB_DQ0';
NODE_NAME     J15 100
 '@S9S_MB_2U_LIB.S9S_MB_2U(SCH_1):PAGE96_I48@PURE_QUANTA.SCONN288_ADR50017P130CC(CHIPS)':
 'DQ0_B': CDS_PINID='DQ0_B';
NODE_NAME     J16 100
 '@S9S_MB_2U_LIB.S9S_MB_2U(SCH_1):PAGE97_I6@PURE_QUANTA.SCONN288_ADR50017P087CC(CHIPS)':
 'DQ0_B': CDS_PINID='DQ0_B';
NET_NAME
'M_H_CPU0_SB_DQ<10>'
 '@S9S_MB_2U_LIB.S9S_MB_2U(SCH_1):M_H_CPU0_SB_DQ'<10>:
 C_SIGNAL='@s9s_mb_2u_lib.s9s_mb_2u(sch_1):m_h_cpu0_sb_dq(10)';
NODE_NAME     U2 DF26
 '@S9S_MB_2U_LIB.S9S_MB_2U(SCH_1):PAGE27_I169@PURE_QUANTA.SOCKET4677_AZIF0045P001C01CS(CHIPS)':
 'DDR7_SB_DQ10': CDS_PINID='DDR7_SB_DQ10';
NODE_NAME     J15 256
 '@S9S_MB_2U_LIB.S9S_MB_2U(SCH_1):PAGE96_I48@PURE_QUANTA.SCONN288_ADR50017P130CC(CHIPS)':
 'DQ10_B': CDS_PINID='DQ10_B';
NODE_NAME     J16 256
 '@S9S_MB_2U_LIB.S9S_MB_2U(SCH_1):PAGE97_I6@PURE_QUANTA.SCONN288_ADR50017P087CC(CHIPS)':
 'DQ10_B': CDS_PINID='DQ10_B';
NET_NAME
'M_H_CPU0_SB_DQ<11>'
 '@S9S_MB_2U_LIB.S9S_MB_2U(SCH_1):M_H_CPU0_SB_DQ'<11>:
 C_SIGNAL='@s9s_mb_2u_lib.s9s_mb_2u(sch_1):m_h_cpu0_sb_dq(11)';
NODE_NAME     U2 DG25
 '@S9S_MB_2U_LIB.S9S_MB_2U(SCH_1):PAGE27_I169@PURE_QUANTA.SOCKET4677_AZIF0045P001C01CS(CHIPS)':
 'DDR7_SB_DQ11': CDS_PINID='DDR7_SB_DQ11';
NODE_NAME     J15 258
 '@S9S_MB_2U_LIB.S9S_MB_2U(SCH_1):PAGE96_I48@PURE_QUANTA.SCONN288_ADR50017P130CC(CHIPS)':
 'DQ11_B': CDS_PINID='DQ11_B';
NODE_NAME     J16 258
 '@S9S_MB_2U_LIB.S9S_MB_2U(SCH_1):PAGE97_I6@PURE_QUANTA.SCONN288_ADR50017P087CC(CHIPS)':
 'DQ11_B': CDS_PINID='DQ11_B';
NET_NAME
'M_H_CPU0_SB_DQ<12>'
 '@S9S_MB_2U_LIB.S9S_MB_2U(SCH_1):M_H_CPU0_SB_DQ'<12>:
 C_SIGNAL='@s9s_mb_2u_lib.s9s_mb_2u(sch_1):m_h_cpu0_sb_dq(12)';
NODE_NAME     U2 DC23
 '@S9S_MB_2U_LIB.S9S_MB_2U(SCH_1):PAGE27_I169@PURE_QUANTA.SOCKET4677_AZIF0045P001C01CS(CHIPS)':
 'DDR7_SB_DQ12': CDS_PINID='DDR7_SB_DQ12';
NODE_NAME     J15 118
 '@S9S_MB_2U_LIB.S9S_MB_2U(SCH_1):PAGE96_I48@PURE_QUANTA.SCONN288_ADR50017P130CC(CHIPS)':
 'DQ12_B': CDS_PINID='DQ12_B';
NODE_NAME     J16 118
 '@S9S_MB_2U_LIB.S9S_MB_2U(SCH_1):PAGE97_I6@PURE_QUANTA.SCONN288_ADR50017P087CC(CHIPS)':
 'DQ12_B': CDS_PINID='DQ12_B';
NET_NAME
'M_H_CPU0_SB_DQ<13>'
 '@S9S_MB_2U_LIB.S9S_MB_2U(SCH_1):M_H_CPU0_SB_DQ'<13>:
 C_SIGNAL='@s9s_mb_2u_lib.s9s_mb_2u(sch_1):m_h_cpu0_sb_dq(13)';
NODE_NAME     U2 DD22
 '@S9S_MB_2U_LIB.S9S_MB_2U(SCH_1):PAGE27_I169@PURE_QUANTA.SOCKET4677_AZIF0045P001C01CS(CHIPS)':
 'DDR7_SB_DQ13': CDS_PINID='DDR7_SB_DQ13';
NODE_NAME     J15 120
 '@S9S_MB_2U_LIB.S9S_MB_2U(SCH_1):PAGE96_I48@PURE_QUANTA.SCONN288_ADR50017P130CC(CHIPS)':
 'DQ13_B': CDS_PINID='DQ13_B';
NODE_NAME     J16 120
 '@S9S_MB_2U_LIB.S9S_MB_2U(SCH_1):PAGE97_I6@PURE_QUANTA.SCONN288_ADR50017P087CC(CHIPS)':
 'DQ13_B': CDS_PINID='DQ13_B';
NET_NAME
'M_H_CPU0_SB_DQ<14>'
 '@S9S_MB_2U_LIB.S9S_MB_2U(SCH_1):M_H_CPU0_SB_DQ'<14>:
 C_SIGNAL='@s9s_mb_2u_lib.s9s_mb_2u(sch_1):m_h_cpu0_sb_dq(14)';
NODE_NAME     U2 DG23
 '@S9S_MB_2U_LIB.S9S_MB_2U(SCH_1):PAGE27_I169@PURE_QUANTA.SOCKET4677_AZIF0045P001C01CS(CHIPS)':
 'DDR7_SB_DQ14': CDS_PINID='DDR7_SB_DQ14';
NODE_NAME     J15 263
 '@S9S_MB_2U_LIB.S9S_MB_2U(SCH_1):PAGE96_I48@PURE_QUANTA.SCONN288_ADR50017P130CC(CHIPS)':
 'DQ14_B': CDS_PINID='DQ14_B';
NODE_NAME     J16 263
 '@S9S_MB_2U_LIB.S9S_MB_2U(SCH_1):PAGE97_I6@PURE_QUANTA.SCONN288_ADR50017P087CC(CHIPS)':
 'DQ14_B': CDS_PINID='DQ14_B';
NET_NAME
'M_H_CPU0_SB_DQ<15>'
 '@S9S_MB_2U_LIB.S9S_MB_2U(SCH_1):M_H_CPU0_SB_DQ'<15>:
 C_SIGNAL='@s9s_mb_2u_lib.s9s_mb_2u(sch_1):m_h_cpu0_sb_dq(15)';
NODE_NAME     U2 DF22
 '@S9S_MB_2U_LIB.S9S_MB_2U(SCH_1):PAGE27_I169@PURE_QUANTA.SOCKET4677_AZIF0045P001C01CS(CHIPS)':
 'DDR7_SB_DQ15': CDS_PINID='DDR7_SB_DQ15';
NODE_NAME     J15 265
 '@S9S_MB_2U_LIB.S9S_MB_2U(SCH_1):PAGE96_I48@PURE_QUANTA.SCONN288_ADR50017P130CC(CHIPS)':
 'DQ15_B': CDS_PINID='DQ15_B';
NODE_NAME     J16 265
 '@S9S_MB_2U_LIB.S9S_MB_2U(SCH_1):PAGE97_I6@PURE_QUANTA.SCONN288_ADR50017P087CC(CHIPS)':
 'DQ15_B': CDS_PINID='DQ15_B';
NET_NAME
'M_H_CPU0_SB_DQ<16>'
 '@S9S_MB_2U_LIB.S9S_MB_2U(SCH_1):M_H_CPU0_SB_DQ'<16>:
 C_SIGNAL='@s9s_mb_2u_lib.s9s_mb_2u(sch_1):m_h_cpu0_sb_dq(16)';
NODE_NAME     U2 DL23
 '@S9S_MB_2U_LIB.S9S_MB_2U(SCH_1):PAGE27_I169@PURE_QUANTA.SOCKET4677_AZIF0045P001C01CS(CHIPS)':
 'DDR7_SB_DQ16': CDS_PINID='DDR7_SB_DQ16';
NODE_NAME     J15 122
 '@S9S_MB_2U_LIB.S9S_MB_2U(SCH_1):PAGE96_I48@PURE_QUANTA.SCONN288_ADR50017P130CC(CHIPS)':
 'DQ16_B': CDS_PINID='DQ16_B';
NODE_NAME     J16 122
 '@S9S_MB_2U_LIB.S9S_MB_2U(SCH_1):PAGE97_I6@PURE_QUANTA.SCONN288_ADR50017P087CC(CHIPS)':
 'DQ16_B': CDS_PINID='DQ16_B';
NET_NAME
'M_H_CPU0_SB_DQ<17>'
 '@S9S_MB_2U_LIB.S9S_MB_2U(SCH_1):M_H_CPU0_SB_DQ'<17>:
 C_SIGNAL='@s9s_mb_2u_lib.s9s_mb_2u(sch_1):m_h_cpu0_sb_dq(17)';
NODE_NAME     U2 DK22
 '@S9S_MB_2U_LIB.S9S_MB_2U(SCH_1):PAGE27_I169@PURE_QUANTA.SOCKET4677_AZIF0045P001C01CS(CHIPS)':
 'DDR7_SB_DQ17': CDS_PINID='DDR7_SB_DQ17';
NODE_NAME     J15 124
 '@S9S_MB_2U_LIB.S9S_MB_2U(SCH_1):PAGE96_I48@PURE_QUANTA.SCONN288_ADR50017P130CC(CHIPS)':
 'DQ17_B': CDS_PINID='DQ17_B';
NODE_NAME     J16 124
 '@S9S_MB_2U_LIB.S9S_MB_2U(SCH_1):PAGE97_I6@PURE_QUANTA.SCONN288_ADR50017P087CC(CHIPS)':
 'DQ17_B': CDS_PINID='DQ17_B';
NET_NAME
'M_H_CPU0_SB_DQ<18>'
 '@S9S_MB_2U_LIB.S9S_MB_2U(SCH_1):M_H_CPU0_SB_DQ'<18>:
 C_SIGNAL='@s9s_mb_2u_lib.s9s_mb_2u(sch_1):m_h_cpu0_sb_dq(18)';
NODE_NAME     U2 DN23
 '@S9S_MB_2U_LIB.S9S_MB_2U(SCH_1):PAGE27_I169@PURE_QUANTA.SOCKET4677_AZIF0045P001C01CS(CHIPS)':
 'DDR7_SB_DQ18': CDS_PINID='DDR7_SB_DQ18';
NODE_NAME     J15 267
 '@S9S_MB_2U_LIB.S9S_MB_2U(SCH_1):PAGE96_I48@PURE_QUANTA.SCONN288_ADR50017P130CC(CHIPS)':
 'DQ18_B': CDS_PINID='DQ18_B';
NODE_NAME     J16 267
 '@S9S_MB_2U_LIB.S9S_MB_2U(SCH_1):PAGE97_I6@PURE_QUANTA.SCONN288_ADR50017P087CC(CHIPS)':
 'DQ18_B': CDS_PINID='DQ18_B';
NET_NAME
'M_H_CPU0_SB_DQ<19>'
 '@S9S_MB_2U_LIB.S9S_MB_2U(SCH_1):M_H_CPU0_SB_DQ'<19>:
 C_SIGNAL='@s9s_mb_2u_lib.s9s_mb_2u(sch_1):m_h_cpu0_sb_dq(19)';
NODE_NAME     U2 DP22
 '@S9S_MB_2U_LIB.S9S_MB_2U(SCH_1):PAGE27_I169@PURE_QUANTA.SOCKET4677_AZIF0045P001C01CS(CHIPS)':
 'DDR7_SB_DQ19': CDS_PINID='DDR7_SB_DQ19';
NODE_NAME     J15 269
 '@S9S_MB_2U_LIB.S9S_MB_2U(SCH_1):PAGE96_I48@PURE_QUANTA.SCONN288_ADR50017P130CC(CHIPS)':
 'DQ19_B': CDS_PINID='DQ19_B';
NODE_NAME     J16 269
 '@S9S_MB_2U_LIB.S9S_MB_2U(SCH_1):PAGE97_I6@PURE_QUANTA.SCONN288_ADR50017P087CC(CHIPS)':
 'DQ19_B': CDS_PINID='DQ19_B';
NET_NAME
'M_H_CPU0_SB_DQ<1>'
 '@S9S_MB_2U_LIB.S9S_MB_2U(SCH_1):M_H_CPU0_SB_DQ'<1>:
 C_SIGNAL='@s9s_mb_2u_lib.s9s_mb_2u(sch_1):m_h_cpu0_sb_dq(1)';
NODE_NAME     U2 DC31
 '@S9S_MB_2U_LIB.S9S_MB_2U(SCH_1):PAGE27_I169@PURE_QUANTA.SOCKET4677_AZIF0045P001C01CS(CHIPS)':
 'DDR7_SB_DQ1': CDS_PINID='DDR7_SB_DQ1';
NODE_NAME     J15 102
 '@S9S_MB_2U_LIB.S9S_MB_2U(SCH_1):PAGE96_I48@PURE_QUANTA.SCONN288_ADR50017P130CC(CHIPS)':
 'DQ1_B': CDS_PINID='DQ1_B';
NODE_NAME     J16 102
 '@S9S_MB_2U_LIB.S9S_MB_2U(SCH_1):PAGE97_I6@PURE_QUANTA.SCONN288_ADR50017P087CC(CHIPS)':
 'DQ1_B': CDS_PINID='DQ1_B';
NET_NAME
'M_H_CPU0_SB_DQ<20>'
 '@S9S_MB_2U_LIB.S9S_MB_2U(SCH_1):M_H_CPU0_SB_DQ'<20>:
 C_SIGNAL='@s9s_mb_2u_lib.s9s_mb_2u(sch_1):m_h_cpu0_sb_dq(20)';
NODE_NAME     U2 DK20
 '@S9S_MB_2U_LIB.S9S_MB_2U(SCH_1):PAGE27_I169@PURE_QUANTA.SOCKET4677_AZIF0045P001C01CS(CHIPS)':
 'DDR7_SB_DQ20': CDS_PINID='DDR7_SB_DQ20';
NODE_NAME     J15 129
 '@S9S_MB_2U_LIB.S9S_MB_2U(SCH_1):PAGE96_I48@PURE_QUANTA.SCONN288_ADR50017P130CC(CHIPS)':
 'DQ20_B': CDS_PINID='DQ20_B';
NODE_NAME     J16 129
 '@S9S_MB_2U_LIB.S9S_MB_2U(SCH_1):PAGE97_I6@PURE_QUANTA.SCONN288_ADR50017P087CC(CHIPS)':
 'DQ20_B': CDS_PINID='DQ20_B';
NET_NAME
'M_H_CPU0_SB_DQ<21>'
 '@S9S_MB_2U_LIB.S9S_MB_2U(SCH_1):M_H_CPU0_SB_DQ'<21>:
 C_SIGNAL='@s9s_mb_2u_lib.s9s_mb_2u(sch_1):m_h_cpu0_sb_dq(21)';
NODE_NAME     U2 DL19
 '@S9S_MB_2U_LIB.S9S_MB_2U(SCH_1):PAGE27_I169@PURE_QUANTA.SOCKET4677_AZIF0045P001C01CS(CHIPS)':
 'DDR7_SB_DQ21': CDS_PINID='DDR7_SB_DQ21';
NODE_NAME     J15 131
 '@S9S_MB_2U_LIB.S9S_MB_2U(SCH_1):PAGE96_I48@PURE_QUANTA.SCONN288_ADR50017P130CC(CHIPS)':
 'DQ21_B': CDS_PINID='DQ21_B';
NODE_NAME     J16 131
 '@S9S_MB_2U_LIB.S9S_MB_2U(SCH_1):PAGE97_I6@PURE_QUANTA.SCONN288_ADR50017P087CC(CHIPS)':
 'DQ21_B': CDS_PINID='DQ21_B';
NET_NAME
'M_H_CPU0_SB_DQ<22>'
 '@S9S_MB_2U_LIB.S9S_MB_2U(SCH_1):M_H_CPU0_SB_DQ'<22>:
 C_SIGNAL='@s9s_mb_2u_lib.s9s_mb_2u(sch_1):m_h_cpu0_sb_dq(22)';
NODE_NAME     U2 DP20
 '@S9S_MB_2U_LIB.S9S_MB_2U(SCH_1):PAGE27_I169@PURE_QUANTA.SOCKET4677_AZIF0045P001C01CS(CHIPS)':
 'DDR7_SB_DQ22': CDS_PINID='DDR7_SB_DQ22';
NODE_NAME     J15 274
 '@S9S_MB_2U_LIB.S9S_MB_2U(SCH_1):PAGE96_I48@PURE_QUANTA.SCONN288_ADR50017P130CC(CHIPS)':
 'DQ22_B': CDS_PINID='DQ22_B';
NODE_NAME     J16 274
 '@S9S_MB_2U_LIB.S9S_MB_2U(SCH_1):PAGE97_I6@PURE_QUANTA.SCONN288_ADR50017P087CC(CHIPS)':
 'DQ22_B': CDS_PINID='DQ22_B';
NET_NAME
'M_H_CPU0_SB_DQ<23>'
 '@S9S_MB_2U_LIB.S9S_MB_2U(SCH_1):M_H_CPU0_SB_DQ'<23>:
 C_SIGNAL='@s9s_mb_2u_lib.s9s_mb_2u(sch_1):m_h_cpu0_sb_dq(23)';
NODE_NAME     U2 DN19
 '@S9S_MB_2U_LIB.S9S_MB_2U(SCH_1):PAGE27_I169@PURE_QUANTA.SOCKET4677_AZIF0045P001C01CS(CHIPS)':
 'DDR7_SB_DQ23': CDS_PINID='DDR7_SB_DQ23';
NODE_NAME     J15 276
 '@S9S_MB_2U_LIB.S9S_MB_2U(SCH_1):PAGE96_I48@PURE_QUANTA.SCONN288_ADR50017P130CC(CHIPS)':
 'DQ23_B': CDS_PINID='DQ23_B';
NODE_NAME     J16 276
 '@S9S_MB_2U_LIB.S9S_MB_2U(SCH_1):PAGE97_I6@PURE_QUANTA.SCONN288_ADR50017P087CC(CHIPS)':
 'DQ23_B': CDS_PINID='DQ23_B';
NET_NAME
'M_H_CPU0_SB_DQ<24>'
 '@S9S_MB_2U_LIB.S9S_MB_2U(SCH_1):M_H_CPU0_SB_DQ'<24>:
 C_SIGNAL='@s9s_mb_2u_lib.s9s_mb_2u(sch_1):m_h_cpu0_sb_dq(24)';
NODE_NAME     U2 DD20
 '@S9S_MB_2U_LIB.S9S_MB_2U(SCH_1):PAGE27_I169@PURE_QUANTA.SOCKET4677_AZIF0045P001C01CS(CHIPS)':
 'DDR7_SB_DQ24': CDS_PINID='DDR7_SB_DQ24';
NODE_NAME     J15 133
 '@S9S_MB_2U_LIB.S9S_MB_2U(SCH_1):PAGE96_I48@PURE_QUANTA.SCONN288_ADR50017P130CC(CHIPS)':
 'DQ24_B': CDS_PINID='DQ24_B';
NODE_NAME     J16 133
 '@S9S_MB_2U_LIB.S9S_MB_2U(SCH_1):PAGE97_I6@PURE_QUANTA.SCONN288_ADR50017P087CC(CHIPS)':
 'DQ24_B': CDS_PINID='DQ24_B';
NET_NAME
'M_H_CPU0_SB_DQ<25>'
 '@S9S_MB_2U_LIB.S9S_MB_2U(SCH_1):M_H_CPU0_SB_DQ'<25>:
 C_SIGNAL='@s9s_mb_2u_lib.s9s_mb_2u(sch_1):m_h_cpu0_sb_dq(25)';
NODE_NAME     U2 DC19
 '@S9S_MB_2U_LIB.S9S_MB_2U(SCH_1):PAGE27_I169@PURE_QUANTA.SOCKET4677_AZIF0045P001C01CS(CHIPS)':
 'DDR7_SB_DQ25': CDS_PINID='DDR7_SB_DQ25';
NODE_NAME     J15 135
 '@S9S_MB_2U_LIB.S9S_MB_2U(SCH_1):PAGE96_I48@PURE_QUANTA.SCONN288_ADR50017P130CC(CHIPS)':
 'DQ25_B': CDS_PINID='DQ25_B';
NODE_NAME     J16 135
 '@S9S_MB_2U_LIB.S9S_MB_2U(SCH_1):PAGE97_I6@PURE_QUANTA.SCONN288_ADR50017P087CC(CHIPS)':
 'DQ25_B': CDS_PINID='DQ25_B';
NET_NAME
'M_H_CPU0_SB_DQ<26>'
 '@S9S_MB_2U_LIB.S9S_MB_2U(SCH_1):M_H_CPU0_SB_DQ'<26>:
 C_SIGNAL='@s9s_mb_2u_lib.s9s_mb_2u(sch_1):m_h_cpu0_sb_dq(26)';
NODE_NAME     U2 DF20
 '@S9S_MB_2U_LIB.S9S_MB_2U(SCH_1):PAGE27_I169@PURE_QUANTA.SOCKET4677_AZIF0045P001C01CS(CHIPS)':
 'DDR7_SB_DQ26': CDS_PINID='DDR7_SB_DQ26';
NODE_NAME     J15 278
 '@S9S_MB_2U_LIB.S9S_MB_2U(SCH_1):PAGE96_I48@PURE_QUANTA.SCONN288_ADR50017P130CC(CHIPS)':
 'DQ26_B': CDS_PINID='DQ26_B';
NODE_NAME     J16 278
 '@S9S_MB_2U_LIB.S9S_MB_2U(SCH_1):PAGE97_I6@PURE_QUANTA.SCONN288_ADR50017P087CC(CHIPS)':
 'DQ26_B': CDS_PINID='DQ26_B';
NET_NAME
'M_H_CPU0_SB_DQ<27>'
 '@S9S_MB_2U_LIB.S9S_MB_2U(SCH_1):M_H_CPU0_SB_DQ'<27>:
 C_SIGNAL='@s9s_mb_2u_lib.s9s_mb_2u(sch_1):m_h_cpu0_sb_dq(27)';
NODE_NAME     U2 DG19
 '@S9S_MB_2U_LIB.S9S_MB_2U(SCH_1):PAGE27_I169@PURE_QUANTA.SOCKET4677_AZIF0045P001C01CS(CHIPS)':
 'DDR7_SB_DQ27': CDS_PINID='DDR7_SB_DQ27';
NODE_NAME     J15 280
 '@S9S_MB_2U_LIB.S9S_MB_2U(SCH_1):PAGE96_I48@PURE_QUANTA.SCONN288_ADR50017P130CC(CHIPS)':
 'DQ27_B': CDS_PINID='DQ27_B';
NODE_NAME     J16 280
 '@S9S_MB_2U_LIB.S9S_MB_2U(SCH_1):PAGE97_I6@PURE_QUANTA.SCONN288_ADR50017P087CC(CHIPS)':
 'DQ27_B': CDS_PINID='DQ27_B';
NET_NAME
'M_H_CPU0_SB_DQ<28>'
 '@S9S_MB_2U_LIB.S9S_MB_2U(SCH_1):M_H_CPU0_SB_DQ'<28>:
 C_SIGNAL='@s9s_mb_2u_lib.s9s_mb_2u(sch_1):m_h_cpu0_sb_dq(28)';
NODE_NAME     U2 DG17
 '@S9S_MB_2U_LIB.S9S_MB_2U(SCH_1):PAGE27_I169@PURE_QUANTA.SOCKET4677_AZIF0045P001C01CS(CHIPS)':
 'DDR7_SB_DQ28': CDS_PINID='DDR7_SB_DQ28';
NODE_NAME     J15 140
 '@S9S_MB_2U_LIB.S9S_MB_2U(SCH_1):PAGE96_I48@PURE_QUANTA.SCONN288_ADR50017P130CC(CHIPS)':
 'DQ28_B': CDS_PINID='DQ28_B';
NODE_NAME     J16 140
 '@S9S_MB_2U_LIB.S9S_MB_2U(SCH_1):PAGE97_I6@PURE_QUANTA.SCONN288_ADR50017P087CC(CHIPS)':
 'DQ28_B': CDS_PINID='DQ28_B';
NET_NAME
'M_H_CPU0_SB_DQ<29>'
 '@S9S_MB_2U_LIB.S9S_MB_2U(SCH_1):M_H_CPU0_SB_DQ'<29>:
 C_SIGNAL='@s9s_mb_2u_lib.s9s_mb_2u(sch_1):m_h_cpu0_sb_dq(29)';
NODE_NAME     U2 DA17
 '@S9S_MB_2U_LIB.S9S_MB_2U(SCH_1):PAGE27_I169@PURE_QUANTA.SOCKET4677_AZIF0045P001C01CS(CHIPS)':
 'DDR7_SB_DQ29': CDS_PINID='DDR7_SB_DQ29';
NODE_NAME     J15 142
 '@S9S_MB_2U_LIB.S9S_MB_2U(SCH_1):PAGE96_I48@PURE_QUANTA.SCONN288_ADR50017P130CC(CHIPS)':
 'DQ29_B': CDS_PINID='DQ29_B';
NODE_NAME     J16 142
 '@S9S_MB_2U_LIB.S9S_MB_2U(SCH_1):PAGE97_I6@PURE_QUANTA.SCONN288_ADR50017P087CC(CHIPS)':
 'DQ29_B': CDS_PINID='DQ29_B';
NET_NAME
'M_H_CPU0_SB_DQ<2>'
 '@S9S_MB_2U_LIB.S9S_MB_2U(SCH_1):M_H_CPU0_SB_DQ'<2>:
 C_SIGNAL='@s9s_mb_2u_lib.s9s_mb_2u(sch_1):m_h_cpu0_sb_dq(2)';
NODE_NAME     U2 DF32
 '@S9S_MB_2U_LIB.S9S_MB_2U(SCH_1):PAGE27_I169@PURE_QUANTA.SOCKET4677_AZIF0045P001C01CS(CHIPS)':
 'DDR7_SB_DQ2': CDS_PINID='DDR7_SB_DQ2';
NODE_NAME     J15 245
 '@S9S_MB_2U_LIB.S9S_MB_2U(SCH_1):PAGE96_I48@PURE_QUANTA.SCONN288_ADR50017P130CC(CHIPS)':
 'DQ2_B': CDS_PINID='DQ2_B';
NODE_NAME     J16 245
 '@S9S_MB_2U_LIB.S9S_MB_2U(SCH_1):PAGE97_I6@PURE_QUANTA.SCONN288_ADR50017P087CC(CHIPS)':
 'DQ2_B': CDS_PINID='DQ2_B';
NET_NAME
'M_H_CPU0_SB_DQ<30>'
 '@S9S_MB_2U_LIB.S9S_MB_2U(SCH_1):M_H_CPU0_SB_DQ'<30>:
 C_SIGNAL='@s9s_mb_2u_lib.s9s_mb_2u(sch_1):m_h_cpu0_sb_dq(30)';
NODE_NAME     U2 DJ17
 '@S9S_MB_2U_LIB.S9S_MB_2U(SCH_1):PAGE27_I169@PURE_QUANTA.SOCKET4677_AZIF0045P001C01CS(CHIPS)':
 'DDR7_SB_DQ30': CDS_PINID='DDR7_SB_DQ30';
NODE_NAME     J15 285
 '@S9S_MB_2U_LIB.S9S_MB_2U(SCH_1):PAGE96_I48@PURE_QUANTA.SCONN288_ADR50017P130CC(CHIPS)':
 'DQ30_B': CDS_PINID='DQ30_B';
NODE_NAME     J16 285
 '@S9S_MB_2U_LIB.S9S_MB_2U(SCH_1):PAGE97_I6@PURE_QUANTA.SCONN288_ADR50017P087CC(CHIPS)':
 'DQ30_B': CDS_PINID='DQ30_B';
NET_NAME
'M_H_CPU0_SB_DQ<31>'
 '@S9S_MB_2U_LIB.S9S_MB_2U(SCH_1):M_H_CPU0_SB_DQ'<31>:
 C_SIGNAL='@s9s_mb_2u_lib.s9s_mb_2u(sch_1):m_h_cpu0_sb_dq(31)';
NODE_NAME     U2 DC17
 '@S9S_MB_2U_LIB.S9S_MB_2U(SCH_1):PAGE27_I169@PURE_QUANTA.SOCKET4677_AZIF0045P001C01CS(CHIPS)':
 'DDR7_SB_DQ31': CDS_PINID='DDR7_SB_DQ31';
NODE_NAME     J15 287
 '@S9S_MB_2U_LIB.S9S_MB_2U(SCH_1):PAGE96_I48@PURE_QUANTA.SCONN288_ADR50017P130CC(CHIPS)':
 'DQ31_B': CDS_PINID='DQ31_B';
NODE_NAME     J16 287
 '@S9S_MB_2U_LIB.S9S_MB_2U(SCH_1):PAGE97_I6@PURE_QUANTA.SCONN288_ADR50017P087CC(CHIPS)':
 'DQ31_B': CDS_PINID='DQ31_B';
NET_NAME
'M_H_CPU0_SB_DQ<3>'
 '@S9S_MB_2U_LIB.S9S_MB_2U(SCH_1):M_H_CPU0_SB_DQ'<3>:
 C_SIGNAL='@s9s_mb_2u_lib.s9s_mb_2u(sch_1):m_h_cpu0_sb_dq(3)';
NODE_NAME     U2 DG31
 '@S9S_MB_2U_LIB.S9S_MB_2U(SCH_1):PAGE27_I169@PURE_QUANTA.SOCKET4677_AZIF0045P001C01CS(CHIPS)':
 'DDR7_SB_DQ3': CDS_PINID='DDR7_SB_DQ3';
NODE_NAME     J15 247
 '@S9S_MB_2U_LIB.S9S_MB_2U(SCH_1):PAGE96_I48@PURE_QUANTA.SCONN288_ADR50017P130CC(CHIPS)':
 'DQ3_B': CDS_PINID='DQ3_B';
NODE_NAME     J16 247
 '@S9S_MB_2U_LIB.S9S_MB_2U(SCH_1):PAGE97_I6@PURE_QUANTA.SCONN288_ADR50017P087CC(CHIPS)':
 'DQ3_B': CDS_PINID='DQ3_B';
NET_NAME
'M_H_CPU0_SB_DQ<4>'
 '@S9S_MB_2U_LIB.S9S_MB_2U(SCH_1):M_H_CPU0_SB_DQ'<4>:
 C_SIGNAL='@s9s_mb_2u_lib.s9s_mb_2u(sch_1):m_h_cpu0_sb_dq(4)';
NODE_NAME     U2 DC29
 '@S9S_MB_2U_LIB.S9S_MB_2U(SCH_1):PAGE27_I169@PURE_QUANTA.SOCKET4677_AZIF0045P001C01CS(CHIPS)':
 'DDR7_SB_DQ4': CDS_PINID='DDR7_SB_DQ4';
NODE_NAME     J15 107
 '@S9S_MB_2U_LIB.S9S_MB_2U(SCH_1):PAGE96_I48@PURE_QUANTA.SCONN288_ADR50017P130CC(CHIPS)':
 'DQ4_B': CDS_PINID='DQ4_B';
NODE_NAME     J16 107
 '@S9S_MB_2U_LIB.S9S_MB_2U(SCH_1):PAGE97_I6@PURE_QUANTA.SCONN288_ADR50017P087CC(CHIPS)':
 'DQ4_B': CDS_PINID='DQ4_B';
NET_NAME
'M_H_CPU0_SB_DQ<5>'
 '@S9S_MB_2U_LIB.S9S_MB_2U(SCH_1):M_H_CPU0_SB_DQ'<5>:
 C_SIGNAL='@s9s_mb_2u_lib.s9s_mb_2u(sch_1):m_h_cpu0_sb_dq(5)';
NODE_NAME     U2 DF28
 '@S9S_MB_2U_LIB.S9S_MB_2U(SCH_1):PAGE27_I169@PURE_QUANTA.SOCKET4677_AZIF0045P001C01CS(CHIPS)':
 'DDR7_SB_DQ5': CDS_PINID='DDR7_SB_DQ5';
NODE_NAME     J15 109
 '@S9S_MB_2U_LIB.S9S_MB_2U(SCH_1):PAGE96_I48@PURE_QUANTA.SCONN288_ADR50017P130CC(CHIPS)':
 'DQ5_B': CDS_PINID='DQ5_B';
NODE_NAME     J16 109
 '@S9S_MB_2U_LIB.S9S_MB_2U(SCH_1):PAGE97_I6@PURE_QUANTA.SCONN288_ADR50017P087CC(CHIPS)':
 'DQ5_B': CDS_PINID='DQ5_B';
NET_NAME
'M_H_CPU0_SB_DQ<6>'
 '@S9S_MB_2U_LIB.S9S_MB_2U(SCH_1):M_H_CPU0_SB_DQ'<6>:
 C_SIGNAL='@s9s_mb_2u_lib.s9s_mb_2u(sch_1):m_h_cpu0_sb_dq(6)';
NODE_NAME     U2 DG29
 '@S9S_MB_2U_LIB.S9S_MB_2U(SCH_1):PAGE27_I169@PURE_QUANTA.SOCKET4677_AZIF0045P001C01CS(CHIPS)':
 'DDR7_SB_DQ6': CDS_PINID='DDR7_SB_DQ6';
NODE_NAME     J15 252
 '@S9S_MB_2U_LIB.S9S_MB_2U(SCH_1):PAGE96_I48@PURE_QUANTA.SCONN288_ADR50017P130CC(CHIPS)':
 'DQ6_B': CDS_PINID='DQ6_B';
NODE_NAME     J16 252
 '@S9S_MB_2U_LIB.S9S_MB_2U(SCH_1):PAGE97_I6@PURE_QUANTA.SCONN288_ADR50017P087CC(CHIPS)':
 'DQ6_B': CDS_PINID='DQ6_B';
NET_NAME
'M_H_CPU0_SB_DQ<7>'
 '@S9S_MB_2U_LIB.S9S_MB_2U(SCH_1):M_H_CPU0_SB_DQ'<7>:
 C_SIGNAL='@s9s_mb_2u_lib.s9s_mb_2u(sch_1):m_h_cpu0_sb_dq(7)';
NODE_NAME     U2 DD28
 '@S9S_MB_2U_LIB.S9S_MB_2U(SCH_1):PAGE27_I169@PURE_QUANTA.SOCKET4677_AZIF0045P001C01CS(CHIPS)':
 'DDR7_SB_DQ7': CDS_PINID='DDR7_SB_DQ7';
NODE_NAME     J15 254
 '@S9S_MB_2U_LIB.S9S_MB_2U(SCH_1):PAGE96_I48@PURE_QUANTA.SCONN288_ADR50017P130CC(CHIPS)':
 'DQ7_B': CDS_PINID='DQ7_B';
NODE_NAME     J16 254
 '@S9S_MB_2U_LIB.S9S_MB_2U(SCH_1):PAGE97_I6@PURE_QUANTA.SCONN288_ADR50017P087CC(CHIPS)':
 'DQ7_B': CDS_PINID='DQ7_B';
NET_NAME
'M_H_CPU0_SB_DQ<8>'
 '@S9S_MB_2U_LIB.S9S_MB_2U(SCH_1):M_H_CPU0_SB_DQ'<8>:
 C_SIGNAL='@s9s_mb_2u_lib.s9s_mb_2u(sch_1):m_h_cpu0_sb_dq(8)';
NODE_NAME     U2 DD26
 '@S9S_MB_2U_LIB.S9S_MB_2U(SCH_1):PAGE27_I169@PURE_QUANTA.SOCKET4677_AZIF0045P001C01CS(CHIPS)':
 'DDR7_SB_DQ8': CDS_PINID='DDR7_SB_DQ8';
NODE_NAME     J15 111
 '@S9S_MB_2U_LIB.S9S_MB_2U(SCH_1):PAGE96_I48@PURE_QUANTA.SCONN288_ADR50017P130CC(CHIPS)':
 'DQ8_B': CDS_PINID='DQ8_B';
NODE_NAME     J16 111
 '@S9S_MB_2U_LIB.S9S_MB_2U(SCH_1):PAGE97_I6@PURE_QUANTA.SCONN288_ADR50017P087CC(CHIPS)':
 'DQ8_B': CDS_PINID='DQ8_B';
NET_NAME
'M_H_CPU0_SB_DQ<9>'
 '@S9S_MB_2U_LIB.S9S_MB_2U(SCH_1):M_H_CPU0_SB_DQ'<9>:
 C_SIGNAL='@s9s_mb_2u_lib.s9s_mb_2u(sch_1):m_h_cpu0_sb_dq(9)';
NODE_NAME     U2 DC25
 '@S9S_MB_2U_LIB.S9S_MB_2U(SCH_1):PAGE27_I169@PURE_QUANTA.SOCKET4677_AZIF0045P001C01CS(CHIPS)':
 'DDR7_SB_DQ9': CDS_PINID='DDR7_SB_DQ9';
NODE_NAME     J15 113
 '@S9S_MB_2U_LIB.S9S_MB_2U(SCH_1):PAGE96_I48@PURE_QUANTA.SCONN288_ADR50017P130CC(CHIPS)':
 'DQ9_B': CDS_PINID='DQ9_B';
NODE_NAME     J16 113
 '@S9S_MB_2U_LIB.S9S_MB_2U(SCH_1):PAGE97_I6@PURE_QUANTA.SCONN288_ADR50017P087CC(CHIPS)':
 'DQ9_B': CDS_PINID='DQ9_B';
NET_NAME
'M_H_CPU0_SB_DQS_DN<0>'
 '@S9S_MB_2U_LIB.S9S_MB_2U(SCH_1):M_H_CPU0_SB_DQS_DN'<0>:
 C_SIGNAL='@s9s_mb_2u_lib.s9s_mb_2u(sch_1):m_h_cpu0_sb_dqs_dn(0)';
NODE_NAME     U2 DD30
 '@S9S_MB_2U_LIB.S9S_MB_2U(SCH_1):PAGE27_I169@PURE_QUANTA.SOCKET4677_AZIF0045P001C01CS(CHIPS)':
 'DDR7_SB_DQS_DN0': CDS_PINID='DDR7_SB_DQS_DN0';
NODE_NAME     J15 105
 '@S9S_MB_2U_LIB.S9S_MB_2U(SCH_1):PAGE96_I178@PURE_QUANTA.SCONN288_ADR50017P130CC(CHIPS)':
 'DQS0_B_C': CDS_PINID='DQS0_B_C';
NODE_NAME     J16 105
 '@S9S_MB_2U_LIB.S9S_MB_2U(SCH_1):PAGE97_I178@PURE_QUANTA.SCONN288_ADR50017P087CC(CHIPS)':
 'DQS0_B_C': CDS_PINID='DQS0_B_C';
NET_NAME
'M_H_CPU0_SB_DQS_DN<1>'
 '@S9S_MB_2U_LIB.S9S_MB_2U(SCH_1):M_H_CPU0_SB_DQS_DN'<1>:
 C_SIGNAL='@s9s_mb_2u_lib.s9s_mb_2u(sch_1):m_h_cpu0_sb_dqs_dn(1)';
NODE_NAME     U2 DD24
 '@S9S_MB_2U_LIB.S9S_MB_2U(SCH_1):PAGE27_I169@PURE_QUANTA.SOCKET4677_AZIF0045P001C01CS(CHIPS)':
 'DDR7_SB_DQS_DN1': CDS_PINID='DDR7_SB_DQS_DN1';
NODE_NAME     J15 116
 '@S9S_MB_2U_LIB.S9S_MB_2U(SCH_1):PAGE96_I178@PURE_QUANTA.SCONN288_ADR50017P130CC(CHIPS)':
 'DQS1_B_C': CDS_PINID='DQS1_B_C';
NODE_NAME     J16 116
 '@S9S_MB_2U_LIB.S9S_MB_2U(SCH_1):PAGE97_I178@PURE_QUANTA.SCONN288_ADR50017P087CC(CHIPS)':
 'DQS1_B_C': CDS_PINID='DQS1_B_C';
NET_NAME
'M_H_CPU0_SB_DQS_DN<2>'
 '@S9S_MB_2U_LIB.S9S_MB_2U(SCH_1):M_H_CPU0_SB_DQS_DN'<2>:
 C_SIGNAL='@s9s_mb_2u_lib.s9s_mb_2u(sch_1):m_h_cpu0_sb_dqs_dn(2)';
NODE_NAME     U2 DL21
 '@S9S_MB_2U_LIB.S9S_MB_2U(SCH_1):PAGE27_I169@PURE_QUANTA.SOCKET4677_AZIF0045P001C01CS(CHIPS)':
 'DDR7_SB_DQS_DN2': CDS_PINID='DDR7_SB_DQS_DN2';
NODE_NAME     J15 127
 '@S9S_MB_2U_LIB.S9S_MB_2U(SCH_1):PAGE96_I178@PURE_QUANTA.SCONN288_ADR50017P130CC(CHIPS)':
 'DQS2_B_C': CDS_PINID='DQS2_B_C';
NODE_NAME     J16 127
 '@S9S_MB_2U_LIB.S9S_MB_2U(SCH_1):PAGE97_I178@PURE_QUANTA.SCONN288_ADR50017P087CC(CHIPS)':
 'DQS2_B_C': CDS_PINID='DQS2_B_C';
NET_NAME
'M_H_CPU0_SB_DQS_DN<3>'
 '@S9S_MB_2U_LIB.S9S_MB_2U(SCH_1):M_H_CPU0_SB_DQS_DN'<3>:
 C_SIGNAL='@s9s_mb_2u_lib.s9s_mb_2u(sch_1):m_h_cpu0_sb_dqs_dn(3)';
NODE_NAME     U2 DB18
 '@S9S_MB_2U_LIB.S9S_MB_2U(SCH_1):PAGE27_I169@PURE_QUANTA.SOCKET4677_AZIF0045P001C01CS(CHIPS)':
 'DDR7_SB_DQS_DN3': CDS_PINID='DDR7_SB_DQS_DN3';
NODE_NAME     J15 138
 '@S9S_MB_2U_LIB.S9S_MB_2U(SCH_1):PAGE96_I178@PURE_QUANTA.SCONN288_ADR50017P130CC(CHIPS)':
 'DQS3_B_C': CDS_PINID='DQS3_B_C';
NODE_NAME     J16 138
 '@S9S_MB_2U_LIB.S9S_MB_2U(SCH_1):PAGE97_I178@PURE_QUANTA.SCONN288_ADR50017P087CC(CHIPS)':
 'DQS3_B_C': CDS_PINID='DQS3_B_C';
NET_NAME
'M_H_CPU0_SB_DQS_DN<4>'
 '@S9S_MB_2U_LIB.S9S_MB_2U(SCH_1):M_H_CPU0_SB_DQS_DN'<4>:
 C_SIGNAL='@s9s_mb_2u_lib.s9s_mb_2u(sch_1):m_h_cpu0_sb_dqs_dn(4)';
NODE_NAME     U2 DH36
 '@S9S_MB_2U_LIB.S9S_MB_2U(SCH_1):PAGE27_I169@PURE_QUANTA.SOCKET4677_AZIF0045P001C01CS(CHIPS)':
 'DDR7_SB_DQS_DN4': CDS_PINID='DDR7_SB_DQS_DN4';
NODE_NAME     J15 238
 '@S9S_MB_2U_LIB.S9S_MB_2U(SCH_1):PAGE96_I178@PURE_QUANTA.SCONN288_ADR50017P130CC(CHIPS)':
 'DQS4_B_C': CDS_PINID='DQS4_B_C';
NODE_NAME     J16 238
 '@S9S_MB_2U_LIB.S9S_MB_2U(SCH_1):PAGE97_I178@PURE_QUANTA.SCONN288_ADR50017P087CC(CHIPS)':
 'DQS4_B_C': CDS_PINID='DQS4_B_C';
NET_NAME
'M_H_CPU0_SB_DQS_DN<5>'
 '@S9S_MB_2U_LIB.S9S_MB_2U(SCH_1):M_H_CPU0_SB_DQS_DN'<5>:
 C_SIGNAL='@s9s_mb_2u_lib.s9s_mb_2u(sch_1):m_h_cpu0_sb_dqs_dn(5)';
NODE_NAME     U2 DH30
 '@S9S_MB_2U_LIB.S9S_MB_2U(SCH_1):PAGE27_I169@PURE_QUANTA.SOCKET4677_AZIF0045P001C01CS(CHIPS)':
 'DDR7_SB_DQS_DN5': CDS_PINID='DDR7_SB_DQS_DN5';
NODE_NAME     J15 249
 '@S9S_MB_2U_LIB.S9S_MB_2U(SCH_1):PAGE96_I178@PURE_QUANTA.SCONN288_ADR50017P130CC(CHIPS)':
 'DQS5_B_C||TDQS5_B_C': CDS_PINID='\dqs5_b_c||tdqs5_b_c\';
NODE_NAME     J16 249
 '@S9S_MB_2U_LIB.S9S_MB_2U(SCH_1):PAGE97_I178@PURE_QUANTA.SCONN288_ADR50017P087CC(CHIPS)':
 'DQS5_B_C||TDQS5_B_C': CDS_PINID='\dqs5_b_c||tdqs5_b_c\';
NET_NAME
'M_H_CPU0_SB_DQS_DN<6>'
 '@S9S_MB_2U_LIB.S9S_MB_2U(SCH_1):M_H_CPU0_SB_DQS_DN'<6>:
 C_SIGNAL='@s9s_mb_2u_lib.s9s_mb_2u(sch_1):m_h_cpu0_sb_dqs_dn(6)';
NODE_NAME     U2 DH24
 '@S9S_MB_2U_LIB.S9S_MB_2U(SCH_1):PAGE27_I169@PURE_QUANTA.SOCKET4677_AZIF0045P001C01CS(CHIPS)':
 'DDR7_SB_DQS_DN6': CDS_PINID='DDR7_SB_DQS_DN6';
NODE_NAME     J15 260
 '@S9S_MB_2U_LIB.S9S_MB_2U(SCH_1):PAGE96_I178@PURE_QUANTA.SCONN288_ADR50017P130CC(CHIPS)':
 'DQS6_B_C||TDQS6_B_C': CDS_PINID='\dqs6_b_c||tdqs6_b_c\';
NODE_NAME     J16 260
 '@S9S_MB_2U_LIB.S9S_MB_2U(SCH_1):PAGE97_I178@PURE_QUANTA.SCONN288_ADR50017P087CC(CHIPS)':
 'DQS6_B_C||TDQS6_B_C': CDS_PINID='\dqs6_b_c||tdqs6_b_c\';
NET_NAME
'M_H_CPU0_SB_DQS_DN<7>'
 '@S9S_MB_2U_LIB.S9S_MB_2U(SCH_1):M_H_CPU0_SB_DQS_DN'<7>:
 C_SIGNAL='@s9s_mb_2u_lib.s9s_mb_2u(sch_1):m_h_cpu0_sb_dqs_dn(7)';
NODE_NAME     U2 DR21
 '@S9S_MB_2U_LIB.S9S_MB_2U(SCH_1):PAGE27_I169@PURE_QUANTA.SOCKET4677_AZIF0045P001C01CS(CHIPS)':
 'DDR7_SB_DQS_DN7': CDS_PINID='DDR7_SB_DQS_DN7';
NODE_NAME     J15 271
 '@S9S_MB_2U_LIB.S9S_MB_2U(SCH_1):PAGE96_I178@PURE_QUANTA.SCONN288_ADR50017P130CC(CHIPS)':
 'DQS7_B_C||TDQS7_B_C': CDS_PINID='\dqs7_b_c||tdqs7_b_c\';
NODE_NAME     J16 271
 '@S9S_MB_2U_LIB.S9S_MB_2U(SCH_1):PAGE97_I178@PURE_QUANTA.SCONN288_ADR50017P087CC(CHIPS)':
 'DQS7_B_C||TDQS7_B_C': CDS_PINID='\dqs7_b_c||tdqs7_b_c\';
NET_NAME
'M_H_CPU0_SB_DQS_DN<8>'
 '@S9S_MB_2U_LIB.S9S_MB_2U(SCH_1):M_H_CPU0_SB_DQS_DN'<8>:
 C_SIGNAL='@s9s_mb_2u_lib.s9s_mb_2u(sch_1):m_h_cpu0_sb_dqs_dn(8)';
NODE_NAME     U2 DF18
 '@S9S_MB_2U_LIB.S9S_MB_2U(SCH_1):PAGE27_I169@PURE_QUANTA.SOCKET4677_AZIF0045P001C01CS(CHIPS)':
 'DDR7_SB_DQS_DN8': CDS_PINID='DDR7_SB_DQS_DN8';
NODE_NAME     J15 282
 '@S9S_MB_2U_LIB.S9S_MB_2U(SCH_1):PAGE96_I178@PURE_QUANTA.SCONN288_ADR50017P130CC(CHIPS)':
 'DQS8_B_C||TDQS8_B_C': CDS_PINID='\dqs8_b_c||tdqs8_b_c\';
NODE_NAME     J16 282
 '@S9S_MB_2U_LIB.S9S_MB_2U(SCH_1):PAGE97_I178@PURE_QUANTA.SCONN288_ADR50017P087CC(CHIPS)':
 'DQS8_B_C||TDQS8_B_C': CDS_PINID='\dqs8_b_c||tdqs8_b_c\';
NET_NAME
'M_H_CPU0_SB_DQS_DN<9>'
 '@S9S_MB_2U_LIB.S9S_MB_2U(SCH_1):M_H_CPU0_SB_DQS_DN'<9>:
 C_SIGNAL='@s9s_mb_2u_lib.s9s_mb_2u(sch_1):m_h_cpu0_sb_dqs_dn(9)';
NODE_NAME     U2 DD36
 '@S9S_MB_2U_LIB.S9S_MB_2U(SCH_1):PAGE27_I169@PURE_QUANTA.SOCKET4677_AZIF0045P001C01CS(CHIPS)':
 'DDR7_SB_DQS_DN9': CDS_PINID='DDR7_SB_DQS_DN9';
NODE_NAME     J15 94
 '@S9S_MB_2U_LIB.S9S_MB_2U(SCH_1):PAGE96_I178@PURE_QUANTA.SCONN288_ADR50017P130CC(CHIPS)':
 'DQS9_B_C||TDQS9_B_C': CDS_PINID='\dqs9_b_c||tdqs9_b_c\';
NODE_NAME     J16 94
 '@S9S_MB_2U_LIB.S9S_MB_2U(SCH_1):PAGE97_I178@PURE_QUANTA.SCONN288_ADR50017P087CC(CHIPS)':
 'DQS9_B_C||TDQS9_B_C': CDS_PINID='\dqs9_b_c||tdqs9_b_c\';
NET_NAME
'M_H_CPU0_SB_DQS_DP<0>'
 '@S9S_MB_2U_LIB.S9S_MB_2U(SCH_1):M_H_CPU0_SB_DQS_DP'<0>:
 C_SIGNAL='@s9s_mb_2u_lib.s9s_mb_2u(sch_1):m_h_cpu0_sb_dqs_dp(0)';
NODE_NAME     U2 DB30
 '@S9S_MB_2U_LIB.S9S_MB_2U(SCH_1):PAGE27_I169@PURE_QUANTA.SOCKET4677_AZIF0045P001C01CS(CHIPS)':
 'DDR7_SB_DQS_DP0': CDS_PINID='DDR7_SB_DQS_DP0';
NODE_NAME     J15 104
 '@S9S_MB_2U_LIB.S9S_MB_2U(SCH_1):PAGE96_I178@PURE_QUANTA.SCONN288_ADR50017P130CC(CHIPS)':
 'DQS0_B_T': CDS_PINID='DQS0_B_T';
NODE_NAME     J16 104
 '@S9S_MB_2U_LIB.S9S_MB_2U(SCH_1):PAGE97_I178@PURE_QUANTA.SCONN288_ADR50017P087CC(CHIPS)':
 'DQS0_B_T': CDS_PINID='DQS0_B_T';
NET_NAME
'M_H_CPU0_SB_DQS_DP<1>'
 '@S9S_MB_2U_LIB.S9S_MB_2U(SCH_1):M_H_CPU0_SB_DQS_DP'<1>:
 C_SIGNAL='@s9s_mb_2u_lib.s9s_mb_2u(sch_1):m_h_cpu0_sb_dqs_dp(1)';
NODE_NAME     U2 DB24
 '@S9S_MB_2U_LIB.S9S_MB_2U(SCH_1):PAGE27_I169@PURE_QUANTA.SOCKET4677_AZIF0045P001C01CS(CHIPS)':
 'DDR7_SB_DQS_DP1': CDS_PINID='DDR7_SB_DQS_DP1';
NODE_NAME     J15 115
 '@S9S_MB_2U_LIB.S9S_MB_2U(SCH_1):PAGE96_I178@PURE_QUANTA.SCONN288_ADR50017P130CC(CHIPS)':
 'DQS1_B_T': CDS_PINID='DQS1_B_T';
NODE_NAME     J16 115
 '@S9S_MB_2U_LIB.S9S_MB_2U(SCH_1):PAGE97_I178@PURE_QUANTA.SCONN288_ADR50017P087CC(CHIPS)':
 'DQS1_B_T': CDS_PINID='DQS1_B_T';
NET_NAME
'M_H_CPU0_SB_DQS_DP<2>'
 '@S9S_MB_2U_LIB.S9S_MB_2U(SCH_1):M_H_CPU0_SB_DQS_DP'<2>:
 C_SIGNAL='@s9s_mb_2u_lib.s9s_mb_2u(sch_1):m_h_cpu0_sb_dqs_dp(2)';
NODE_NAME     U2 DJ21
 '@S9S_MB_2U_LIB.S9S_MB_2U(SCH_1):PAGE27_I169@PURE_QUANTA.SOCKET4677_AZIF0045P001C01CS(CHIPS)':
 'DDR7_SB_DQS_DP2': CDS_PINID='DDR7_SB_DQS_DP2';
NODE_NAME     J15 126
 '@S9S_MB_2U_LIB.S9S_MB_2U(SCH_1):PAGE96_I178@PURE_QUANTA.SCONN288_ADR50017P130CC(CHIPS)':
 'DQS2_B_T': CDS_PINID='DQS2_B_T';
NODE_NAME     J16 126
 '@S9S_MB_2U_LIB.S9S_MB_2U(SCH_1):PAGE97_I178@PURE_QUANTA.SCONN288_ADR50017P087CC(CHIPS)':
 'DQS2_B_T': CDS_PINID='DQS2_B_T';
NET_NAME
'M_H_CPU0_SB_DQS_DP<3>'
 '@S9S_MB_2U_LIB.S9S_MB_2U(SCH_1):M_H_CPU0_SB_DQS_DP'<3>:
 C_SIGNAL='@s9s_mb_2u_lib.s9s_mb_2u(sch_1):m_h_cpu0_sb_dqs_dp(3)';
NODE_NAME     U2 DD18
 '@S9S_MB_2U_LIB.S9S_MB_2U(SCH_1):PAGE27_I169@PURE_QUANTA.SOCKET4677_AZIF0045P001C01CS(CHIPS)':
 'DDR7_SB_DQS_DP3': CDS_PINID='DDR7_SB_DQS_DP3';
NODE_NAME     J15 137
 '@S9S_MB_2U_LIB.S9S_MB_2U(SCH_1):PAGE96_I178@PURE_QUANTA.SCONN288_ADR50017P130CC(CHIPS)':
 'DQS3_B_T': CDS_PINID='DQS3_B_T';
NODE_NAME     J16 137
 '@S9S_MB_2U_LIB.S9S_MB_2U(SCH_1):PAGE97_I178@PURE_QUANTA.SCONN288_ADR50017P087CC(CHIPS)':
 'DQS3_B_T': CDS_PINID='DQS3_B_T';
NET_NAME
'M_H_CPU0_SB_DQS_DP<4>'
 '@S9S_MB_2U_LIB.S9S_MB_2U(SCH_1):M_H_CPU0_SB_DQS_DP'<4>:
 C_SIGNAL='@s9s_mb_2u_lib.s9s_mb_2u(sch_1):m_h_cpu0_sb_dqs_dp(4)';
NODE_NAME     U2 DF36
 '@S9S_MB_2U_LIB.S9S_MB_2U(SCH_1):PAGE27_I169@PURE_QUANTA.SOCKET4677_AZIF0045P001C01CS(CHIPS)':
 'DDR7_SB_DQS_DP4': CDS_PINID='DDR7_SB_DQS_DP4';
NODE_NAME     J15 239
 '@S9S_MB_2U_LIB.S9S_MB_2U(SCH_1):PAGE96_I178@PURE_QUANTA.SCONN288_ADR50017P130CC(CHIPS)':
 'DQS4_B_T': CDS_PINID='DQS4_B_T';
NODE_NAME     J16 239
 '@S9S_MB_2U_LIB.S9S_MB_2U(SCH_1):PAGE97_I178@PURE_QUANTA.SCONN288_ADR50017P087CC(CHIPS)':
 'DQS4_B_T': CDS_PINID='DQS4_B_T';
NET_NAME
'M_H_CPU0_SB_DQS_DP<5>'
 '@S9S_MB_2U_LIB.S9S_MB_2U(SCH_1):M_H_CPU0_SB_DQS_DP'<5>:
 C_SIGNAL='@s9s_mb_2u_lib.s9s_mb_2u(sch_1):m_h_cpu0_sb_dqs_dp(5)';
NODE_NAME     U2 DF30
 '@S9S_MB_2U_LIB.S9S_MB_2U(SCH_1):PAGE27_I169@PURE_QUANTA.SOCKET4677_AZIF0045P001C01CS(CHIPS)':
 'DDR7_SB_DQS_DP5': CDS_PINID='DDR7_SB_DQS_DP5';
NODE_NAME     J15 250
 '@S9S_MB_2U_LIB.S9S_MB_2U(SCH_1):PAGE96_I178@PURE_QUANTA.SCONN288_ADR50017P130CC(CHIPS)':
 'DQS5_B_T||TDQS5_B_T': CDS_PINID='\dqs5_b_t||tdqs5_b_t\';
NODE_NAME     J16 250
 '@S9S_MB_2U_LIB.S9S_MB_2U(SCH_1):PAGE97_I178@PURE_QUANTA.SCONN288_ADR50017P087CC(CHIPS)':
 'DQS5_B_T||TDQS5_B_T': CDS_PINID='\dqs5_b_t||tdqs5_b_t\';
NET_NAME
'M_H_CPU0_SB_DQS_DP<6>'
 '@S9S_MB_2U_LIB.S9S_MB_2U(SCH_1):M_H_CPU0_SB_DQS_DP'<6>:
 C_SIGNAL='@s9s_mb_2u_lib.s9s_mb_2u(sch_1):m_h_cpu0_sb_dqs_dp(6)';
NODE_NAME     U2 DF24
 '@S9S_MB_2U_LIB.S9S_MB_2U(SCH_1):PAGE27_I169@PURE_QUANTA.SOCKET4677_AZIF0045P001C01CS(CHIPS)':
 'DDR7_SB_DQS_DP6': CDS_PINID='DDR7_SB_DQS_DP6';
NODE_NAME     J15 261
 '@S9S_MB_2U_LIB.S9S_MB_2U(SCH_1):PAGE96_I178@PURE_QUANTA.SCONN288_ADR50017P130CC(CHIPS)':
 'DQS6_B_T||TDQS6_B_T': CDS_PINID='\dqs6_b_t||tdqs6_b_t\';
NODE_NAME     J16 261
 '@S9S_MB_2U_LIB.S9S_MB_2U(SCH_1):PAGE97_I178@PURE_QUANTA.SCONN288_ADR50017P087CC(CHIPS)':
 'DQS6_B_T||TDQS6_B_T': CDS_PINID='\dqs6_b_t||tdqs6_b_t\';
NET_NAME
'M_H_CPU0_SB_DQS_DP<7>'
 '@S9S_MB_2U_LIB.S9S_MB_2U(SCH_1):M_H_CPU0_SB_DQS_DP'<7>:
 C_SIGNAL='@s9s_mb_2u_lib.s9s_mb_2u(sch_1):m_h_cpu0_sb_dqs_dp(7)';
NODE_NAME     U2 DN21
 '@S9S_MB_2U_LIB.S9S_MB_2U(SCH_1):PAGE27_I169@PURE_QUANTA.SOCKET4677_AZIF0045P001C01CS(CHIPS)':
 'DDR7_SB_DQS_DP7': CDS_PINID='DDR7_SB_DQS_DP7';
NODE_NAME     J15 272
 '@S9S_MB_2U_LIB.S9S_MB_2U(SCH_1):PAGE96_I178@PURE_QUANTA.SCONN288_ADR50017P130CC(CHIPS)':
 'DQS7_B_T||TDQS7_B_T': CDS_PINID='\dqs7_b_t||tdqs7_b_t\';
NODE_NAME     J16 272
 '@S9S_MB_2U_LIB.S9S_MB_2U(SCH_1):PAGE97_I178@PURE_QUANTA.SCONN288_ADR50017P087CC(CHIPS)':
 'DQS7_B_T||TDQS7_B_T': CDS_PINID='\dqs7_b_t||tdqs7_b_t\';
NET_NAME
'M_H_CPU0_SB_DQS_DP<8>'
 '@S9S_MB_2U_LIB.S9S_MB_2U(SCH_1):M_H_CPU0_SB_DQS_DP'<8>:
 C_SIGNAL='@s9s_mb_2u_lib.s9s_mb_2u(sch_1):m_h_cpu0_sb_dqs_dp(8)';
NODE_NAME     U2 DH18
 '@S9S_MB_2U_LIB.S9S_MB_2U(SCH_1):PAGE27_I169@PURE_QUANTA.SOCKET4677_AZIF0045P001C01CS(CHIPS)':
 'DDR7_SB_DQS_DP8': CDS_PINID='DDR7_SB_DQS_DP8';
NODE_NAME     J15 283
 '@S9S_MB_2U_LIB.S9S_MB_2U(SCH_1):PAGE96_I178@PURE_QUANTA.SCONN288_ADR50017P130CC(CHIPS)':
 'DQS8_B_T||TDQS8_B_T': CDS_PINID='\dqs8_b_t||tdqs8_b_t\';
NODE_NAME     J16 283
 '@S9S_MB_2U_LIB.S9S_MB_2U(SCH_1):PAGE97_I178@PURE_QUANTA.SCONN288_ADR50017P087CC(CHIPS)':
 'DQS8_B_T||TDQS8_B_T': CDS_PINID='\dqs8_b_t||tdqs8_b_t\';
NET_NAME
'M_H_CPU0_SB_DQS_DP<9>'
 '@S9S_MB_2U_LIB.S9S_MB_2U(SCH_1):M_H_CPU0_SB_DQS_DP'<9>:
 C_SIGNAL='@s9s_mb_2u_lib.s9s_mb_2u(sch_1):m_h_cpu0_sb_dqs_dp(9)';
NODE_NAME     U2 DB36
 '@S9S_MB_2U_LIB.S9S_MB_2U(SCH_1):PAGE27_I169@PURE_QUANTA.SOCKET4677_AZIF0045P001C01CS(CHIPS)':
 'DDR7_SB_DQS_DP9': CDS_PINID='DDR7_SB_DQS_DP9';
NODE_NAME     J15 93
 '@S9S_MB_2U_LIB.S9S_MB_2U(SCH_1):PAGE96_I178@PURE_QUANTA.SCONN288_ADR50017P130CC(CHIPS)':
 'DQS9_B_T||TDQS9_B_T||DBI4_B_N': CDS_PINID='\dqs9_b_t||tdqs9_b_t||dbi4_b_n\';
NODE_NAME     J16 93
 '@S9S_MB_2U_LIB.S9S_MB_2U(SCH_1):PAGE97_I178@PURE_QUANTA.SCONN288_ADR50017P087CC(CHIPS)':
 'DQS9_B_T||TDQS9_B_T||DBI4_B_N': CDS_PINID='\dqs9_b_t||tdqs9_b_t||dbi4_b_n\';
NET_NAME
'M_H_CPU0_SB_PAR'
 '@S9S_MB_2U_LIB.S9S_MB_2U(SCH_1):M_H_CPU0_SB_PAR':
 C_SIGNAL='@s9s_mb_2u_lib.s9s_mb_2u(sch_1):m_h_cpu0_sb_par';
NODE_NAME     U2 DR39
 '@S9S_MB_2U_LIB.S9S_MB_2U(SCH_1):PAGE27_I169@PURE_QUANTA.SOCKET4677_AZIF0045P001C01CS(CHIPS)':
 'DDR7_SB_PAR': CDS_PINID='DDR7_SB_PAR';
NODE_NAME     J15 227
 '@S9S_MB_2U_LIB.S9S_MB_2U(SCH_1):PAGE96_I48@PURE_QUANTA.SCONN288_ADR50017P130CC(CHIPS)':
 'PAR_B': CDS_PINID='PAR_B';
NODE_NAME     J16 227
 '@S9S_MB_2U_LIB.S9S_MB_2U(SCH_1):PAGE97_I6@PURE_QUANTA.SCONN288_ADR50017P087CC(CHIPS)':
 'PAR_B': CDS_PINID='PAR_B';
NET_NAME
'M_H_CPU0_SB_RSP<0>'
 '@S9S_MB_2U_LIB.S9S_MB_2U(SCH_1):M_H_CPU0_SB_RSP'<0>:
 C_SIGNAL='@s9s_mb_2u_lib.s9s_mb_2u(sch_1):m_h_cpu0_sb_rsp(0)';
NODE_NAME     U2 EE48
 '@S9S_MB_2U_LIB.S9S_MB_2U(SCH_1):PAGE27_I169@PURE_QUANTA.SOCKET4677_AZIF0045P001C01CS(CHIPS)':
 'DDR7_B_RSP0': CDS_PINID='DDR7_B_RSP0';
NODE_NAME     J15 87
 '@S9S_MB_2U_LIB.S9S_MB_2U(SCH_1):PAGE96_I48@PURE_QUANTA.SCONN288_ADR50017P130CC(CHIPS)':
 'LBS||RSP_B_N': CDS_PINID='\lbs||rsp_b_n\';
NET_NAME
'M_H_CPU0_SB_RSP<1>'
 '@S9S_MB_2U_LIB.S9S_MB_2U(SCH_1):M_H_CPU0_SB_RSP'<1>:
 C_SIGNAL='@s9s_mb_2u_lib.s9s_mb_2u(sch_1):m_h_cpu0_sb_rsp(1)';
NODE_NAME     U2 ED47
 '@S9S_MB_2U_LIB.S9S_MB_2U(SCH_1):PAGE27_I169@PURE_QUANTA.SOCKET4677_AZIF0045P001C01CS(CHIPS)':
 'DDR7_B_RSP1': CDS_PINID='DDR7_B_RSP1';
NODE_NAME     J16 87
 '@S9S_MB_2U_LIB.S9S_MB_2U(SCH_1):PAGE97_I6@PURE_QUANTA.SCONN288_ADR50017P087CC(CHIPS)':
 'LBS||RSP_B_N': CDS_PINID='\lbs||rsp_b_n\';
NET_NAME
'M_H_CPU1_ALERT_N'
 '@S9S_MB_2U_LIB.S9S_MB_2U(SCH_1):M_H_CPU1_ALERT_N':
 C_SIGNAL='@s9s_mb_2u_lib.s9s_mb_2u(sch_1):m_h_cpu1_alert_n';
NODE_NAME     U1 CY51
 '@S9S_MB_2U_LIB.S9S_MB_2U(SCH_1):PAGE58_I20@PURE_QUANTA.SOCKET4677_AZIF0045P001C01CS(CHIPS)':
 'DDR7_ALERT_N': CDS_PINID='DDR7_ALERT_N';
NODE_NAME     J31 62
 '@S9S_MB_2U_LIB.S9S_MB_2U(SCH_1):PAGE112_I180@PURE_QUANTA.SCONN288_ADR50017P130CC(CHIPS)':
 'ALERT_N': CDS_PINID='ALERT_N';
NODE_NAME     J32 62
 '@S9S_MB_2U_LIB.S9S_MB_2U(SCH_1):PAGE113_I179@PURE_QUANTA.SCONN288_ADR50017P087CC(CHIPS)':
 'ALERT_N': CDS_PINID='ALERT_N';
NET_NAME
'M_H_CPU1_CLK_DN<0>'
 '@S9S_MB_2U_LIB.S9S_MB_2U(SCH_1):M_H_CPU1_CLK_DN'<0>:
 C_SIGNAL='@s9s_mb_2u_lib.s9s_mb_2u(sch_1):m_h_cpu1_clk_dn(0)';
NODE_NAME     U1 DH42
 '@S9S_MB_2U_LIB.S9S_MB_2U(SCH_1):PAGE58_I20@PURE_QUANTA.SOCKET4677_AZIF0045P001C01CS(CHIPS)':
 'DDR7_CLK_DN0': CDS_PINID='DDR7_CLK_DN0';
NODE_NAME     J31 218
 '@S9S_MB_2U_LIB.S9S_MB_2U(SCH_1):PAGE112_I180@PURE_QUANTA.SCONN288_ADR50017P130CC(CHIPS)':
 'CK_C': CDS_PINID='CK_C';
NET_NAME
'M_H_CPU1_CLK_DN<1>'
 '@S9S_MB_2U_LIB.S9S_MB_2U(SCH_1):M_H_CPU1_CLK_DN'<1>:
 C_SIGNAL='@s9s_mb_2u_lib.s9s_mb_2u(sch_1):m_h_cpu1_clk_dn(1)';
NODE_NAME     U1 DD42
 '@S9S_MB_2U_LIB.S9S_MB_2U(SCH_1):PAGE58_I20@PURE_QUANTA.SOCKET4677_AZIF0045P001C01CS(CHIPS)':
 'DDR7_CLK_DN1': CDS_PINID='DDR7_CLK_DN1';
NODE_NAME     J32 218
 '@S9S_MB_2U_LIB.S9S_MB_2U(SCH_1):PAGE113_I179@PURE_QUANTA.SCONN288_ADR50017P087CC(CHIPS)':
 'CK_C': CDS_PINID='CK_C';
NET_NAME
'M_H_CPU1_CLK_DP<0>'
 '@S9S_MB_2U_LIB.S9S_MB_2U(SCH_1):M_H_CPU1_CLK_DP'<0>:
 C_SIGNAL='@s9s_mb_2u_lib.s9s_mb_2u(sch_1):m_h_cpu1_clk_dp(0)';
NODE_NAME     U1 DF42
 '@S9S_MB_2U_LIB.S9S_MB_2U(SCH_1):PAGE58_I20@PURE_QUANTA.SOCKET4677_AZIF0045P001C01CS(CHIPS)':
 'DDR7_CLK_DP0': CDS_PINID='DDR7_CLK_DP0';
NODE_NAME     J31 217
 '@S9S_MB_2U_LIB.S9S_MB_2U(SCH_1):PAGE112_I180@PURE_QUANTA.SCONN288_ADR50017P130CC(CHIPS)':
 'CK_T': CDS_PINID='CK_T';
NET_NAME
'M_H_CPU1_CLK_DP<1>'
 '@S9S_MB_2U_LIB.S9S_MB_2U(SCH_1):M_H_CPU1_CLK_DP'<1>:
 C_SIGNAL='@s9s_mb_2u_lib.s9s_mb_2u(sch_1):m_h_cpu1_clk_dp(1)';
NODE_NAME     U1 DB42
 '@S9S_MB_2U_LIB.S9S_MB_2U(SCH_1):PAGE58_I20@PURE_QUANTA.SOCKET4677_AZIF0045P001C01CS(CHIPS)':
 'DDR7_CLK_DP1': CDS_PINID='DDR7_CLK_DP1';
NODE_NAME     J32 217
 '@S9S_MB_2U_LIB.S9S_MB_2U(SCH_1):PAGE113_I179@PURE_QUANTA.SCONN288_ADR50017P087CC(CHIPS)':
 'CK_T': CDS_PINID='CK_T';
NET_NAME
'M_H_CPU1_SA_CA<0>'
 '@S9S_MB_2U_LIB.S9S_MB_2U(SCH_1):M_H_CPU1_SA_CA'<0>:
 C_SIGNAL='@s9s_mb_2u_lib.s9s_mb_2u(sch_1):m_h_cpu1_sa_ca(0)';
NODE_NAME     U1 DB49
 '@S9S_MB_2U_LIB.S9S_MB_2U(SCH_1):PAGE58_I20@PURE_QUANTA.SOCKET4677_AZIF0045P001C01CS(CHIPS)':
 'DDR7_SA_CA0': CDS_PINID='DDR7_SA_CA0';
NODE_NAME     J31 66
 '@S9S_MB_2U_LIB.S9S_MB_2U(SCH_1):PAGE112_I180@PURE_QUANTA.SCONN288_ADR50017P130CC(CHIPS)':
 'CA0_A': CDS_PINID='CA0_A';
NODE_NAME     J32 66
 '@S9S_MB_2U_LIB.S9S_MB_2U(SCH_1):PAGE113_I179@PURE_QUANTA.SCONN288_ADR50017P087CC(CHIPS)':
 'CA0_A': CDS_PINID='CA0_A';
NET_NAME
'M_H_CPU1_SA_CA<1>'
 '@S9S_MB_2U_LIB.S9S_MB_2U(SCH_1):M_H_CPU1_SA_CA'<1>:
 C_SIGNAL='@s9s_mb_2u_lib.s9s_mb_2u(sch_1):m_h_cpu1_sa_ca(1)';
NODE_NAME     U1 DH49
 '@S9S_MB_2U_LIB.S9S_MB_2U(SCH_1):PAGE58_I20@PURE_QUANTA.SOCKET4677_AZIF0045P001C01CS(CHIPS)':
 'DDR7_SA_CA1': CDS_PINID='DDR7_SA_CA1';
NODE_NAME     J31 211
 '@S9S_MB_2U_LIB.S9S_MB_2U(SCH_1):PAGE112_I180@PURE_QUANTA.SCONN288_ADR50017P130CC(CHIPS)':
 'CA1_A': CDS_PINID='CA1_A';
NODE_NAME     J32 211
 '@S9S_MB_2U_LIB.S9S_MB_2U(SCH_1):PAGE113_I179@PURE_QUANTA.SCONN288_ADR50017P087CC(CHIPS)':
 'CA1_A': CDS_PINID='CA1_A';
NET_NAME
'M_H_CPU1_SA_CA<2>'
 '@S9S_MB_2U_LIB.S9S_MB_2U(SCH_1):M_H_CPU1_SA_CA'<2>:
 C_SIGNAL='@s9s_mb_2u_lib.s9s_mb_2u(sch_1):m_h_cpu1_sa_ca(2)';
NODE_NAME     U1 DC48
 '@S9S_MB_2U_LIB.S9S_MB_2U(SCH_1):PAGE58_I20@PURE_QUANTA.SOCKET4677_AZIF0045P001C01CS(CHIPS)':
 'DDR7_SA_CA2': CDS_PINID='DDR7_SA_CA2';
NODE_NAME     J31 68
 '@S9S_MB_2U_LIB.S9S_MB_2U(SCH_1):PAGE112_I180@PURE_QUANTA.SCONN288_ADR50017P130CC(CHIPS)':
 'CA2_A': CDS_PINID='CA2_A';
NODE_NAME     J32 68
 '@S9S_MB_2U_LIB.S9S_MB_2U(SCH_1):PAGE113_I179@PURE_QUANTA.SCONN288_ADR50017P087CC(CHIPS)':
 'CA2_A': CDS_PINID='CA2_A';
NET_NAME
'M_H_CPU1_SA_CA<3>'
 '@S9S_MB_2U_LIB.S9S_MB_2U(SCH_1):M_H_CPU1_SA_CA'<3>:
 C_SIGNAL='@s9s_mb_2u_lib.s9s_mb_2u(sch_1):m_h_cpu1_sa_ca(3)';
NODE_NAME     U1 DG48
 '@S9S_MB_2U_LIB.S9S_MB_2U(SCH_1):PAGE58_I20@PURE_QUANTA.SOCKET4677_AZIF0045P001C01CS(CHIPS)':
 'DDR7_SA_CA3': CDS_PINID='DDR7_SA_CA3';
NODE_NAME     J31 213
 '@S9S_MB_2U_LIB.S9S_MB_2U(SCH_1):PAGE112_I180@PURE_QUANTA.SCONN288_ADR50017P130CC(CHIPS)':
 'CA3_A': CDS_PINID='CA3_A';
NODE_NAME     J32 213
 '@S9S_MB_2U_LIB.S9S_MB_2U(SCH_1):PAGE113_I179@PURE_QUANTA.SCONN288_ADR50017P087CC(CHIPS)':
 'CA3_A': CDS_PINID='CA3_A';
NET_NAME
'M_H_CPU1_SA_CA<4>'
 '@S9S_MB_2U_LIB.S9S_MB_2U(SCH_1):M_H_CPU1_SA_CA'<4>:
 C_SIGNAL='@s9s_mb_2u_lib.s9s_mb_2u(sch_1):m_h_cpu1_sa_ca(4)';
NODE_NAME     U1 DD47
 '@S9S_MB_2U_LIB.S9S_MB_2U(SCH_1):PAGE58_I20@PURE_QUANTA.SOCKET4677_AZIF0045P001C01CS(CHIPS)':
 'DDR7_SA_CA4': CDS_PINID='DDR7_SA_CA4';
NODE_NAME     J31 70
 '@S9S_MB_2U_LIB.S9S_MB_2U(SCH_1):PAGE112_I180@PURE_QUANTA.SCONN288_ADR50017P130CC(CHIPS)':
 'CA4_A': CDS_PINID='CA4_A';
NODE_NAME     J32 70
 '@S9S_MB_2U_LIB.S9S_MB_2U(SCH_1):PAGE113_I179@PURE_QUANTA.SCONN288_ADR50017P087CC(CHIPS)':
 'CA4_A': CDS_PINID='CA4_A';
NET_NAME
'M_H_CPU1_SA_CA<5>'
 '@S9S_MB_2U_LIB.S9S_MB_2U(SCH_1):M_H_CPU1_SA_CA'<5>:
 C_SIGNAL='@s9s_mb_2u_lib.s9s_mb_2u(sch_1):m_h_cpu1_sa_ca(5)';
NODE_NAME     U1 DF47
 '@S9S_MB_2U_LIB.S9S_MB_2U(SCH_1):PAGE58_I20@PURE_QUANTA.SOCKET4677_AZIF0045P001C01CS(CHIPS)':
 'DDR7_SA_CA5': CDS_PINID='DDR7_SA_CA5';
NODE_NAME     J31 215
 '@S9S_MB_2U_LIB.S9S_MB_2U(SCH_1):PAGE112_I180@PURE_QUANTA.SCONN288_ADR50017P130CC(CHIPS)':
 'CA5_A': CDS_PINID='CA5_A';
NODE_NAME     J32 215
 '@S9S_MB_2U_LIB.S9S_MB_2U(SCH_1):PAGE113_I179@PURE_QUANTA.SCONN288_ADR50017P087CC(CHIPS)':
 'CA5_A': CDS_PINID='CA5_A';
NET_NAME
'M_H_CPU1_SA_CA<6>'
 '@S9S_MB_2U_LIB.S9S_MB_2U(SCH_1):M_H_CPU1_SA_CA'<6>:
 C_SIGNAL='@s9s_mb_2u_lib.s9s_mb_2u(sch_1):m_h_cpu1_sa_ca(6)';
NODE_NAME     U1 DC41
 '@S9S_MB_2U_LIB.S9S_MB_2U(SCH_1):PAGE58_I20@PURE_QUANTA.SOCKET4677_AZIF0045P001C01CS(CHIPS)':
 'DDR7_SA_CA6': CDS_PINID='DDR7_SA_CA6';
NODE_NAME     J31 72
 '@S9S_MB_2U_LIB.S9S_MB_2U(SCH_1):PAGE112_I180@PURE_QUANTA.SCONN288_ADR50017P130CC(CHIPS)':
 'CA6_A': CDS_PINID='CA6_A';
NODE_NAME     J32 72
 '@S9S_MB_2U_LIB.S9S_MB_2U(SCH_1):PAGE113_I179@PURE_QUANTA.SCONN288_ADR50017P087CC(CHIPS)':
 'CA6_A': CDS_PINID='CA6_A';
NET_NAME
'M_H_CPU1_SA_CB<0>'
 '@S9S_MB_2U_LIB.S9S_MB_2U(SCH_1):M_H_CPU1_SA_CB'<0>:
 C_SIGNAL='@s9s_mb_2u_lib.s9s_mb_2u(sch_1):m_h_cpu1_sa_cb(0)';
NODE_NAME     U1 DD57
 '@S9S_MB_2U_LIB.S9S_MB_2U(SCH_1):PAGE58_I20@PURE_QUANTA.SOCKET4677_AZIF0045P001C01CS(CHIPS)':
 'DDR7_SA_ECC0': CDS_PINID='DDR7_SA_ECC0';
NODE_NAME     J31 51
 '@S9S_MB_2U_LIB.S9S_MB_2U(SCH_1):PAGE112_I180@PURE_QUANTA.SCONN288_ADR50017P130CC(CHIPS)':
 'CB0_A': CDS_PINID='CB0_A';
NODE_NAME     J32 51
 '@S9S_MB_2U_LIB.S9S_MB_2U(SCH_1):PAGE113_I179@PURE_QUANTA.SCONN288_ADR50017P087CC(CHIPS)':
 'CB0_A': CDS_PINID='CB0_A';
NET_NAME
'M_H_CPU1_SA_CB<1>'
 '@S9S_MB_2U_LIB.S9S_MB_2U(SCH_1):M_H_CPU1_SA_CB'<1>:
 C_SIGNAL='@s9s_mb_2u_lib.s9s_mb_2u(sch_1):m_h_cpu1_sa_cb(1)';
NODE_NAME     U1 DC56
 '@S9S_MB_2U_LIB.S9S_MB_2U(SCH_1):PAGE58_I20@PURE_QUANTA.SOCKET4677_AZIF0045P001C01CS(CHIPS)':
 'DDR7_SA_ECC1': CDS_PINID='DDR7_SA_ECC1';
NODE_NAME     J31 53
 '@S9S_MB_2U_LIB.S9S_MB_2U(SCH_1):PAGE112_I180@PURE_QUANTA.SCONN288_ADR50017P130CC(CHIPS)':
 'CB1_A': CDS_PINID='CB1_A';
NODE_NAME     J32 53
 '@S9S_MB_2U_LIB.S9S_MB_2U(SCH_1):PAGE113_I179@PURE_QUANTA.SCONN288_ADR50017P087CC(CHIPS)':
 'CB1_A': CDS_PINID='CB1_A';
NET_NAME
'M_H_CPU1_SA_CB<2>'
 '@S9S_MB_2U_LIB.S9S_MB_2U(SCH_1):M_H_CPU1_SA_CB'<2>:
 C_SIGNAL='@s9s_mb_2u_lib.s9s_mb_2u(sch_1):m_h_cpu1_sa_cb(2)';
NODE_NAME     U1 DF57
 '@S9S_MB_2U_LIB.S9S_MB_2U(SCH_1):PAGE58_I20@PURE_QUANTA.SOCKET4677_AZIF0045P001C01CS(CHIPS)':
 'DDR7_SA_ECC2': CDS_PINID='DDR7_SA_ECC2';
NODE_NAME     J31 196
 '@S9S_MB_2U_LIB.S9S_MB_2U(SCH_1):PAGE112_I180@PURE_QUANTA.SCONN288_ADR50017P130CC(CHIPS)':
 'CB2_A': CDS_PINID='CB2_A';
NODE_NAME     J32 196
 '@S9S_MB_2U_LIB.S9S_MB_2U(SCH_1):PAGE113_I179@PURE_QUANTA.SCONN288_ADR50017P087CC(CHIPS)':
 'CB2_A': CDS_PINID='CB2_A';
NET_NAME
'M_H_CPU1_SA_CB<3>'
 '@S9S_MB_2U_LIB.S9S_MB_2U(SCH_1):M_H_CPU1_SA_CB'<3>:
 C_SIGNAL='@s9s_mb_2u_lib.s9s_mb_2u(sch_1):m_h_cpu1_sa_cb(3)';
NODE_NAME     U1 DG56
 '@S9S_MB_2U_LIB.S9S_MB_2U(SCH_1):PAGE58_I20@PURE_QUANTA.SOCKET4677_AZIF0045P001C01CS(CHIPS)':
 'DDR7_SA_ECC3': CDS_PINID='DDR7_SA_ECC3';
NODE_NAME     J31 198
 '@S9S_MB_2U_LIB.S9S_MB_2U(SCH_1):PAGE112_I180@PURE_QUANTA.SCONN288_ADR50017P130CC(CHIPS)':
 'CB3_A': CDS_PINID='CB3_A';
NODE_NAME     J32 198
 '@S9S_MB_2U_LIB.S9S_MB_2U(SCH_1):PAGE113_I179@PURE_QUANTA.SCONN288_ADR50017P087CC(CHIPS)':
 'CB3_A': CDS_PINID='CB3_A';
NET_NAME
'M_H_CPU1_SA_CB<4>'
 '@S9S_MB_2U_LIB.S9S_MB_2U(SCH_1):M_H_CPU1_SA_CB'<4>:
 C_SIGNAL='@s9s_mb_2u_lib.s9s_mb_2u(sch_1):m_h_cpu1_sa_cb(4)';
NODE_NAME     U1 DC54
 '@S9S_MB_2U_LIB.S9S_MB_2U(SCH_1):PAGE58_I20@PURE_QUANTA.SOCKET4677_AZIF0045P001C01CS(CHIPS)':
 'DDR7_SA_ECC4': CDS_PINID='DDR7_SA_ECC4';
NODE_NAME     J31 58
 '@S9S_MB_2U_LIB.S9S_MB_2U(SCH_1):PAGE112_I180@PURE_QUANTA.SCONN288_ADR50017P130CC(CHIPS)':
 'CB4_A': CDS_PINID='CB4_A';
NODE_NAME     J32 58
 '@S9S_MB_2U_LIB.S9S_MB_2U(SCH_1):PAGE113_I179@PURE_QUANTA.SCONN288_ADR50017P087CC(CHIPS)':
 'CB4_A': CDS_PINID='CB4_A';
NET_NAME
'M_H_CPU1_SA_CB<5>'
 '@S9S_MB_2U_LIB.S9S_MB_2U(SCH_1):M_H_CPU1_SA_CB'<5>:
 C_SIGNAL='@s9s_mb_2u_lib.s9s_mb_2u(sch_1):m_h_cpu1_sa_cb(5)';
NODE_NAME     U1 DD53
 '@S9S_MB_2U_LIB.S9S_MB_2U(SCH_1):PAGE58_I20@PURE_QUANTA.SOCKET4677_AZIF0045P001C01CS(CHIPS)':
 'DDR7_SA_ECC5': CDS_PINID='DDR7_SA_ECC5';
NODE_NAME     J31 60
 '@S9S_MB_2U_LIB.S9S_MB_2U(SCH_1):PAGE112_I180@PURE_QUANTA.SCONN288_ADR50017P130CC(CHIPS)':
 'CB5_A': CDS_PINID='CB5_A';
NODE_NAME     J32 60
 '@S9S_MB_2U_LIB.S9S_MB_2U(SCH_1):PAGE113_I179@PURE_QUANTA.SCONN288_ADR50017P087CC(CHIPS)':
 'CB5_A': CDS_PINID='CB5_A';
NET_NAME
'M_H_CPU1_SA_CB<6>'
 '@S9S_MB_2U_LIB.S9S_MB_2U(SCH_1):M_H_CPU1_SA_CB'<6>:
 C_SIGNAL='@s9s_mb_2u_lib.s9s_mb_2u(sch_1):m_h_cpu1_sa_cb(6)';
NODE_NAME     U1 DG54
 '@S9S_MB_2U_LIB.S9S_MB_2U(SCH_1):PAGE58_I20@PURE_QUANTA.SOCKET4677_AZIF0045P001C01CS(CHIPS)':
 'DDR7_SA_ECC6': CDS_PINID='DDR7_SA_ECC6';
NODE_NAME     J31 203
 '@S9S_MB_2U_LIB.S9S_MB_2U(SCH_1):PAGE112_I180@PURE_QUANTA.SCONN288_ADR50017P130CC(CHIPS)':
 'CB6_A': CDS_PINID='CB6_A';
NODE_NAME     J32 203
 '@S9S_MB_2U_LIB.S9S_MB_2U(SCH_1):PAGE113_I179@PURE_QUANTA.SCONN288_ADR50017P087CC(CHIPS)':
 'CB6_A': CDS_PINID='CB6_A';
NET_NAME
'M_H_CPU1_SA_CB<7>'
 '@S9S_MB_2U_LIB.S9S_MB_2U(SCH_1):M_H_CPU1_SA_CB'<7>:
 C_SIGNAL='@s9s_mb_2u_lib.s9s_mb_2u(sch_1):m_h_cpu1_sa_cb(7)';
NODE_NAME     U1 DF53
 '@S9S_MB_2U_LIB.S9S_MB_2U(SCH_1):PAGE58_I20@PURE_QUANTA.SOCKET4677_AZIF0045P001C01CS(CHIPS)':
 'DDR7_SA_ECC7': CDS_PINID='DDR7_SA_ECC7';
NODE_NAME     J31 205
 '@S9S_MB_2U_LIB.S9S_MB_2U(SCH_1):PAGE112_I180@PURE_QUANTA.SCONN288_ADR50017P130CC(CHIPS)':
 'CB7_A': CDS_PINID='CB7_A';
NODE_NAME     J32 205
 '@S9S_MB_2U_LIB.S9S_MB_2U(SCH_1):PAGE113_I179@PURE_QUANTA.SCONN288_ADR50017P087CC(CHIPS)':
 'CB7_A': CDS_PINID='CB7_A';
NET_NAME
'M_H_CPU1_SA_CS_N<0>'
 '@S9S_MB_2U_LIB.S9S_MB_2U(SCH_1):M_H_CPU1_SA_CS_N'<0>:
 C_SIGNAL='@s9s_mb_2u_lib.s9s_mb_2u(sch_1):m_h_cpu1_sa_cs_n(0)';
NODE_NAME     U1 DF51
 '@S9S_MB_2U_LIB.S9S_MB_2U(SCH_1):PAGE58_I20@PURE_QUANTA.SOCKET4677_AZIF0045P001C01CS(CHIPS)':
 'DDR7_SA_CS_N0': CDS_PINID='DDR7_SA_CS_N0';
NODE_NAME     J31 64
 '@S9S_MB_2U_LIB.S9S_MB_2U(SCH_1):PAGE112_I180@PURE_QUANTA.SCONN288_ADR50017P130CC(CHIPS)':
 'CS0_A_N': CDS_PINID='CS0_A_N';
NET_NAME
'M_H_CPU1_SA_CS_N<1>'
 '@S9S_MB_2U_LIB.S9S_MB_2U(SCH_1):M_H_CPU1_SA_CS_N'<1>:
 C_SIGNAL='@s9s_mb_2u_lib.s9s_mb_2u(sch_1):m_h_cpu1_sa_cs_n(1)';
NODE_NAME     U1 DG50
 '@S9S_MB_2U_LIB.S9S_MB_2U(SCH_1):PAGE58_I20@PURE_QUANTA.SOCKET4677_AZIF0045P001C01CS(CHIPS)':
 'DDR7_SA_CS_N1': CDS_PINID='DDR7_SA_CS_N1';
NODE_NAME     J31 209
 '@S9S_MB_2U_LIB.S9S_MB_2U(SCH_1):PAGE112_I180@PURE_QUANTA.SCONN288_ADR50017P130CC(CHIPS)':
 'CS1_A_N': CDS_PINID='CS1_A_N';
NET_NAME
'M_H_CPU1_SA_CS_N<2>'
 '@S9S_MB_2U_LIB.S9S_MB_2U(SCH_1):M_H_CPU1_SA_CS_N'<2>:
 C_SIGNAL='@s9s_mb_2u_lib.s9s_mb_2u(sch_1):m_h_cpu1_sa_cs_n(2)';
NODE_NAME     U1 DD51
 '@S9S_MB_2U_LIB.S9S_MB_2U(SCH_1):PAGE58_I20@PURE_QUANTA.SOCKET4677_AZIF0045P001C01CS(CHIPS)':
 'DDR7_SA_CS_N2': CDS_PINID='DDR7_SA_CS_N2';
NODE_NAME     J32 64
 '@S9S_MB_2U_LIB.S9S_MB_2U(SCH_1):PAGE113_I179@PURE_QUANTA.SCONN288_ADR50017P087CC(CHIPS)':
 'CS0_A_N': CDS_PINID='CS0_A_N';
NET_NAME
'M_H_CPU1_SA_CS_N<3>'
 '@S9S_MB_2U_LIB.S9S_MB_2U(SCH_1):M_H_CPU1_SA_CS_N'<3>:
 C_SIGNAL='@s9s_mb_2u_lib.s9s_mb_2u(sch_1):m_h_cpu1_sa_cs_n(3)';
NODE_NAME     U1 DC50
 '@S9S_MB_2U_LIB.S9S_MB_2U(SCH_1):PAGE58_I20@PURE_QUANTA.SOCKET4677_AZIF0045P001C01CS(CHIPS)':
 'DDR7_SA_CS_N3': CDS_PINID='DDR7_SA_CS_N3';
NODE_NAME     J32 209
 '@S9S_MB_2U_LIB.S9S_MB_2U(SCH_1):PAGE113_I179@PURE_QUANTA.SCONN288_ADR50017P087CC(CHIPS)':
 'CS1_A_N': CDS_PINID='CS1_A_N';
NET_NAME
'M_H_CPU1_SA_DQ<0>'
 '@S9S_MB_2U_LIB.S9S_MB_2U(SCH_1):M_H_CPU1_SA_DQ'<0>:
 C_SIGNAL='@s9s_mb_2u_lib.s9s_mb_2u(sch_1):m_h_cpu1_sa_dq(0)';
NODE_NAME     U1 DY79
 '@S9S_MB_2U_LIB.S9S_MB_2U(SCH_1):PAGE58_I20@PURE_QUANTA.SOCKET4677_AZIF0045P001C01CS(CHIPS)':
 'DDR7_SA_DQ0': CDS_PINID='DDR7_SA_DQ0';
NODE_NAME     J31 7
 '@S9S_MB_2U_LIB.S9S_MB_2U(SCH_1):PAGE112_I180@PURE_QUANTA.SCONN288_ADR50017P130CC(CHIPS)':
 'DQ0_A': CDS_PINID='DQ0_A';
NODE_NAME     J32 7
 '@S9S_MB_2U_LIB.S9S_MB_2U(SCH_1):PAGE113_I179@PURE_QUANTA.SCONN288_ADR50017P087CC(CHIPS)':
 'DQ0_A': CDS_PINID='DQ0_A';
NET_NAME
'M_H_CPU1_SA_DQ<10>'
 '@S9S_MB_2U_LIB.S9S_MB_2U(SCH_1):M_H_CPU1_SA_DQ'<10>:
 C_SIGNAL='@s9s_mb_2u_lib.s9s_mb_2u(sch_1):m_h_cpu1_sa_dq(10)';
NODE_NAME     U1 DF75
 '@S9S_MB_2U_LIB.S9S_MB_2U(SCH_1):PAGE58_I20@PURE_QUANTA.SOCKET4677_AZIF0045P001C01CS(CHIPS)':
 'DDR7_SA_DQ10': CDS_PINID='DDR7_SA_DQ10';
NODE_NAME     J31 163
 '@S9S_MB_2U_LIB.S9S_MB_2U(SCH_1):PAGE112_I180@PURE_QUANTA.SCONN288_ADR50017P130CC(CHIPS)':
 'DQ10_A': CDS_PINID='DQ10_A';
NODE_NAME     J32 163
 '@S9S_MB_2U_LIB.S9S_MB_2U(SCH_1):PAGE113_I179@PURE_QUANTA.SCONN288_ADR50017P087CC(CHIPS)':
 'DQ10_A': CDS_PINID='DQ10_A';
NET_NAME
'M_H_CPU1_SA_DQ<11>'
 '@S9S_MB_2U_LIB.S9S_MB_2U(SCH_1):M_H_CPU1_SA_DQ'<11>:
 C_SIGNAL='@s9s_mb_2u_lib.s9s_mb_2u(sch_1):m_h_cpu1_sa_dq(11)';
NODE_NAME     U1 DG74
 '@S9S_MB_2U_LIB.S9S_MB_2U(SCH_1):PAGE58_I20@PURE_QUANTA.SOCKET4677_AZIF0045P001C01CS(CHIPS)':
 'DDR7_SA_DQ11': CDS_PINID='DDR7_SA_DQ11';
NODE_NAME     J31 165
 '@S9S_MB_2U_LIB.S9S_MB_2U(SCH_1):PAGE112_I180@PURE_QUANTA.SCONN288_ADR50017P130CC(CHIPS)':
 'DQ11_A': CDS_PINID='DQ11_A';
NODE_NAME     J32 165
 '@S9S_MB_2U_LIB.S9S_MB_2U(SCH_1):PAGE113_I179@PURE_QUANTA.SCONN288_ADR50017P087CC(CHIPS)':
 'DQ11_A': CDS_PINID='DQ11_A';
NET_NAME
'M_H_CPU1_SA_DQ<12>'
 '@S9S_MB_2U_LIB.S9S_MB_2U(SCH_1):M_H_CPU1_SA_DQ'<12>:
 C_SIGNAL='@s9s_mb_2u_lib.s9s_mb_2u(sch_1):m_h_cpu1_sa_dq(12)';
NODE_NAME     U1 DC72
 '@S9S_MB_2U_LIB.S9S_MB_2U(SCH_1):PAGE58_I20@PURE_QUANTA.SOCKET4677_AZIF0045P001C01CS(CHIPS)':
 'DDR7_SA_DQ12': CDS_PINID='DDR7_SA_DQ12';
NODE_NAME     J31 25
 '@S9S_MB_2U_LIB.S9S_MB_2U(SCH_1):PAGE112_I180@PURE_QUANTA.SCONN288_ADR50017P130CC(CHIPS)':
 'DQ12_A': CDS_PINID='DQ12_A';
NODE_NAME     J32 25
 '@S9S_MB_2U_LIB.S9S_MB_2U(SCH_1):PAGE113_I179@PURE_QUANTA.SCONN288_ADR50017P087CC(CHIPS)':
 'DQ12_A': CDS_PINID='DQ12_A';
NET_NAME
'M_H_CPU1_SA_DQ<13>'
 '@S9S_MB_2U_LIB.S9S_MB_2U(SCH_1):M_H_CPU1_SA_DQ'<13>:
 C_SIGNAL='@s9s_mb_2u_lib.s9s_mb_2u(sch_1):m_h_cpu1_sa_dq(13)';
NODE_NAME     U1 DD71
 '@S9S_MB_2U_LIB.S9S_MB_2U(SCH_1):PAGE58_I20@PURE_QUANTA.SOCKET4677_AZIF0045P001C01CS(CHIPS)':
 'DDR7_SA_DQ13': CDS_PINID='DDR7_SA_DQ13';
NODE_NAME     J31 27
 '@S9S_MB_2U_LIB.S9S_MB_2U(SCH_1):PAGE112_I180@PURE_QUANTA.SCONN288_ADR50017P130CC(CHIPS)':
 'DQ13_A': CDS_PINID='DQ13_A';
NODE_NAME     J32 27
 '@S9S_MB_2U_LIB.S9S_MB_2U(SCH_1):PAGE113_I179@PURE_QUANTA.SCONN288_ADR50017P087CC(CHIPS)':
 'DQ13_A': CDS_PINID='DQ13_A';
NET_NAME
'M_H_CPU1_SA_DQ<14>'
 '@S9S_MB_2U_LIB.S9S_MB_2U(SCH_1):M_H_CPU1_SA_DQ'<14>:
 C_SIGNAL='@s9s_mb_2u_lib.s9s_mb_2u(sch_1):m_h_cpu1_sa_dq(14)';
NODE_NAME     U1 DG72
 '@S9S_MB_2U_LIB.S9S_MB_2U(SCH_1):PAGE58_I20@PURE_QUANTA.SOCKET4677_AZIF0045P001C01CS(CHIPS)':
 'DDR7_SA_DQ14': CDS_PINID='DDR7_SA_DQ14';
NODE_NAME     J31 170
 '@S9S_MB_2U_LIB.S9S_MB_2U(SCH_1):PAGE112_I180@PURE_QUANTA.SCONN288_ADR50017P130CC(CHIPS)':
 'DQ14_A': CDS_PINID='DQ14_A';
NODE_NAME     J32 170
 '@S9S_MB_2U_LIB.S9S_MB_2U(SCH_1):PAGE113_I179@PURE_QUANTA.SCONN288_ADR50017P087CC(CHIPS)':
 'DQ14_A': CDS_PINID='DQ14_A';
NET_NAME
'M_H_CPU1_SA_DQ<15>'
 '@S9S_MB_2U_LIB.S9S_MB_2U(SCH_1):M_H_CPU1_SA_DQ'<15>:
 C_SIGNAL='@s9s_mb_2u_lib.s9s_mb_2u(sch_1):m_h_cpu1_sa_dq(15)';
NODE_NAME     U1 DF71
 '@S9S_MB_2U_LIB.S9S_MB_2U(SCH_1):PAGE58_I20@PURE_QUANTA.SOCKET4677_AZIF0045P001C01CS(CHIPS)':
 'DDR7_SA_DQ15': CDS_PINID='DDR7_SA_DQ15';
NODE_NAME     J31 172
 '@S9S_MB_2U_LIB.S9S_MB_2U(SCH_1):PAGE112_I180@PURE_QUANTA.SCONN288_ADR50017P130CC(CHIPS)':
 'DQ15_A': CDS_PINID='DQ15_A';
NODE_NAME     J32 172
 '@S9S_MB_2U_LIB.S9S_MB_2U(SCH_1):PAGE113_I179@PURE_QUANTA.SCONN288_ADR50017P087CC(CHIPS)':
 'DQ15_A': CDS_PINID='DQ15_A';
NET_NAME
'M_H_CPU1_SA_DQ<16>'
 '@S9S_MB_2U_LIB.S9S_MB_2U(SCH_1):M_H_CPU1_SA_DQ'<16>:
 C_SIGNAL='@s9s_mb_2u_lib.s9s_mb_2u(sch_1):m_h_cpu1_sa_dq(16)';
NODE_NAME     U1 DD69
 '@S9S_MB_2U_LIB.S9S_MB_2U(SCH_1):PAGE58_I20@PURE_QUANTA.SOCKET4677_AZIF0045P001C01CS(CHIPS)':
 'DDR7_SA_DQ16': CDS_PINID='DDR7_SA_DQ16';
NODE_NAME     J31 29
 '@S9S_MB_2U_LIB.S9S_MB_2U(SCH_1):PAGE112_I180@PURE_QUANTA.SCONN288_ADR50017P130CC(CHIPS)':
 'DQ16_A': CDS_PINID='DQ16_A';
NODE_NAME     J32 29
 '@S9S_MB_2U_LIB.S9S_MB_2U(SCH_1):PAGE113_I179@PURE_QUANTA.SCONN288_ADR50017P087CC(CHIPS)':
 'DQ16_A': CDS_PINID='DQ16_A';
NET_NAME
'M_H_CPU1_SA_DQ<17>'
 '@S9S_MB_2U_LIB.S9S_MB_2U(SCH_1):M_H_CPU1_SA_DQ'<17>:
 C_SIGNAL='@s9s_mb_2u_lib.s9s_mb_2u(sch_1):m_h_cpu1_sa_dq(17)';
NODE_NAME     U1 DC68
 '@S9S_MB_2U_LIB.S9S_MB_2U(SCH_1):PAGE58_I20@PURE_QUANTA.SOCKET4677_AZIF0045P001C01CS(CHIPS)':
 'DDR7_SA_DQ17': CDS_PINID='DDR7_SA_DQ17';
NODE_NAME     J31 31
 '@S9S_MB_2U_LIB.S9S_MB_2U(SCH_1):PAGE112_I180@PURE_QUANTA.SCONN288_ADR50017P130CC(CHIPS)':
 'DQ17_A': CDS_PINID='DQ17_A';
NODE_NAME     J32 31
 '@S9S_MB_2U_LIB.S9S_MB_2U(SCH_1):PAGE113_I179@PURE_QUANTA.SCONN288_ADR50017P087CC(CHIPS)':
 'DQ17_A': CDS_PINID='DQ17_A';
NET_NAME
'M_H_CPU1_SA_DQ<18>'
 '@S9S_MB_2U_LIB.S9S_MB_2U(SCH_1):M_H_CPU1_SA_DQ'<18>:
 C_SIGNAL='@s9s_mb_2u_lib.s9s_mb_2u(sch_1):m_h_cpu1_sa_dq(18)';
NODE_NAME     U1 DF69
 '@S9S_MB_2U_LIB.S9S_MB_2U(SCH_1):PAGE58_I20@PURE_QUANTA.SOCKET4677_AZIF0045P001C01CS(CHIPS)':
 'DDR7_SA_DQ18': CDS_PINID='DDR7_SA_DQ18';
NODE_NAME     J31 174
 '@S9S_MB_2U_LIB.S9S_MB_2U(SCH_1):PAGE112_I180@PURE_QUANTA.SCONN288_ADR50017P130CC(CHIPS)':
 'DQ18_A': CDS_PINID='DQ18_A';
NODE_NAME     J32 174
 '@S9S_MB_2U_LIB.S9S_MB_2U(SCH_1):PAGE113_I179@PURE_QUANTA.SCONN288_ADR50017P087CC(CHIPS)':
 'DQ18_A': CDS_PINID='DQ18_A';
NET_NAME
'M_H_CPU1_SA_DQ<19>'
 '@S9S_MB_2U_LIB.S9S_MB_2U(SCH_1):M_H_CPU1_SA_DQ'<19>:
 C_SIGNAL='@s9s_mb_2u_lib.s9s_mb_2u(sch_1):m_h_cpu1_sa_dq(19)';
NODE_NAME     U1 DG68
 '@S9S_MB_2U_LIB.S9S_MB_2U(SCH_1):PAGE58_I20@PURE_QUANTA.SOCKET4677_AZIF0045P001C01CS(CHIPS)':
 'DDR7_SA_DQ19': CDS_PINID='DDR7_SA_DQ19';
NODE_NAME     J31 176
 '@S9S_MB_2U_LIB.S9S_MB_2U(SCH_1):PAGE112_I180@PURE_QUANTA.SCONN288_ADR50017P130CC(CHIPS)':
 'DQ19_A': CDS_PINID='DQ19_A';
NODE_NAME     J32 176
 '@S9S_MB_2U_LIB.S9S_MB_2U(SCH_1):PAGE113_I179@PURE_QUANTA.SCONN288_ADR50017P087CC(CHIPS)':
 'DQ19_A': CDS_PINID='DQ19_A';
NET_NAME
'M_H_CPU1_SA_DQ<1>'
 '@S9S_MB_2U_LIB.S9S_MB_2U(SCH_1):M_H_CPU1_SA_DQ'<1>:
 C_SIGNAL='@s9s_mb_2u_lib.s9s_mb_2u(sch_1):m_h_cpu1_sa_dq(1)';
NODE_NAME     U1 DT77
 '@S9S_MB_2U_LIB.S9S_MB_2U(SCH_1):PAGE58_I20@PURE_QUANTA.SOCKET4677_AZIF0045P001C01CS(CHIPS)':
 'DDR7_SA_DQ1': CDS_PINID='DDR7_SA_DQ1';
NODE_NAME     J31 9
 '@S9S_MB_2U_LIB.S9S_MB_2U(SCH_1):PAGE112_I180@PURE_QUANTA.SCONN288_ADR50017P130CC(CHIPS)':
 'DQ1_A': CDS_PINID='DQ1_A';
NODE_NAME     J32 9
 '@S9S_MB_2U_LIB.S9S_MB_2U(SCH_1):PAGE113_I179@PURE_QUANTA.SCONN288_ADR50017P087CC(CHIPS)':
 'DQ1_A': CDS_PINID='DQ1_A';
NET_NAME
'M_H_CPU1_SA_DQ<20>'
 '@S9S_MB_2U_LIB.S9S_MB_2U(SCH_1):M_H_CPU1_SA_DQ'<20>:
 C_SIGNAL='@s9s_mb_2u_lib.s9s_mb_2u(sch_1):m_h_cpu1_sa_dq(20)';
NODE_NAME     U1 DC66
 '@S9S_MB_2U_LIB.S9S_MB_2U(SCH_1):PAGE58_I20@PURE_QUANTA.SOCKET4677_AZIF0045P001C01CS(CHIPS)':
 'DDR7_SA_DQ20': CDS_PINID='DDR7_SA_DQ20';
NODE_NAME     J31 36
 '@S9S_MB_2U_LIB.S9S_MB_2U(SCH_1):PAGE112_I180@PURE_QUANTA.SCONN288_ADR50017P130CC(CHIPS)':
 'DQ20_A': CDS_PINID='DQ20_A';
NODE_NAME     J32 36
 '@S9S_MB_2U_LIB.S9S_MB_2U(SCH_1):PAGE113_I179@PURE_QUANTA.SCONN288_ADR50017P087CC(CHIPS)':
 'DQ20_A': CDS_PINID='DQ20_A';
NET_NAME
'M_H_CPU1_SA_DQ<21>'
 '@S9S_MB_2U_LIB.S9S_MB_2U(SCH_1):M_H_CPU1_SA_DQ'<21>:
 C_SIGNAL='@s9s_mb_2u_lib.s9s_mb_2u(sch_1):m_h_cpu1_sa_dq(21)';
NODE_NAME     U1 DD65
 '@S9S_MB_2U_LIB.S9S_MB_2U(SCH_1):PAGE58_I20@PURE_QUANTA.SOCKET4677_AZIF0045P001C01CS(CHIPS)':
 'DDR7_SA_DQ21': CDS_PINID='DDR7_SA_DQ21';
NODE_NAME     J31 38
 '@S9S_MB_2U_LIB.S9S_MB_2U(SCH_1):PAGE112_I180@PURE_QUANTA.SCONN288_ADR50017P130CC(CHIPS)':
 'DQ21_A': CDS_PINID='DQ21_A';
NODE_NAME     J32 38
 '@S9S_MB_2U_LIB.S9S_MB_2U(SCH_1):PAGE113_I179@PURE_QUANTA.SCONN288_ADR50017P087CC(CHIPS)':
 'DQ21_A': CDS_PINID='DQ21_A';
NET_NAME
'M_H_CPU1_SA_DQ<22>'
 '@S9S_MB_2U_LIB.S9S_MB_2U(SCH_1):M_H_CPU1_SA_DQ'<22>:
 C_SIGNAL='@s9s_mb_2u_lib.s9s_mb_2u(sch_1):m_h_cpu1_sa_dq(22)';
NODE_NAME     U1 DG66
 '@S9S_MB_2U_LIB.S9S_MB_2U(SCH_1):PAGE58_I20@PURE_QUANTA.SOCKET4677_AZIF0045P001C01CS(CHIPS)':
 'DDR7_SA_DQ22': CDS_PINID='DDR7_SA_DQ22';
NODE_NAME     J31 181
 '@S9S_MB_2U_LIB.S9S_MB_2U(SCH_1):PAGE112_I180@PURE_QUANTA.SCONN288_ADR50017P130CC(CHIPS)':
 'DQ22_A': CDS_PINID='DQ22_A';
NODE_NAME     J32 181
 '@S9S_MB_2U_LIB.S9S_MB_2U(SCH_1):PAGE113_I179@PURE_QUANTA.SCONN288_ADR50017P087CC(CHIPS)':
 'DQ22_A': CDS_PINID='DQ22_A';
NET_NAME
'M_H_CPU1_SA_DQ<23>'
 '@S9S_MB_2U_LIB.S9S_MB_2U(SCH_1):M_H_CPU1_SA_DQ'<23>:
 C_SIGNAL='@s9s_mb_2u_lib.s9s_mb_2u(sch_1):m_h_cpu1_sa_dq(23)';
NODE_NAME     U1 DF65
 '@S9S_MB_2U_LIB.S9S_MB_2U(SCH_1):PAGE58_I20@PURE_QUANTA.SOCKET4677_AZIF0045P001C01CS(CHIPS)':
 'DDR7_SA_DQ23': CDS_PINID='DDR7_SA_DQ23';
NODE_NAME     J31 183
 '@S9S_MB_2U_LIB.S9S_MB_2U(SCH_1):PAGE112_I180@PURE_QUANTA.SCONN288_ADR50017P130CC(CHIPS)':
 'DQ23_A': CDS_PINID='DQ23_A';
NODE_NAME     J32 183
 '@S9S_MB_2U_LIB.S9S_MB_2U(SCH_1):PAGE113_I179@PURE_QUANTA.SCONN288_ADR50017P087CC(CHIPS)':
 'DQ23_A': CDS_PINID='DQ23_A';
NET_NAME
'M_H_CPU1_SA_DQ<24>'
 '@S9S_MB_2U_LIB.S9S_MB_2U(SCH_1):M_H_CPU1_SA_DQ'<24>:
 C_SIGNAL='@s9s_mb_2u_lib.s9s_mb_2u(sch_1):m_h_cpu1_sa_dq(24)';
NODE_NAME     U1 DD63
 '@S9S_MB_2U_LIB.S9S_MB_2U(SCH_1):PAGE58_I20@PURE_QUANTA.SOCKET4677_AZIF0045P001C01CS(CHIPS)':
 'DDR7_SA_DQ24': CDS_PINID='DDR7_SA_DQ24';
NODE_NAME     J31 40
 '@S9S_MB_2U_LIB.S9S_MB_2U(SCH_1):PAGE112_I180@PURE_QUANTA.SCONN288_ADR50017P130CC(CHIPS)':
 'DQ24_A': CDS_PINID='DQ24_A';
NODE_NAME     J32 40
 '@S9S_MB_2U_LIB.S9S_MB_2U(SCH_1):PAGE113_I179@PURE_QUANTA.SCONN288_ADR50017P087CC(CHIPS)':
 'DQ24_A': CDS_PINID='DQ24_A';
NET_NAME
'M_H_CPU1_SA_DQ<25>'
 '@S9S_MB_2U_LIB.S9S_MB_2U(SCH_1):M_H_CPU1_SA_DQ'<25>:
 C_SIGNAL='@s9s_mb_2u_lib.s9s_mb_2u(sch_1):m_h_cpu1_sa_dq(25)';
NODE_NAME     U1 DC62
 '@S9S_MB_2U_LIB.S9S_MB_2U(SCH_1):PAGE58_I20@PURE_QUANTA.SOCKET4677_AZIF0045P001C01CS(CHIPS)':
 'DDR7_SA_DQ25': CDS_PINID='DDR7_SA_DQ25';
NODE_NAME     J31 42
 '@S9S_MB_2U_LIB.S9S_MB_2U(SCH_1):PAGE112_I180@PURE_QUANTA.SCONN288_ADR50017P130CC(CHIPS)':
 'DQ25_A': CDS_PINID='DQ25_A';
NODE_NAME     J32 42
 '@S9S_MB_2U_LIB.S9S_MB_2U(SCH_1):PAGE113_I179@PURE_QUANTA.SCONN288_ADR50017P087CC(CHIPS)':
 'DQ25_A': CDS_PINID='DQ25_A';
NET_NAME
'M_H_CPU1_SA_DQ<26>'
 '@S9S_MB_2U_LIB.S9S_MB_2U(SCH_1):M_H_CPU1_SA_DQ'<26>:
 C_SIGNAL='@s9s_mb_2u_lib.s9s_mb_2u(sch_1):m_h_cpu1_sa_dq(26)';
NODE_NAME     U1 DF63
 '@S9S_MB_2U_LIB.S9S_MB_2U(SCH_1):PAGE58_I20@PURE_QUANTA.SOCKET4677_AZIF0045P001C01CS(CHIPS)':
 'DDR7_SA_DQ26': CDS_PINID='DDR7_SA_DQ26';
NODE_NAME     J31 185
 '@S9S_MB_2U_LIB.S9S_MB_2U(SCH_1):PAGE112_I180@PURE_QUANTA.SCONN288_ADR50017P130CC(CHIPS)':
 'DQ26_A': CDS_PINID='DQ26_A';
NODE_NAME     J32 185
 '@S9S_MB_2U_LIB.S9S_MB_2U(SCH_1):PAGE113_I179@PURE_QUANTA.SCONN288_ADR50017P087CC(CHIPS)':
 'DQ26_A': CDS_PINID='DQ26_A';
NET_NAME
'M_H_CPU1_SA_DQ<27>'
 '@S9S_MB_2U_LIB.S9S_MB_2U(SCH_1):M_H_CPU1_SA_DQ'<27>:
 C_SIGNAL='@s9s_mb_2u_lib.s9s_mb_2u(sch_1):m_h_cpu1_sa_dq(27)';
NODE_NAME     U1 DG62
 '@S9S_MB_2U_LIB.S9S_MB_2U(SCH_1):PAGE58_I20@PURE_QUANTA.SOCKET4677_AZIF0045P001C01CS(CHIPS)':
 'DDR7_SA_DQ27': CDS_PINID='DDR7_SA_DQ27';
NODE_NAME     J31 187
 '@S9S_MB_2U_LIB.S9S_MB_2U(SCH_1):PAGE112_I180@PURE_QUANTA.SCONN288_ADR50017P130CC(CHIPS)':
 'DQ27_A': CDS_PINID='DQ27_A';
NODE_NAME     J32 187
 '@S9S_MB_2U_LIB.S9S_MB_2U(SCH_1):PAGE113_I179@PURE_QUANTA.SCONN288_ADR50017P087CC(CHIPS)':
 'DQ27_A': CDS_PINID='DQ27_A';
NET_NAME
'M_H_CPU1_SA_DQ<28>'
 '@S9S_MB_2U_LIB.S9S_MB_2U(SCH_1):M_H_CPU1_SA_DQ'<28>:
 C_SIGNAL='@s9s_mb_2u_lib.s9s_mb_2u(sch_1):m_h_cpu1_sa_dq(28)';
NODE_NAME     U1 DC60
 '@S9S_MB_2U_LIB.S9S_MB_2U(SCH_1):PAGE58_I20@PURE_QUANTA.SOCKET4677_AZIF0045P001C01CS(CHIPS)':
 'DDR7_SA_DQ28': CDS_PINID='DDR7_SA_DQ28';
NODE_NAME     J31 47
 '@S9S_MB_2U_LIB.S9S_MB_2U(SCH_1):PAGE112_I180@PURE_QUANTA.SCONN288_ADR50017P130CC(CHIPS)':
 'DQ28_A': CDS_PINID='DQ28_A';
NODE_NAME     J32 47
 '@S9S_MB_2U_LIB.S9S_MB_2U(SCH_1):PAGE113_I179@PURE_QUANTA.SCONN288_ADR50017P087CC(CHIPS)':
 'DQ28_A': CDS_PINID='DQ28_A';
NET_NAME
'M_H_CPU1_SA_DQ<29>'
 '@S9S_MB_2U_LIB.S9S_MB_2U(SCH_1):M_H_CPU1_SA_DQ'<29>:
 C_SIGNAL='@s9s_mb_2u_lib.s9s_mb_2u(sch_1):m_h_cpu1_sa_dq(29)';
NODE_NAME     U1 DD59
 '@S9S_MB_2U_LIB.S9S_MB_2U(SCH_1):PAGE58_I20@PURE_QUANTA.SOCKET4677_AZIF0045P001C01CS(CHIPS)':
 'DDR7_SA_DQ29': CDS_PINID='DDR7_SA_DQ29';
NODE_NAME     J31 49
 '@S9S_MB_2U_LIB.S9S_MB_2U(SCH_1):PAGE112_I180@PURE_QUANTA.SCONN288_ADR50017P130CC(CHIPS)':
 'DQ29_A': CDS_PINID='DQ29_A';
NODE_NAME     J32 49
 '@S9S_MB_2U_LIB.S9S_MB_2U(SCH_1):PAGE113_I179@PURE_QUANTA.SCONN288_ADR50017P087CC(CHIPS)':
 'DQ29_A': CDS_PINID='DQ29_A';
NET_NAME
'M_H_CPU1_SA_DQ<2>'
 '@S9S_MB_2U_LIB.S9S_MB_2U(SCH_1):M_H_CPU1_SA_DQ'<2>:
 C_SIGNAL='@s9s_mb_2u_lib.s9s_mb_2u(sch_1):m_h_cpu1_sa_dq(2)';
NODE_NAME     U1 DW78
 '@S9S_MB_2U_LIB.S9S_MB_2U(SCH_1):PAGE58_I20@PURE_QUANTA.SOCKET4677_AZIF0045P001C01CS(CHIPS)':
 'DDR7_SA_DQ2': CDS_PINID='DDR7_SA_DQ2';
NODE_NAME     J31 152
 '@S9S_MB_2U_LIB.S9S_MB_2U(SCH_1):PAGE112_I180@PURE_QUANTA.SCONN288_ADR50017P130CC(CHIPS)':
 'DQ2_A': CDS_PINID='DQ2_A';
NODE_NAME     J32 152
 '@S9S_MB_2U_LIB.S9S_MB_2U(SCH_1):PAGE113_I179@PURE_QUANTA.SCONN288_ADR50017P087CC(CHIPS)':
 'DQ2_A': CDS_PINID='DQ2_A';
NET_NAME
'M_H_CPU1_SA_DQ<30>'
 '@S9S_MB_2U_LIB.S9S_MB_2U(SCH_1):M_H_CPU1_SA_DQ'<30>:
 C_SIGNAL='@s9s_mb_2u_lib.s9s_mb_2u(sch_1):m_h_cpu1_sa_dq(30)';
NODE_NAME     U1 DG60
 '@S9S_MB_2U_LIB.S9S_MB_2U(SCH_1):PAGE58_I20@PURE_QUANTA.SOCKET4677_AZIF0045P001C01CS(CHIPS)':
 'DDR7_SA_DQ30': CDS_PINID='DDR7_SA_DQ30';
NODE_NAME     J31 192
 '@S9S_MB_2U_LIB.S9S_MB_2U(SCH_1):PAGE112_I180@PURE_QUANTA.SCONN288_ADR50017P130CC(CHIPS)':
 'DQ30_A': CDS_PINID='DQ30_A';
NODE_NAME     J32 192
 '@S9S_MB_2U_LIB.S9S_MB_2U(SCH_1):PAGE113_I179@PURE_QUANTA.SCONN288_ADR50017P087CC(CHIPS)':
 'DQ30_A': CDS_PINID='DQ30_A';
NET_NAME
'M_H_CPU1_SA_DQ<31>'
 '@S9S_MB_2U_LIB.S9S_MB_2U(SCH_1):M_H_CPU1_SA_DQ'<31>:
 C_SIGNAL='@s9s_mb_2u_lib.s9s_mb_2u(sch_1):m_h_cpu1_sa_dq(31)';
NODE_NAME     U1 DF59
 '@S9S_MB_2U_LIB.S9S_MB_2U(SCH_1):PAGE58_I20@PURE_QUANTA.SOCKET4677_AZIF0045P001C01CS(CHIPS)':
 'DDR7_SA_DQ31': CDS_PINID='DDR7_SA_DQ31';
NODE_NAME     J31 194
 '@S9S_MB_2U_LIB.S9S_MB_2U(SCH_1):PAGE112_I180@PURE_QUANTA.SCONN288_ADR50017P130CC(CHIPS)':
 'DQ31_A': CDS_PINID='DQ31_A';
NODE_NAME     J32 194
 '@S9S_MB_2U_LIB.S9S_MB_2U(SCH_1):PAGE113_I179@PURE_QUANTA.SCONN288_ADR50017P087CC(CHIPS)':
 'DQ31_A': CDS_PINID='DQ31_A';
NET_NAME
'M_H_CPU1_SA_DQ<3>'
 '@S9S_MB_2U_LIB.S9S_MB_2U(SCH_1):M_H_CPU1_SA_DQ'<3>:
 C_SIGNAL='@s9s_mb_2u_lib.s9s_mb_2u(sch_1):m_h_cpu1_sa_dq(3)';
NODE_NAME     U1 DP77
 '@S9S_MB_2U_LIB.S9S_MB_2U(SCH_1):PAGE58_I20@PURE_QUANTA.SOCKET4677_AZIF0045P001C01CS(CHIPS)':
 'DDR7_SA_DQ3': CDS_PINID='DDR7_SA_DQ3';
NODE_NAME     J31 154
 '@S9S_MB_2U_LIB.S9S_MB_2U(SCH_1):PAGE112_I180@PURE_QUANTA.SCONN288_ADR50017P130CC(CHIPS)':
 'DQ3_A': CDS_PINID='DQ3_A';
NODE_NAME     J32 154
 '@S9S_MB_2U_LIB.S9S_MB_2U(SCH_1):PAGE113_I179@PURE_QUANTA.SCONN288_ADR50017P087CC(CHIPS)':
 'DQ3_A': CDS_PINID='DQ3_A';
NET_NAME
'M_H_CPU1_SA_DQ<4>'
 '@S9S_MB_2U_LIB.S9S_MB_2U(SCH_1):M_H_CPU1_SA_DQ'<4>:
 C_SIGNAL='@s9s_mb_2u_lib.s9s_mb_2u(sch_1):m_h_cpu1_sa_dq(4)';
NODE_NAME     U1 DK75
 '@S9S_MB_2U_LIB.S9S_MB_2U(SCH_1):PAGE58_I20@PURE_QUANTA.SOCKET4677_AZIF0045P001C01CS(CHIPS)':
 'DDR7_SA_DQ4': CDS_PINID='DDR7_SA_DQ4';
NODE_NAME     J31 14
 '@S9S_MB_2U_LIB.S9S_MB_2U(SCH_1):PAGE112_I180@PURE_QUANTA.SCONN288_ADR50017P130CC(CHIPS)':
 'DQ4_A': CDS_PINID='DQ4_A';
NODE_NAME     J32 14
 '@S9S_MB_2U_LIB.S9S_MB_2U(SCH_1):PAGE113_I179@PURE_QUANTA.SCONN288_ADR50017P087CC(CHIPS)':
 'DQ4_A': CDS_PINID='DQ4_A';
NET_NAME
'M_H_CPU1_SA_DQ<5>'
 '@S9S_MB_2U_LIB.S9S_MB_2U(SCH_1):M_H_CPU1_SA_DQ'<5>:
 C_SIGNAL='@s9s_mb_2u_lib.s9s_mb_2u(sch_1):m_h_cpu1_sa_dq(5)';
NODE_NAME     U1 DL74
 '@S9S_MB_2U_LIB.S9S_MB_2U(SCH_1):PAGE58_I20@PURE_QUANTA.SOCKET4677_AZIF0045P001C01CS(CHIPS)':
 'DDR7_SA_DQ5': CDS_PINID='DDR7_SA_DQ5';
NODE_NAME     J31 16
 '@S9S_MB_2U_LIB.S9S_MB_2U(SCH_1):PAGE112_I180@PURE_QUANTA.SCONN288_ADR50017P130CC(CHIPS)':
 'DQ5_A': CDS_PINID='DQ5_A';
NODE_NAME     J32 16
 '@S9S_MB_2U_LIB.S9S_MB_2U(SCH_1):PAGE113_I179@PURE_QUANTA.SCONN288_ADR50017P087CC(CHIPS)':
 'DQ5_A': CDS_PINID='DQ5_A';
NET_NAME
'M_H_CPU1_SA_DQ<6>'
 '@S9S_MB_2U_LIB.S9S_MB_2U(SCH_1):M_H_CPU1_SA_DQ'<6>:
 C_SIGNAL='@s9s_mb_2u_lib.s9s_mb_2u(sch_1):m_h_cpu1_sa_dq(6)';
NODE_NAME     U1 DP75
 '@S9S_MB_2U_LIB.S9S_MB_2U(SCH_1):PAGE58_I20@PURE_QUANTA.SOCKET4677_AZIF0045P001C01CS(CHIPS)':
 'DDR7_SA_DQ6': CDS_PINID='DDR7_SA_DQ6';
NODE_NAME     J31 159
 '@S9S_MB_2U_LIB.S9S_MB_2U(SCH_1):PAGE112_I180@PURE_QUANTA.SCONN288_ADR50017P130CC(CHIPS)':
 'DQ6_A': CDS_PINID='DQ6_A';
NODE_NAME     J32 159
 '@S9S_MB_2U_LIB.S9S_MB_2U(SCH_1):PAGE113_I179@PURE_QUANTA.SCONN288_ADR50017P087CC(CHIPS)':
 'DQ6_A': CDS_PINID='DQ6_A';
NET_NAME
'M_H_CPU1_SA_DQ<7>'
 '@S9S_MB_2U_LIB.S9S_MB_2U(SCH_1):M_H_CPU1_SA_DQ'<7>:
 C_SIGNAL='@s9s_mb_2u_lib.s9s_mb_2u(sch_1):m_h_cpu1_sa_dq(7)';
NODE_NAME     U1 DN74
 '@S9S_MB_2U_LIB.S9S_MB_2U(SCH_1):PAGE58_I20@PURE_QUANTA.SOCKET4677_AZIF0045P001C01CS(CHIPS)':
 'DDR7_SA_DQ7': CDS_PINID='DDR7_SA_DQ7';
NODE_NAME     J31 161
 '@S9S_MB_2U_LIB.S9S_MB_2U(SCH_1):PAGE112_I180@PURE_QUANTA.SCONN288_ADR50017P130CC(CHIPS)':
 'DQ7_A': CDS_PINID='DQ7_A';
NODE_NAME     J32 161
 '@S9S_MB_2U_LIB.S9S_MB_2U(SCH_1):PAGE113_I179@PURE_QUANTA.SCONN288_ADR50017P087CC(CHIPS)':
 'DQ7_A': CDS_PINID='DQ7_A';
NET_NAME
'M_H_CPU1_SA_DQ<8>'
 '@S9S_MB_2U_LIB.S9S_MB_2U(SCH_1):M_H_CPU1_SA_DQ'<8>:
 C_SIGNAL='@s9s_mb_2u_lib.s9s_mb_2u(sch_1):m_h_cpu1_sa_dq(8)';
NODE_NAME     U1 DD75
 '@S9S_MB_2U_LIB.S9S_MB_2U(SCH_1):PAGE58_I20@PURE_QUANTA.SOCKET4677_AZIF0045P001C01CS(CHIPS)':
 'DDR7_SA_DQ8': CDS_PINID='DDR7_SA_DQ8';
NODE_NAME     J31 18
 '@S9S_MB_2U_LIB.S9S_MB_2U(SCH_1):PAGE112_I180@PURE_QUANTA.SCONN288_ADR50017P130CC(CHIPS)':
 'DQ8_A': CDS_PINID='DQ8_A';
NODE_NAME     J32 18
 '@S9S_MB_2U_LIB.S9S_MB_2U(SCH_1):PAGE113_I179@PURE_QUANTA.SCONN288_ADR50017P087CC(CHIPS)':
 'DQ8_A': CDS_PINID='DQ8_A';
NET_NAME
'M_H_CPU1_SA_DQ<9>'
 '@S9S_MB_2U_LIB.S9S_MB_2U(SCH_1):M_H_CPU1_SA_DQ'<9>:
 C_SIGNAL='@s9s_mb_2u_lib.s9s_mb_2u(sch_1):m_h_cpu1_sa_dq(9)';
NODE_NAME     U1 DC74
 '@S9S_MB_2U_LIB.S9S_MB_2U(SCH_1):PAGE58_I20@PURE_QUANTA.SOCKET4677_AZIF0045P001C01CS(CHIPS)':
 'DDR7_SA_DQ9': CDS_PINID='DDR7_SA_DQ9';
NODE_NAME     J31 20
 '@S9S_MB_2U_LIB.S9S_MB_2U(SCH_1):PAGE112_I180@PURE_QUANTA.SCONN288_ADR50017P130CC(CHIPS)':
 'DQ9_A': CDS_PINID='DQ9_A';
NODE_NAME     J32 20
 '@S9S_MB_2U_LIB.S9S_MB_2U(SCH_1):PAGE113_I179@PURE_QUANTA.SCONN288_ADR50017P087CC(CHIPS)':
 'DQ9_A': CDS_PINID='DQ9_A';
NET_NAME
'M_H_CPU1_SA_DQS_DN<0>'
 '@S9S_MB_2U_LIB.S9S_MB_2U(SCH_1):M_H_CPU1_SA_DQS_DN'<0>:
 C_SIGNAL='@s9s_mb_2u_lib.s9s_mb_2u(sch_1):m_h_cpu1_sa_dqs_dn(0)';
NODE_NAME     U1 DJ76
 '@S9S_MB_2U_LIB.S9S_MB_2U(SCH_1):PAGE58_I20@PURE_QUANTA.SOCKET4677_AZIF0045P001C01CS(CHIPS)':
 'DDR7_SA_DQS_DN0': CDS_PINID='DDR7_SA_DQS_DN0';
NODE_NAME     J31 12
 '@S9S_MB_2U_LIB.S9S_MB_2U(SCH_1):PAGE112_I181@PURE_QUANTA.SCONN288_ADR50017P130CC(CHIPS)':
 'DQS0_A_C': CDS_PINID='DQS0_A_C';
NODE_NAME     J32 12
 '@S9S_MB_2U_LIB.S9S_MB_2U(SCH_1):PAGE113_I180@PURE_QUANTA.SCONN288_ADR50017P087CC(CHIPS)':
 'DQS0_A_C': CDS_PINID='DQS0_A_C';
NET_NAME
'M_H_CPU1_SA_DQS_DN<1>'
 '@S9S_MB_2U_LIB.S9S_MB_2U(SCH_1):M_H_CPU1_SA_DQS_DN'<1>:
 C_SIGNAL='@s9s_mb_2u_lib.s9s_mb_2u(sch_1):m_h_cpu1_sa_dqs_dn(1)';
NODE_NAME     U1 DB73
 '@S9S_MB_2U_LIB.S9S_MB_2U(SCH_1):PAGE58_I20@PURE_QUANTA.SOCKET4677_AZIF0045P001C01CS(CHIPS)':
 'DDR7_SA_DQS_DN1': CDS_PINID='DDR7_SA_DQS_DN1';
NODE_NAME     J31 23
 '@S9S_MB_2U_LIB.S9S_MB_2U(SCH_1):PAGE112_I181@PURE_QUANTA.SCONN288_ADR50017P130CC(CHIPS)':
 'DQS1_A_C': CDS_PINID='DQS1_A_C';
NODE_NAME     J32 23
 '@S9S_MB_2U_LIB.S9S_MB_2U(SCH_1):PAGE113_I180@PURE_QUANTA.SCONN288_ADR50017P087CC(CHIPS)':
 'DQS1_A_C': CDS_PINID='DQS1_A_C';
NET_NAME
'M_H_CPU1_SA_DQS_DN<2>'
 '@S9S_MB_2U_LIB.S9S_MB_2U(SCH_1):M_H_CPU1_SA_DQS_DN'<2>:
 C_SIGNAL='@s9s_mb_2u_lib.s9s_mb_2u(sch_1):m_h_cpu1_sa_dqs_dn(2)';
NODE_NAME     U1 DD67
 '@S9S_MB_2U_LIB.S9S_MB_2U(SCH_1):PAGE58_I20@PURE_QUANTA.SOCKET4677_AZIF0045P001C01CS(CHIPS)':
 'DDR7_SA_DQS_DN2': CDS_PINID='DDR7_SA_DQS_DN2';
NODE_NAME     J31 34
 '@S9S_MB_2U_LIB.S9S_MB_2U(SCH_1):PAGE112_I181@PURE_QUANTA.SCONN288_ADR50017P130CC(CHIPS)':
 'DQS2_A_C': CDS_PINID='DQS2_A_C';
NODE_NAME     J32 34
 '@S9S_MB_2U_LIB.S9S_MB_2U(SCH_1):PAGE113_I180@PURE_QUANTA.SCONN288_ADR50017P087CC(CHIPS)':
 'DQS2_A_C': CDS_PINID='DQS2_A_C';
NET_NAME
'M_H_CPU1_SA_DQS_DN<3>'
 '@S9S_MB_2U_LIB.S9S_MB_2U(SCH_1):M_H_CPU1_SA_DQS_DN'<3>:
 C_SIGNAL='@s9s_mb_2u_lib.s9s_mb_2u(sch_1):m_h_cpu1_sa_dqs_dn(3)';
NODE_NAME     U1 DD61
 '@S9S_MB_2U_LIB.S9S_MB_2U(SCH_1):PAGE58_I20@PURE_QUANTA.SOCKET4677_AZIF0045P001C01CS(CHIPS)':
 'DDR7_SA_DQS_DN3': CDS_PINID='DDR7_SA_DQS_DN3';
NODE_NAME     J31 45
 '@S9S_MB_2U_LIB.S9S_MB_2U(SCH_1):PAGE112_I181@PURE_QUANTA.SCONN288_ADR50017P130CC(CHIPS)':
 'DQS3_A_C': CDS_PINID='DQS3_A_C';
NODE_NAME     J32 45
 '@S9S_MB_2U_LIB.S9S_MB_2U(SCH_1):PAGE113_I180@PURE_QUANTA.SCONN288_ADR50017P087CC(CHIPS)':
 'DQS3_A_C': CDS_PINID='DQS3_A_C';
NET_NAME
'M_H_CPU1_SA_DQS_DN<4>'
 '@S9S_MB_2U_LIB.S9S_MB_2U(SCH_1):M_H_CPU1_SA_DQS_DN'<4>:
 C_SIGNAL='@s9s_mb_2u_lib.s9s_mb_2u(sch_1):m_h_cpu1_sa_dqs_dn(4)';
NODE_NAME     U1 DD55
 '@S9S_MB_2U_LIB.S9S_MB_2U(SCH_1):PAGE58_I20@PURE_QUANTA.SOCKET4677_AZIF0045P001C01CS(CHIPS)':
 'DDR7_SA_DQS_DN4': CDS_PINID='DDR7_SA_DQS_DN4';
NODE_NAME     J31 56
 '@S9S_MB_2U_LIB.S9S_MB_2U(SCH_1):PAGE112_I181@PURE_QUANTA.SCONN288_ADR50017P130CC(CHIPS)':
 'DQS4_A_C': CDS_PINID='DQS4_A_C';
NODE_NAME     J32 56
 '@S9S_MB_2U_LIB.S9S_MB_2U(SCH_1):PAGE113_I180@PURE_QUANTA.SCONN288_ADR50017P087CC(CHIPS)':
 'DQS4_A_C': CDS_PINID='DQS4_A_C';
NET_NAME
'M_H_CPU1_SA_DQS_DN<5>'
 '@S9S_MB_2U_LIB.S9S_MB_2U(SCH_1):M_H_CPU1_SA_DQS_DN'<5>:
 C_SIGNAL='@s9s_mb_2u_lib.s9s_mb_2u(sch_1):m_h_cpu1_sa_dqs_dn(5)';
NODE_NAME     U1 DR76
 '@S9S_MB_2U_LIB.S9S_MB_2U(SCH_1):PAGE58_I20@PURE_QUANTA.SOCKET4677_AZIF0045P001C01CS(CHIPS)':
 'DDR7_SA_DQS_DN5': CDS_PINID='DDR7_SA_DQS_DN5';
NODE_NAME     J31 156
 '@S9S_MB_2U_LIB.S9S_MB_2U(SCH_1):PAGE112_I181@PURE_QUANTA.SCONN288_ADR50017P130CC(CHIPS)':
 'DQS5_A_C||TDQS5_A_C||DQS5_A_T||TDQS5_A_T': CDS_PINID='\dqs5_a_c||tdqs5_a_c||dqs5_a_t||tdqs5_a_t\';
NODE_NAME     J32 156
 '@S9S_MB_2U_LIB.S9S_MB_2U(SCH_1):PAGE113_I180@PURE_QUANTA.SCONN288_ADR50017P087CC(CHIPS)':
 'DQS5_A_C||TDQS5_A_C||DQS5_A_T||TDQS5_A_T': CDS_PINID='\dqs5_a_c||tdqs5_a_c||dqs5_a_t||tdqs5_a_t\';
NET_NAME
'M_H_CPU1_SA_DQS_DN<6>'
 '@S9S_MB_2U_LIB.S9S_MB_2U(SCH_1):M_H_CPU1_SA_DQS_DN'<6>:
 C_SIGNAL='@s9s_mb_2u_lib.s9s_mb_2u(sch_1):m_h_cpu1_sa_dqs_dn(6)';
NODE_NAME     U1 DH73
 '@S9S_MB_2U_LIB.S9S_MB_2U(SCH_1):PAGE58_I20@PURE_QUANTA.SOCKET4677_AZIF0045P001C01CS(CHIPS)':
 'DDR7_SA_DQS_DN6': CDS_PINID='DDR7_SA_DQS_DN6';
NODE_NAME     J31 167
 '@S9S_MB_2U_LIB.S9S_MB_2U(SCH_1):PAGE112_I181@PURE_QUANTA.SCONN288_ADR50017P130CC(CHIPS)':
 'DQS6_A_C||TDQS6_A_C||DQS6_A_T||TDQS6_A_T': CDS_PINID='\dqs6_a_c||tdqs6_a_c||dqs6_a_t||tdqs6_a_t\';
NODE_NAME     J32 167
 '@S9S_MB_2U_LIB.S9S_MB_2U(SCH_1):PAGE113_I180@PURE_QUANTA.SCONN288_ADR50017P087CC(CHIPS)':
 'DQS6_A_C||TDQS6_A_C||DQS6_A_T||TDQS6_A_T': CDS_PINID='\dqs6_a_c||tdqs6_a_c||dqs6_a_t||tdqs6_a_t\';
NET_NAME
'M_H_CPU1_SA_DQS_DN<7>'
 '@S9S_MB_2U_LIB.S9S_MB_2U(SCH_1):M_H_CPU1_SA_DQS_DN'<7>:
 C_SIGNAL='@s9s_mb_2u_lib.s9s_mb_2u(sch_1):m_h_cpu1_sa_dqs_dn(7)';
NODE_NAME     U1 DH67
 '@S9S_MB_2U_LIB.S9S_MB_2U(SCH_1):PAGE58_I20@PURE_QUANTA.SOCKET4677_AZIF0045P001C01CS(CHIPS)':
 'DDR7_SA_DQS_DN7': CDS_PINID='DDR7_SA_DQS_DN7';
NODE_NAME     J31 178
 '@S9S_MB_2U_LIB.S9S_MB_2U(SCH_1):PAGE112_I181@PURE_QUANTA.SCONN288_ADR50017P130CC(CHIPS)':
 'DQS7_A_C||TDQS7_A_C': CDS_PINID='\dqs7_a_c||tdqs7_a_c\';
NODE_NAME     J32 178
 '@S9S_MB_2U_LIB.S9S_MB_2U(SCH_1):PAGE113_I180@PURE_QUANTA.SCONN288_ADR50017P087CC(CHIPS)':
 'DQS7_A_C||TDQS7_A_C': CDS_PINID='\dqs7_a_c||tdqs7_a_c\';
NET_NAME
'M_H_CPU1_SA_DQS_DN<8>'
 '@S9S_MB_2U_LIB.S9S_MB_2U(SCH_1):M_H_CPU1_SA_DQS_DN'<8>:
 C_SIGNAL='@s9s_mb_2u_lib.s9s_mb_2u(sch_1):m_h_cpu1_sa_dqs_dn(8)';
NODE_NAME     U1 DH61
 '@S9S_MB_2U_LIB.S9S_MB_2U(SCH_1):PAGE58_I20@PURE_QUANTA.SOCKET4677_AZIF0045P001C01CS(CHIPS)':
 'DDR7_SA_DQS_DN8': CDS_PINID='DDR7_SA_DQS_DN8';
NODE_NAME     J31 189
 '@S9S_MB_2U_LIB.S9S_MB_2U(SCH_1):PAGE112_I181@PURE_QUANTA.SCONN288_ADR50017P130CC(CHIPS)':
 'DQS8_A_C||TDQS8_A_C': CDS_PINID='\dqs8_a_c||tdqs8_a_c\';
NODE_NAME     J32 189
 '@S9S_MB_2U_LIB.S9S_MB_2U(SCH_1):PAGE113_I180@PURE_QUANTA.SCONN288_ADR50017P087CC(CHIPS)':
 'DQS8_A_C||TDQS8_A_C': CDS_PINID='\dqs8_a_c||tdqs8_a_c\';
NET_NAME
'M_H_CPU1_SA_DQS_DN<9>'
 '@S9S_MB_2U_LIB.S9S_MB_2U(SCH_1):M_H_CPU1_SA_DQS_DN'<9>:
 C_SIGNAL='@s9s_mb_2u_lib.s9s_mb_2u(sch_1):m_h_cpu1_sa_dqs_dn(9)';
NODE_NAME     U1 DH55
 '@S9S_MB_2U_LIB.S9S_MB_2U(SCH_1):PAGE58_I20@PURE_QUANTA.SOCKET4677_AZIF0045P001C01CS(CHIPS)':
 'DDR7_SA_DQS_DN9': CDS_PINID='DDR7_SA_DQS_DN9';
NODE_NAME     J31 200
 '@S9S_MB_2U_LIB.S9S_MB_2U(SCH_1):PAGE112_I181@PURE_QUANTA.SCONN288_ADR50017P130CC(CHIPS)':
 'DQS9_A_C||TDQS9_A_C': CDS_PINID='\dqs9_a_c||tdqs9_a_c\';
NODE_NAME     J32 200
 '@S9S_MB_2U_LIB.S9S_MB_2U(SCH_1):PAGE113_I180@PURE_QUANTA.SCONN288_ADR50017P087CC(CHIPS)':
 'DQS9_A_C||TDQS9_A_C': CDS_PINID='\dqs9_a_c||tdqs9_a_c\';
NET_NAME
'M_H_CPU1_SA_DQS_DP<0>'
 '@S9S_MB_2U_LIB.S9S_MB_2U(SCH_1):M_H_CPU1_SA_DQS_DP'<0>:
 C_SIGNAL='@s9s_mb_2u_lib.s9s_mb_2u(sch_1):m_h_cpu1_sa_dqs_dp(0)';
NODE_NAME     U1 DL76
 '@S9S_MB_2U_LIB.S9S_MB_2U(SCH_1):PAGE58_I20@PURE_QUANTA.SOCKET4677_AZIF0045P001C01CS(CHIPS)':
 'DDR7_SA_DQS_DP0': CDS_PINID='DDR7_SA_DQS_DP0';
NODE_NAME     J31 11
 '@S9S_MB_2U_LIB.S9S_MB_2U(SCH_1):PAGE112_I181@PURE_QUANTA.SCONN288_ADR50017P130CC(CHIPS)':
 'DQS0_A_T': CDS_PINID='DQS0_A_T';
NODE_NAME     J32 11
 '@S9S_MB_2U_LIB.S9S_MB_2U(SCH_1):PAGE113_I180@PURE_QUANTA.SCONN288_ADR50017P087CC(CHIPS)':
 'DQS0_A_T': CDS_PINID='DQS0_A_T';
NET_NAME
'M_H_CPU1_SA_DQS_DP<1>'
 '@S9S_MB_2U_LIB.S9S_MB_2U(SCH_1):M_H_CPU1_SA_DQS_DP'<1>:
 C_SIGNAL='@s9s_mb_2u_lib.s9s_mb_2u(sch_1):m_h_cpu1_sa_dqs_dp(1)';
NODE_NAME     U1 DD73
 '@S9S_MB_2U_LIB.S9S_MB_2U(SCH_1):PAGE58_I20@PURE_QUANTA.SOCKET4677_AZIF0045P001C01CS(CHIPS)':
 'DDR7_SA_DQS_DP1': CDS_PINID='DDR7_SA_DQS_DP1';
NODE_NAME     J31 22
 '@S9S_MB_2U_LIB.S9S_MB_2U(SCH_1):PAGE112_I181@PURE_QUANTA.SCONN288_ADR50017P130CC(CHIPS)':
 'DQS1_A_T': CDS_PINID='DQS1_A_T';
NODE_NAME     J32 22
 '@S9S_MB_2U_LIB.S9S_MB_2U(SCH_1):PAGE113_I180@PURE_QUANTA.SCONN288_ADR50017P087CC(CHIPS)':
 'DQS1_A_T': CDS_PINID='DQS1_A_T';
NET_NAME
'M_H_CPU1_SA_DQS_DP<2>'
 '@S9S_MB_2U_LIB.S9S_MB_2U(SCH_1):M_H_CPU1_SA_DQS_DP'<2>:
 C_SIGNAL='@s9s_mb_2u_lib.s9s_mb_2u(sch_1):m_h_cpu1_sa_dqs_dp(2)';
NODE_NAME     U1 DB67
 '@S9S_MB_2U_LIB.S9S_MB_2U(SCH_1):PAGE58_I20@PURE_QUANTA.SOCKET4677_AZIF0045P001C01CS(CHIPS)':
 'DDR7_SA_DQS_DP2': CDS_PINID='DDR7_SA_DQS_DP2';
NODE_NAME     J31 33
 '@S9S_MB_2U_LIB.S9S_MB_2U(SCH_1):PAGE112_I181@PURE_QUANTA.SCONN288_ADR50017P130CC(CHIPS)':
 'DQS2_A_T': CDS_PINID='DQS2_A_T';
NODE_NAME     J32 33
 '@S9S_MB_2U_LIB.S9S_MB_2U(SCH_1):PAGE113_I180@PURE_QUANTA.SCONN288_ADR50017P087CC(CHIPS)':
 'DQS2_A_T': CDS_PINID='DQS2_A_T';
NET_NAME
'M_H_CPU1_SA_DQS_DP<3>'
 '@S9S_MB_2U_LIB.S9S_MB_2U(SCH_1):M_H_CPU1_SA_DQS_DP'<3>:
 C_SIGNAL='@s9s_mb_2u_lib.s9s_mb_2u(sch_1):m_h_cpu1_sa_dqs_dp(3)';
NODE_NAME     U1 DB61
 '@S9S_MB_2U_LIB.S9S_MB_2U(SCH_1):PAGE58_I20@PURE_QUANTA.SOCKET4677_AZIF0045P001C01CS(CHIPS)':
 'DDR7_SA_DQS_DP3': CDS_PINID='DDR7_SA_DQS_DP3';
NODE_NAME     J31 44
 '@S9S_MB_2U_LIB.S9S_MB_2U(SCH_1):PAGE112_I181@PURE_QUANTA.SCONN288_ADR50017P130CC(CHIPS)':
 'DQS3_A_T': CDS_PINID='DQS3_A_T';
NODE_NAME     J32 44
 '@S9S_MB_2U_LIB.S9S_MB_2U(SCH_1):PAGE113_I180@PURE_QUANTA.SCONN288_ADR50017P087CC(CHIPS)':
 'DQS3_A_T': CDS_PINID='DQS3_A_T';
NET_NAME
'M_H_CPU1_SA_DQS_DP<4>'
 '@S9S_MB_2U_LIB.S9S_MB_2U(SCH_1):M_H_CPU1_SA_DQS_DP'<4>:
 C_SIGNAL='@s9s_mb_2u_lib.s9s_mb_2u(sch_1):m_h_cpu1_sa_dqs_dp(4)';
NODE_NAME     U1 DB55
 '@S9S_MB_2U_LIB.S9S_MB_2U(SCH_1):PAGE58_I20@PURE_QUANTA.SOCKET4677_AZIF0045P001C01CS(CHIPS)':
 'DDR7_SA_DQS_DP4': CDS_PINID='DDR7_SA_DQS_DP4';
NODE_NAME     J31 55
 '@S9S_MB_2U_LIB.S9S_MB_2U(SCH_1):PAGE112_I181@PURE_QUANTA.SCONN288_ADR50017P130CC(CHIPS)':
 'DQS4_A_T': CDS_PINID='DQS4_A_T';
NODE_NAME     J32 55
 '@S9S_MB_2U_LIB.S9S_MB_2U(SCH_1):PAGE113_I180@PURE_QUANTA.SCONN288_ADR50017P087CC(CHIPS)':
 'DQS4_A_T': CDS_PINID='DQS4_A_T';
NET_NAME
'M_H_CPU1_SA_DQS_DP<5>'
 '@S9S_MB_2U_LIB.S9S_MB_2U(SCH_1):M_H_CPU1_SA_DQS_DP'<5>:
 C_SIGNAL='@s9s_mb_2u_lib.s9s_mb_2u(sch_1):m_h_cpu1_sa_dqs_dp(5)';
NODE_NAME     U1 DN76
 '@S9S_MB_2U_LIB.S9S_MB_2U(SCH_1):PAGE58_I20@PURE_QUANTA.SOCKET4677_AZIF0045P001C01CS(CHIPS)':
 'DDR7_SA_DQS_DP5': CDS_PINID='DDR7_SA_DQS_DP5';
NODE_NAME     J31 157
 '@S9S_MB_2U_LIB.S9S_MB_2U(SCH_1):PAGE112_I181@PURE_QUANTA.SCONN288_ADR50017P130CC(CHIPS)':
 'DQS5_A_T||TDQS5_A_T': CDS_PINID='\dqs5_a_t||tdqs5_a_t\';
NODE_NAME     J32 157
 '@S9S_MB_2U_LIB.S9S_MB_2U(SCH_1):PAGE113_I180@PURE_QUANTA.SCONN288_ADR50017P087CC(CHIPS)':
 'DQS5_A_T||TDQS5_A_T': CDS_PINID='\dqs5_a_t||tdqs5_a_t\';
NET_NAME
'M_H_CPU1_SA_DQS_DP<6>'
 '@S9S_MB_2U_LIB.S9S_MB_2U(SCH_1):M_H_CPU1_SA_DQS_DP'<6>:
 C_SIGNAL='@s9s_mb_2u_lib.s9s_mb_2u(sch_1):m_h_cpu1_sa_dqs_dp(6)';
NODE_NAME     U1 DF73
 '@S9S_MB_2U_LIB.S9S_MB_2U(SCH_1):PAGE58_I20@PURE_QUANTA.SOCKET4677_AZIF0045P001C01CS(CHIPS)':
 'DDR7_SA_DQS_DP6': CDS_PINID='DDR7_SA_DQS_DP6';
NODE_NAME     J31 168
 '@S9S_MB_2U_LIB.S9S_MB_2U(SCH_1):PAGE112_I181@PURE_QUANTA.SCONN288_ADR50017P130CC(CHIPS)':
 'DQS6_A_T||TDQS6_A_T': CDS_PINID='\dqs6_a_t||tdqs6_a_t\';
NODE_NAME     J32 168
 '@S9S_MB_2U_LIB.S9S_MB_2U(SCH_1):PAGE113_I180@PURE_QUANTA.SCONN288_ADR50017P087CC(CHIPS)':
 'DQS6_A_T||TDQS6_A_T': CDS_PINID='\dqs6_a_t||tdqs6_a_t\';
NET_NAME
'M_H_CPU1_SA_DQS_DP<7>'
 '@S9S_MB_2U_LIB.S9S_MB_2U(SCH_1):M_H_CPU1_SA_DQS_DP'<7>:
 C_SIGNAL='@s9s_mb_2u_lib.s9s_mb_2u(sch_1):m_h_cpu1_sa_dqs_dp(7)';
NODE_NAME     U1 DF67
 '@S9S_MB_2U_LIB.S9S_MB_2U(SCH_1):PAGE58_I20@PURE_QUANTA.SOCKET4677_AZIF0045P001C01CS(CHIPS)':
 'DDR7_SA_DQS_DP7': CDS_PINID='DDR7_SA_DQS_DP7';
NODE_NAME     J31 179
 '@S9S_MB_2U_LIB.S9S_MB_2U(SCH_1):PAGE112_I181@PURE_QUANTA.SCONN288_ADR50017P130CC(CHIPS)':
 'DQS7_A_T||TDQS7_A_T': CDS_PINID='\dqs7_a_t||tdqs7_a_t\';
NODE_NAME     J32 179
 '@S9S_MB_2U_LIB.S9S_MB_2U(SCH_1):PAGE113_I180@PURE_QUANTA.SCONN288_ADR50017P087CC(CHIPS)':
 'DQS7_A_T||TDQS7_A_T': CDS_PINID='\dqs7_a_t||tdqs7_a_t\';
NET_NAME
'M_H_CPU1_SA_DQS_DP<8>'
 '@S9S_MB_2U_LIB.S9S_MB_2U(SCH_1):M_H_CPU1_SA_DQS_DP'<8>:
 C_SIGNAL='@s9s_mb_2u_lib.s9s_mb_2u(sch_1):m_h_cpu1_sa_dqs_dp(8)';
NODE_NAME     U1 DF61
 '@S9S_MB_2U_LIB.S9S_MB_2U(SCH_1):PAGE58_I20@PURE_QUANTA.SOCKET4677_AZIF0045P001C01CS(CHIPS)':
 'DDR7_SA_DQS_DP8': CDS_PINID='DDR7_SA_DQS_DP8';
NODE_NAME     J31 190
 '@S9S_MB_2U_LIB.S9S_MB_2U(SCH_1):PAGE112_I181@PURE_QUANTA.SCONN288_ADR50017P130CC(CHIPS)':
 'DQS8_A_T||TDQS8_A_T': CDS_PINID='\dqs8_a_t||tdqs8_a_t\';
NODE_NAME     J32 190
 '@S9S_MB_2U_LIB.S9S_MB_2U(SCH_1):PAGE113_I180@PURE_QUANTA.SCONN288_ADR50017P087CC(CHIPS)':
 'DQS8_A_T||TDQS8_A_T': CDS_PINID='\dqs8_a_t||tdqs8_a_t\';
NET_NAME
'M_H_CPU1_SA_DQS_DP<9>'
 '@S9S_MB_2U_LIB.S9S_MB_2U(SCH_1):M_H_CPU1_SA_DQS_DP'<9>:
 C_SIGNAL='@s9s_mb_2u_lib.s9s_mb_2u(sch_1):m_h_cpu1_sa_dqs_dp(9)';
NODE_NAME     U1 DF55
 '@S9S_MB_2U_LIB.S9S_MB_2U(SCH_1):PAGE58_I20@PURE_QUANTA.SOCKET4677_AZIF0045P001C01CS(CHIPS)':
 'DDR7_SA_DQS_DP9': CDS_PINID='DDR7_SA_DQS_DP9';
NODE_NAME     J31 201
 '@S9S_MB_2U_LIB.S9S_MB_2U(SCH_1):PAGE112_I181@PURE_QUANTA.SCONN288_ADR50017P130CC(CHIPS)':
 'DQS9_A_T||TDQS9_A_T': CDS_PINID='\dqs9_a_t||tdqs9_a_t\';
NODE_NAME     J32 201
 '@S9S_MB_2U_LIB.S9S_MB_2U(SCH_1):PAGE113_I180@PURE_QUANTA.SCONN288_ADR50017P087CC(CHIPS)':
 'DQS9_A_T||TDQS9_A_T': CDS_PINID='\dqs9_a_t||tdqs9_a_t\';
NET_NAME
'M_H_CPU1_SA_PAR'
 '@S9S_MB_2U_LIB.S9S_MB_2U(SCH_1):M_H_CPU1_SA_PAR':
 C_SIGNAL='@s9s_mb_2u_lib.s9s_mb_2u(sch_1):m_h_cpu1_sa_par';
NODE_NAME     U1 DD40
 '@S9S_MB_2U_LIB.S9S_MB_2U(SCH_1):PAGE58_I20@PURE_QUANTA.SOCKET4677_AZIF0045P001C01CS(CHIPS)':
 'DDR7_SA_PAR': CDS_PINID='DDR7_SA_PAR';
NODE_NAME     J31 74
 '@S9S_MB_2U_LIB.S9S_MB_2U(SCH_1):PAGE112_I180@PURE_QUANTA.SCONN288_ADR50017P130CC(CHIPS)':
 'PAR_A': CDS_PINID='PAR_A';
NODE_NAME     J32 74
 '@S9S_MB_2U_LIB.S9S_MB_2U(SCH_1):PAGE113_I179@PURE_QUANTA.SCONN288_ADR50017P087CC(CHIPS)':
 'PAR_A': CDS_PINID='PAR_A';
NET_NAME
'M_H_CPU1_SA_RSP<0>'
 '@S9S_MB_2U_LIB.S9S_MB_2U(SCH_1):M_H_CPU1_SA_RSP'<0>:
 C_SIGNAL='@s9s_mb_2u_lib.s9s_mb_2u(sch_1):m_h_cpu1_sa_rsp(0)';
NODE_NAME     U1 EG48
 '@S9S_MB_2U_LIB.S9S_MB_2U(SCH_1):PAGE58_I20@PURE_QUANTA.SOCKET4677_AZIF0045P001C01CS(CHIPS)':
 'DDR7_A_RSP0': CDS_PINID='DDR7_A_RSP0';
NODE_NAME     J31 86
 '@S9S_MB_2U_LIB.S9S_MB_2U(SCH_1):PAGE112_I180@PURE_QUANTA.SCONN288_ADR50017P130CC(CHIPS)':
 'LBD||RSP_A_N': CDS_PINID='\lbd||rsp_a_n\';
NET_NAME
'M_H_CPU1_SA_RSP<1>'
 '@S9S_MB_2U_LIB.S9S_MB_2U(SCH_1):M_H_CPU1_SA_RSP'<1>:
 C_SIGNAL='@s9s_mb_2u_lib.s9s_mb_2u(sch_1):m_h_cpu1_sa_rsp(1)';
NODE_NAME     U1 EH47
 '@S9S_MB_2U_LIB.S9S_MB_2U(SCH_1):PAGE58_I20@PURE_QUANTA.SOCKET4677_AZIF0045P001C01CS(CHIPS)':
 'DDR7_A_RSP1': CDS_PINID='DDR7_A_RSP1';
NODE_NAME     J32 86
 '@S9S_MB_2U_LIB.S9S_MB_2U(SCH_1):PAGE113_I179@PURE_QUANTA.SCONN288_ADR50017P087CC(CHIPS)':
 'LBD||RSP_A_N': CDS_PINID='\lbd||rsp_a_n\';
NET_NAME
'M_H_CPU1_SB_CA<0>'
 '@S9S_MB_2U_LIB.S9S_MB_2U(SCH_1):M_H_CPU1_SB_CA'<0>:
 C_SIGNAL='@s9s_mb_2u_lib.s9s_mb_2u(sch_1):m_h_cpu1_sb_ca(0)';
NODE_NAME     U1 DF40
 '@S9S_MB_2U_LIB.S9S_MB_2U(SCH_1):PAGE58_I20@PURE_QUANTA.SOCKET4677_AZIF0045P001C01CS(CHIPS)':
 'DDR7_SB_CA0': CDS_PINID='DDR7_SB_CA0';
NODE_NAME     J31 76
 '@S9S_MB_2U_LIB.S9S_MB_2U(SCH_1):PAGE112_I180@PURE_QUANTA.SCONN288_ADR50017P130CC(CHIPS)':
 'CA0_B': CDS_PINID='CA0_B';
NODE_NAME     J32 76
 '@S9S_MB_2U_LIB.S9S_MB_2U(SCH_1):PAGE113_I179@PURE_QUANTA.SCONN288_ADR50017P087CC(CHIPS)':
 'CA0_B': CDS_PINID='CA0_B';
NET_NAME
'M_H_CPU1_SB_CA<1>'
 '@S9S_MB_2U_LIB.S9S_MB_2U(SCH_1):M_H_CPU1_SB_CA'<1>:
 C_SIGNAL='@s9s_mb_2u_lib.s9s_mb_2u(sch_1):m_h_cpu1_sb_ca(1)';
NODE_NAME     U1 DG41
 '@S9S_MB_2U_LIB.S9S_MB_2U(SCH_1):PAGE58_I20@PURE_QUANTA.SOCKET4677_AZIF0045P001C01CS(CHIPS)':
 'DDR7_SB_CA1': CDS_PINID='DDR7_SB_CA1';
NODE_NAME     J31 221
 '@S9S_MB_2U_LIB.S9S_MB_2U(SCH_1):PAGE112_I180@PURE_QUANTA.SCONN288_ADR50017P130CC(CHIPS)':
 'CA1_B': CDS_PINID='CA1_B';
NODE_NAME     J32 221
 '@S9S_MB_2U_LIB.S9S_MB_2U(SCH_1):PAGE113_I179@PURE_QUANTA.SCONN288_ADR50017P087CC(CHIPS)':
 'CA1_B': CDS_PINID='CA1_B';
NET_NAME
'M_H_CPU1_SB_CA<2>'
 '@S9S_MB_2U_LIB.S9S_MB_2U(SCH_1):M_H_CPU1_SB_CA'<2>:
 C_SIGNAL='@s9s_mb_2u_lib.s9s_mb_2u(sch_1):m_h_cpu1_sb_ca(2)';
NODE_NAME     U1 DL41
 '@S9S_MB_2U_LIB.S9S_MB_2U(SCH_1):PAGE58_I20@PURE_QUANTA.SOCKET4677_AZIF0045P001C01CS(CHIPS)':
 'DDR7_SB_CA2': CDS_PINID='DDR7_SB_CA2';
NODE_NAME     J31 78
 '@S9S_MB_2U_LIB.S9S_MB_2U(SCH_1):PAGE112_I180@PURE_QUANTA.SCONN288_ADR50017P130CC(CHIPS)':
 'CA2_B': CDS_PINID='CA2_B';
NODE_NAME     J32 78
 '@S9S_MB_2U_LIB.S9S_MB_2U(SCH_1):PAGE113_I179@PURE_QUANTA.SCONN288_ADR50017P087CC(CHIPS)':
 'CA2_B': CDS_PINID='CA2_B';
NET_NAME
'M_H_CPU1_SB_CA<3>'
 '@S9S_MB_2U_LIB.S9S_MB_2U(SCH_1):M_H_CPU1_SB_CA'<3>:
 C_SIGNAL='@s9s_mb_2u_lib.s9s_mb_2u(sch_1):m_h_cpu1_sb_ca(3)';
NODE_NAME     U1 DN41
 '@S9S_MB_2U_LIB.S9S_MB_2U(SCH_1):PAGE58_I20@PURE_QUANTA.SOCKET4677_AZIF0045P001C01CS(CHIPS)':
 'DDR7_SB_CA3': CDS_PINID='DDR7_SB_CA3';
NODE_NAME     J31 223
 '@S9S_MB_2U_LIB.S9S_MB_2U(SCH_1):PAGE112_I180@PURE_QUANTA.SCONN288_ADR50017P130CC(CHIPS)':
 'CA3_B': CDS_PINID='CA3_B';
NODE_NAME     J32 223
 '@S9S_MB_2U_LIB.S9S_MB_2U(SCH_1):PAGE113_I179@PURE_QUANTA.SCONN288_ADR50017P087CC(CHIPS)':
 'CA3_B': CDS_PINID='CA3_B';
NET_NAME
'M_H_CPU1_SB_CA<4>'
 '@S9S_MB_2U_LIB.S9S_MB_2U(SCH_1):M_H_CPU1_SB_CA'<4>:
 C_SIGNAL='@s9s_mb_2u_lib.s9s_mb_2u(sch_1):m_h_cpu1_sb_ca(4)';
NODE_NAME     U1 DK40
 '@S9S_MB_2U_LIB.S9S_MB_2U(SCH_1):PAGE58_I20@PURE_QUANTA.SOCKET4677_AZIF0045P001C01CS(CHIPS)':
 'DDR7_SB_CA4': CDS_PINID='DDR7_SB_CA4';
NODE_NAME     J31 80
 '@S9S_MB_2U_LIB.S9S_MB_2U(SCH_1):PAGE112_I180@PURE_QUANTA.SCONN288_ADR50017P130CC(CHIPS)':
 'CA4_B': CDS_PINID='CA4_B';
NODE_NAME     J32 80
 '@S9S_MB_2U_LIB.S9S_MB_2U(SCH_1):PAGE113_I179@PURE_QUANTA.SCONN288_ADR50017P087CC(CHIPS)':
 'CA4_B': CDS_PINID='CA4_B';
NET_NAME
'M_H_CPU1_SB_CA<5>'
 '@S9S_MB_2U_LIB.S9S_MB_2U(SCH_1):M_H_CPU1_SB_CA'<5>:
 C_SIGNAL='@s9s_mb_2u_lib.s9s_mb_2u(sch_1):m_h_cpu1_sb_ca(5)';
NODE_NAME     U1 DP40
 '@S9S_MB_2U_LIB.S9S_MB_2U(SCH_1):PAGE58_I20@PURE_QUANTA.SOCKET4677_AZIF0045P001C01CS(CHIPS)':
 'DDR7_SB_CA5': CDS_PINID='DDR7_SB_CA5';
NODE_NAME     J31 225
 '@S9S_MB_2U_LIB.S9S_MB_2U(SCH_1):PAGE112_I180@PURE_QUANTA.SCONN288_ADR50017P130CC(CHIPS)':
 'CA5_B': CDS_PINID='CA5_B';
NODE_NAME     J32 225
 '@S9S_MB_2U_LIB.S9S_MB_2U(SCH_1):PAGE113_I179@PURE_QUANTA.SCONN288_ADR50017P087CC(CHIPS)':
 'CA5_B': CDS_PINID='CA5_B';
NET_NAME
'M_H_CPU1_SB_CA<6>'
 '@S9S_MB_2U_LIB.S9S_MB_2U(SCH_1):M_H_CPU1_SB_CA'<6>:
 C_SIGNAL='@s9s_mb_2u_lib.s9s_mb_2u(sch_1):m_h_cpu1_sb_ca(6)';
NODE_NAME     U1 DJ39
 '@S9S_MB_2U_LIB.S9S_MB_2U(SCH_1):PAGE58_I20@PURE_QUANTA.SOCKET4677_AZIF0045P001C01CS(CHIPS)':
 'DDR7_SB_CA6': CDS_PINID='DDR7_SB_CA6';
NODE_NAME     J31 82
 '@S9S_MB_2U_LIB.S9S_MB_2U(SCH_1):PAGE112_I180@PURE_QUANTA.SCONN288_ADR50017P130CC(CHIPS)':
 'CA6_B': CDS_PINID='CA6_B';
NODE_NAME     J32 82
 '@S9S_MB_2U_LIB.S9S_MB_2U(SCH_1):PAGE113_I179@PURE_QUANTA.SCONN288_ADR50017P087CC(CHIPS)':
 'CA6_B': CDS_PINID='CA6_B';
NET_NAME
'M_H_CPU1_SB_CB<0>'
 '@S9S_MB_2U_LIB.S9S_MB_2U(SCH_1):M_H_CPU1_SB_CB'<0>:
 C_SIGNAL='@s9s_mb_2u_lib.s9s_mb_2u(sch_1):m_h_cpu1_sb_cb(0)';
NODE_NAME     U1 DC35
 '@S9S_MB_2U_LIB.S9S_MB_2U(SCH_1):PAGE58_I20@PURE_QUANTA.SOCKET4677_AZIF0045P001C01CS(CHIPS)':
 'DDR7_SB_ECC0': CDS_PINID='DDR7_SB_ECC0';
NODE_NAME     J31 96
 '@S9S_MB_2U_LIB.S9S_MB_2U(SCH_1):PAGE112_I180@PURE_QUANTA.SCONN288_ADR50017P130CC(CHIPS)':
 'CB0_B': CDS_PINID='CB0_B';
NODE_NAME     J32 96
 '@S9S_MB_2U_LIB.S9S_MB_2U(SCH_1):PAGE113_I179@PURE_QUANTA.SCONN288_ADR50017P087CC(CHIPS)':
 'CB0_B': CDS_PINID='CB0_B';
NET_NAME
'M_H_CPU1_SB_CB<1>'
 '@S9S_MB_2U_LIB.S9S_MB_2U(SCH_1):M_H_CPU1_SB_CB'<1>:
 C_SIGNAL='@s9s_mb_2u_lib.s9s_mb_2u(sch_1):m_h_cpu1_sb_cb(1)';
NODE_NAME     U1 DD34
 '@S9S_MB_2U_LIB.S9S_MB_2U(SCH_1):PAGE58_I20@PURE_QUANTA.SOCKET4677_AZIF0045P001C01CS(CHIPS)':
 'DDR7_SB_ECC1': CDS_PINID='DDR7_SB_ECC1';
NODE_NAME     J31 98
 '@S9S_MB_2U_LIB.S9S_MB_2U(SCH_1):PAGE112_I180@PURE_QUANTA.SCONN288_ADR50017P130CC(CHIPS)':
 'CB1_B': CDS_PINID='CB1_B';
NODE_NAME     J32 98
 '@S9S_MB_2U_LIB.S9S_MB_2U(SCH_1):PAGE113_I179@PURE_QUANTA.SCONN288_ADR50017P087CC(CHIPS)':
 'CB1_B': CDS_PINID='CB1_B';
NET_NAME
'M_H_CPU1_SB_CB<2>'
 '@S9S_MB_2U_LIB.S9S_MB_2U(SCH_1):M_H_CPU1_SB_CB'<2>:
 C_SIGNAL='@s9s_mb_2u_lib.s9s_mb_2u(sch_1):m_h_cpu1_sb_cb(2)';
NODE_NAME     U1 DG35
 '@S9S_MB_2U_LIB.S9S_MB_2U(SCH_1):PAGE58_I20@PURE_QUANTA.SOCKET4677_AZIF0045P001C01CS(CHIPS)':
 'DDR7_SB_ECC2': CDS_PINID='DDR7_SB_ECC2';
NODE_NAME     J31 241
 '@S9S_MB_2U_LIB.S9S_MB_2U(SCH_1):PAGE112_I180@PURE_QUANTA.SCONN288_ADR50017P130CC(CHIPS)':
 'CB2_B': CDS_PINID='CB2_B';
NODE_NAME     J32 241
 '@S9S_MB_2U_LIB.S9S_MB_2U(SCH_1):PAGE113_I179@PURE_QUANTA.SCONN288_ADR50017P087CC(CHIPS)':
 'CB2_B': CDS_PINID='CB2_B';
NET_NAME
'M_H_CPU1_SB_CB<3>'
 '@S9S_MB_2U_LIB.S9S_MB_2U(SCH_1):M_H_CPU1_SB_CB'<3>:
 C_SIGNAL='@s9s_mb_2u_lib.s9s_mb_2u(sch_1):m_h_cpu1_sb_cb(3)';
NODE_NAME     U1 DF34
 '@S9S_MB_2U_LIB.S9S_MB_2U(SCH_1):PAGE58_I20@PURE_QUANTA.SOCKET4677_AZIF0045P001C01CS(CHIPS)':
 'DDR7_SB_ECC3': CDS_PINID='DDR7_SB_ECC3';
NODE_NAME     J31 243
 '@S9S_MB_2U_LIB.S9S_MB_2U(SCH_1):PAGE112_I180@PURE_QUANTA.SCONN288_ADR50017P130CC(CHIPS)':
 'CB3_B': CDS_PINID='CB3_B';
NODE_NAME     J32 243
 '@S9S_MB_2U_LIB.S9S_MB_2U(SCH_1):PAGE113_I179@PURE_QUANTA.SCONN288_ADR50017P087CC(CHIPS)':
 'CB3_B': CDS_PINID='CB3_B';
NET_NAME
'M_H_CPU1_SB_CB<4>'
 '@S9S_MB_2U_LIB.S9S_MB_2U(SCH_1):M_H_CPU1_SB_CB'<4>:
 C_SIGNAL='@s9s_mb_2u_lib.s9s_mb_2u(sch_1):m_h_cpu1_sb_cb(4)';
NODE_NAME     U1 DF38
 '@S9S_MB_2U_LIB.S9S_MB_2U(SCH_1):PAGE58_I20@PURE_QUANTA.SOCKET4677_AZIF0045P001C01CS(CHIPS)':
 'DDR7_SB_ECC4': CDS_PINID='DDR7_SB_ECC4';
NODE_NAME     J31 89
 '@S9S_MB_2U_LIB.S9S_MB_2U(SCH_1):PAGE112_I180@PURE_QUANTA.SCONN288_ADR50017P130CC(CHIPS)':
 'CB4_B': CDS_PINID='CB4_B';
NODE_NAME     J32 89
 '@S9S_MB_2U_LIB.S9S_MB_2U(SCH_1):PAGE113_I179@PURE_QUANTA.SCONN288_ADR50017P087CC(CHIPS)':
 'CB4_B': CDS_PINID='CB4_B';
NET_NAME
'M_H_CPU1_SB_CB<5>'
 '@S9S_MB_2U_LIB.S9S_MB_2U(SCH_1):M_H_CPU1_SB_CB'<5>:
 C_SIGNAL='@s9s_mb_2u_lib.s9s_mb_2u(sch_1):m_h_cpu1_sb_cb(5)';
NODE_NAME     U1 DG37
 '@S9S_MB_2U_LIB.S9S_MB_2U(SCH_1):PAGE58_I20@PURE_QUANTA.SOCKET4677_AZIF0045P001C01CS(CHIPS)':
 'DDR7_SB_ECC5': CDS_PINID='DDR7_SB_ECC5';
NODE_NAME     J31 91
 '@S9S_MB_2U_LIB.S9S_MB_2U(SCH_1):PAGE112_I180@PURE_QUANTA.SCONN288_ADR50017P130CC(CHIPS)':
 'CB5_B': CDS_PINID='CB5_B';
NODE_NAME     J32 91
 '@S9S_MB_2U_LIB.S9S_MB_2U(SCH_1):PAGE113_I179@PURE_QUANTA.SCONN288_ADR50017P087CC(CHIPS)':
 'CB5_B': CDS_PINID='CB5_B';
NET_NAME
'M_H_CPU1_SB_CB<6>'
 '@S9S_MB_2U_LIB.S9S_MB_2U(SCH_1):M_H_CPU1_SB_CB'<6>:
 C_SIGNAL='@s9s_mb_2u_lib.s9s_mb_2u(sch_1):m_h_cpu1_sb_cb(6)';
NODE_NAME     U1 DD38
 '@S9S_MB_2U_LIB.S9S_MB_2U(SCH_1):PAGE58_I20@PURE_QUANTA.SOCKET4677_AZIF0045P001C01CS(CHIPS)':
 'DDR7_SB_ECC6': CDS_PINID='DDR7_SB_ECC6';
NODE_NAME     J31 234
 '@S9S_MB_2U_LIB.S9S_MB_2U(SCH_1):PAGE112_I180@PURE_QUANTA.SCONN288_ADR50017P130CC(CHIPS)':
 'CB6_B': CDS_PINID='CB6_B';
NODE_NAME     J32 234
 '@S9S_MB_2U_LIB.S9S_MB_2U(SCH_1):PAGE113_I179@PURE_QUANTA.SCONN288_ADR50017P087CC(CHIPS)':
 'CB6_B': CDS_PINID='CB6_B';
NET_NAME
'M_H_CPU1_SB_CB<7>'
 '@S9S_MB_2U_LIB.S9S_MB_2U(SCH_1):M_H_CPU1_SB_CB'<7>:
 C_SIGNAL='@s9s_mb_2u_lib.s9s_mb_2u(sch_1):m_h_cpu1_sb_cb(7)';
NODE_NAME     U1 DC37
 '@S9S_MB_2U_LIB.S9S_MB_2U(SCH_1):PAGE58_I20@PURE_QUANTA.SOCKET4677_AZIF0045P001C01CS(CHIPS)':
 'DDR7_SB_ECC7': CDS_PINID='DDR7_SB_ECC7';
NODE_NAME     J31 236
 '@S9S_MB_2U_LIB.S9S_MB_2U(SCH_1):PAGE112_I180@PURE_QUANTA.SCONN288_ADR50017P130CC(CHIPS)':
 'CB7_B': CDS_PINID='CB7_B';
NODE_NAME     J32 236
 '@S9S_MB_2U_LIB.S9S_MB_2U(SCH_1):PAGE113_I179@PURE_QUANTA.SCONN288_ADR50017P087CC(CHIPS)':
 'CB7_B': CDS_PINID='CB7_B';
NET_NAME
'M_H_CPU1_SB_CS_N<0>'
 '@S9S_MB_2U_LIB.S9S_MB_2U(SCH_1):M_H_CPU1_SB_CS_N'<0>:
 C_SIGNAL='@s9s_mb_2u_lib.s9s_mb_2u(sch_1):m_h_cpu1_sb_cs_n(0)';
NODE_NAME     U1 DL37
 '@S9S_MB_2U_LIB.S9S_MB_2U(SCH_1):PAGE58_I20@PURE_QUANTA.SOCKET4677_AZIF0045P001C01CS(CHIPS)':
 'DDR7_SB_CS_N0': CDS_PINID='DDR7_SB_CS_N0';
NODE_NAME     J31 84
 '@S9S_MB_2U_LIB.S9S_MB_2U(SCH_1):PAGE112_I180@PURE_QUANTA.SCONN288_ADR50017P130CC(CHIPS)':
 'CS0_B_N': CDS_PINID='CS0_B_N';
NET_NAME
'M_H_CPU1_SB_CS_N<1>'
 '@S9S_MB_2U_LIB.S9S_MB_2U(SCH_1):M_H_CPU1_SB_CS_N'<1>:
 C_SIGNAL='@s9s_mb_2u_lib.s9s_mb_2u(sch_1):m_h_cpu1_sb_cs_n(1)';
NODE_NAME     U1 DN37
 '@S9S_MB_2U_LIB.S9S_MB_2U(SCH_1):PAGE58_I20@PURE_QUANTA.SOCKET4677_AZIF0045P001C01CS(CHIPS)':
 'DDR7_SB_CS_N1': CDS_PINID='DDR7_SB_CS_N1';
NODE_NAME     J31 229
 '@S9S_MB_2U_LIB.S9S_MB_2U(SCH_1):PAGE112_I180@PURE_QUANTA.SCONN288_ADR50017P130CC(CHIPS)':
 'CS1_B_N': CDS_PINID='CS1_B_N';
NET_NAME
'M_H_CPU1_SB_CS_N<2>'
 '@S9S_MB_2U_LIB.S9S_MB_2U(SCH_1):M_H_CPU1_SB_CS_N'<2>:
 C_SIGNAL='@s9s_mb_2u_lib.s9s_mb_2u(sch_1):m_h_cpu1_sb_cs_n(2)';
NODE_NAME     U1 DK38
 '@S9S_MB_2U_LIB.S9S_MB_2U(SCH_1):PAGE58_I20@PURE_QUANTA.SOCKET4677_AZIF0045P001C01CS(CHIPS)':
 'DDR7_SB_CS_N2': CDS_PINID='DDR7_SB_CS_N2';
NODE_NAME     J32 84
 '@S9S_MB_2U_LIB.S9S_MB_2U(SCH_1):PAGE113_I179@PURE_QUANTA.SCONN288_ADR50017P087CC(CHIPS)':
 'CS0_B_N': CDS_PINID='CS0_B_N';
NET_NAME
'M_H_CPU1_SB_CS_N<3>'
 '@S9S_MB_2U_LIB.S9S_MB_2U(SCH_1):M_H_CPU1_SB_CS_N'<3>:
 C_SIGNAL='@s9s_mb_2u_lib.s9s_mb_2u(sch_1):m_h_cpu1_sb_cs_n(3)';
NODE_NAME     U1 DP38
 '@S9S_MB_2U_LIB.S9S_MB_2U(SCH_1):PAGE58_I20@PURE_QUANTA.SOCKET4677_AZIF0045P001C01CS(CHIPS)':
 'DDR7_SB_CS_N3': CDS_PINID='DDR7_SB_CS_N3';
NODE_NAME     J32 229
 '@S9S_MB_2U_LIB.S9S_MB_2U(SCH_1):PAGE113_I179@PURE_QUANTA.SCONN288_ADR50017P087CC(CHIPS)':
 'CS1_B_N': CDS_PINID='CS1_B_N';
NET_NAME
'M_H_CPU1_SB_DQ<0>'
 '@S9S_MB_2U_LIB.S9S_MB_2U(SCH_1):M_H_CPU1_SB_DQ'<0>:
 C_SIGNAL='@s9s_mb_2u_lib.s9s_mb_2u(sch_1):m_h_cpu1_sb_dq(0)';
NODE_NAME     U1 DD32
 '@S9S_MB_2U_LIB.S9S_MB_2U(SCH_1):PAGE58_I20@PURE_QUANTA.SOCKET4677_AZIF0045P001C01CS(CHIPS)':
 'DDR7_SB_DQ0': CDS_PINID='DDR7_SB_DQ0';
NODE_NAME     J31 100
 '@S9S_MB_2U_LIB.S9S_MB_2U(SCH_1):PAGE112_I180@PURE_QUANTA.SCONN288_ADR50017P130CC(CHIPS)':
 'DQ0_B': CDS_PINID='DQ0_B';
NODE_NAME     J32 100
 '@S9S_MB_2U_LIB.S9S_MB_2U(SCH_1):PAGE113_I179@PURE_QUANTA.SCONN288_ADR50017P087CC(CHIPS)':
 'DQ0_B': CDS_PINID='DQ0_B';
NET_NAME
'M_H_CPU1_SB_DQ<10>'
 '@S9S_MB_2U_LIB.S9S_MB_2U(SCH_1):M_H_CPU1_SB_DQ'<10>:
 C_SIGNAL='@s9s_mb_2u_lib.s9s_mb_2u(sch_1):m_h_cpu1_sb_dq(10)';
NODE_NAME     U1 DF26
 '@S9S_MB_2U_LIB.S9S_MB_2U(SCH_1):PAGE58_I20@PURE_QUANTA.SOCKET4677_AZIF0045P001C01CS(CHIPS)':
 'DDR7_SB_DQ10': CDS_PINID='DDR7_SB_DQ10';
NODE_NAME     J31 256
 '@S9S_MB_2U_LIB.S9S_MB_2U(SCH_1):PAGE112_I180@PURE_QUANTA.SCONN288_ADR50017P130CC(CHIPS)':
 'DQ10_B': CDS_PINID='DQ10_B';
NODE_NAME     J32 256
 '@S9S_MB_2U_LIB.S9S_MB_2U(SCH_1):PAGE113_I179@PURE_QUANTA.SCONN288_ADR50017P087CC(CHIPS)':
 'DQ10_B': CDS_PINID='DQ10_B';
NET_NAME
'M_H_CPU1_SB_DQ<11>'
 '@S9S_MB_2U_LIB.S9S_MB_2U(SCH_1):M_H_CPU1_SB_DQ'<11>:
 C_SIGNAL='@s9s_mb_2u_lib.s9s_mb_2u(sch_1):m_h_cpu1_sb_dq(11)';
NODE_NAME     U1 DG25
 '@S9S_MB_2U_LIB.S9S_MB_2U(SCH_1):PAGE58_I20@PURE_QUANTA.SOCKET4677_AZIF0045P001C01CS(CHIPS)':
 'DDR7_SB_DQ11': CDS_PINID='DDR7_SB_DQ11';
NODE_NAME     J31 258
 '@S9S_MB_2U_LIB.S9S_MB_2U(SCH_1):PAGE112_I180@PURE_QUANTA.SCONN288_ADR50017P130CC(CHIPS)':
 'DQ11_B': CDS_PINID='DQ11_B';
NODE_NAME     J32 258
 '@S9S_MB_2U_LIB.S9S_MB_2U(SCH_1):PAGE113_I179@PURE_QUANTA.SCONN288_ADR50017P087CC(CHIPS)':
 'DQ11_B': CDS_PINID='DQ11_B';
NET_NAME
'M_H_CPU1_SB_DQ<12>'
 '@S9S_MB_2U_LIB.S9S_MB_2U(SCH_1):M_H_CPU1_SB_DQ'<12>:
 C_SIGNAL='@s9s_mb_2u_lib.s9s_mb_2u(sch_1):m_h_cpu1_sb_dq(12)';
NODE_NAME     U1 DC23
 '@S9S_MB_2U_LIB.S9S_MB_2U(SCH_1):PAGE58_I20@PURE_QUANTA.SOCKET4677_AZIF0045P001C01CS(CHIPS)':
 'DDR7_SB_DQ12': CDS_PINID='DDR7_SB_DQ12';
NODE_NAME     J31 118
 '@S9S_MB_2U_LIB.S9S_MB_2U(SCH_1):PAGE112_I180@PURE_QUANTA.SCONN288_ADR50017P130CC(CHIPS)':
 'DQ12_B': CDS_PINID='DQ12_B';
NODE_NAME     J32 118
 '@S9S_MB_2U_LIB.S9S_MB_2U(SCH_1):PAGE113_I179@PURE_QUANTA.SCONN288_ADR50017P087CC(CHIPS)':
 'DQ12_B': CDS_PINID='DQ12_B';
NET_NAME
'M_H_CPU1_SB_DQ<13>'
 '@S9S_MB_2U_LIB.S9S_MB_2U(SCH_1):M_H_CPU1_SB_DQ'<13>:
 C_SIGNAL='@s9s_mb_2u_lib.s9s_mb_2u(sch_1):m_h_cpu1_sb_dq(13)';
NODE_NAME     U1 DD22
 '@S9S_MB_2U_LIB.S9S_MB_2U(SCH_1):PAGE58_I20@PURE_QUANTA.SOCKET4677_AZIF0045P001C01CS(CHIPS)':
 'DDR7_SB_DQ13': CDS_PINID='DDR7_SB_DQ13';
NODE_NAME     J31 120
 '@S9S_MB_2U_LIB.S9S_MB_2U(SCH_1):PAGE112_I180@PURE_QUANTA.SCONN288_ADR50017P130CC(CHIPS)':
 'DQ13_B': CDS_PINID='DQ13_B';
NODE_NAME     J32 120
 '@S9S_MB_2U_LIB.S9S_MB_2U(SCH_1):PAGE113_I179@PURE_QUANTA.SCONN288_ADR50017P087CC(CHIPS)':
 'DQ13_B': CDS_PINID='DQ13_B';
NET_NAME
'M_H_CPU1_SB_DQ<14>'
 '@S9S_MB_2U_LIB.S9S_MB_2U(SCH_1):M_H_CPU1_SB_DQ'<14>:
 C_SIGNAL='@s9s_mb_2u_lib.s9s_mb_2u(sch_1):m_h_cpu1_sb_dq(14)';
NODE_NAME     U1 DG23
 '@S9S_MB_2U_LIB.S9S_MB_2U(SCH_1):PAGE58_I20@PURE_QUANTA.SOCKET4677_AZIF0045P001C01CS(CHIPS)':
 'DDR7_SB_DQ14': CDS_PINID='DDR7_SB_DQ14';
NODE_NAME     J31 263
 '@S9S_MB_2U_LIB.S9S_MB_2U(SCH_1):PAGE112_I180@PURE_QUANTA.SCONN288_ADR50017P130CC(CHIPS)':
 'DQ14_B': CDS_PINID='DQ14_B';
NODE_NAME     J32 263
 '@S9S_MB_2U_LIB.S9S_MB_2U(SCH_1):PAGE113_I179@PURE_QUANTA.SCONN288_ADR50017P087CC(CHIPS)':
 'DQ14_B': CDS_PINID='DQ14_B';
NET_NAME
'M_H_CPU1_SB_DQ<15>'
 '@S9S_MB_2U_LIB.S9S_MB_2U(SCH_1):M_H_CPU1_SB_DQ'<15>:
 C_SIGNAL='@s9s_mb_2u_lib.s9s_mb_2u(sch_1):m_h_cpu1_sb_dq(15)';
NODE_NAME     U1 DF22
 '@S9S_MB_2U_LIB.S9S_MB_2U(SCH_1):PAGE58_I20@PURE_QUANTA.SOCKET4677_AZIF0045P001C01CS(CHIPS)':
 'DDR7_SB_DQ15': CDS_PINID='DDR7_SB_DQ15';
NODE_NAME     J31 265
 '@S9S_MB_2U_LIB.S9S_MB_2U(SCH_1):PAGE112_I180@PURE_QUANTA.SCONN288_ADR50017P130CC(CHIPS)':
 'DQ15_B': CDS_PINID='DQ15_B';
NODE_NAME     J32 265
 '@S9S_MB_2U_LIB.S9S_MB_2U(SCH_1):PAGE113_I179@PURE_QUANTA.SCONN288_ADR50017P087CC(CHIPS)':
 'DQ15_B': CDS_PINID='DQ15_B';
NET_NAME
'M_H_CPU1_SB_DQ<16>'
 '@S9S_MB_2U_LIB.S9S_MB_2U(SCH_1):M_H_CPU1_SB_DQ'<16>:
 C_SIGNAL='@s9s_mb_2u_lib.s9s_mb_2u(sch_1):m_h_cpu1_sb_dq(16)';
NODE_NAME     U1 DL23
 '@S9S_MB_2U_LIB.S9S_MB_2U(SCH_1):PAGE58_I20@PURE_QUANTA.SOCKET4677_AZIF0045P001C01CS(CHIPS)':
 'DDR7_SB_DQ16': CDS_PINID='DDR7_SB_DQ16';
NODE_NAME     J31 122
 '@S9S_MB_2U_LIB.S9S_MB_2U(SCH_1):PAGE112_I180@PURE_QUANTA.SCONN288_ADR50017P130CC(CHIPS)':
 'DQ16_B': CDS_PINID='DQ16_B';
NODE_NAME     J32 122
 '@S9S_MB_2U_LIB.S9S_MB_2U(SCH_1):PAGE113_I179@PURE_QUANTA.SCONN288_ADR50017P087CC(CHIPS)':
 'DQ16_B': CDS_PINID='DQ16_B';
NET_NAME
'M_H_CPU1_SB_DQ<17>'
 '@S9S_MB_2U_LIB.S9S_MB_2U(SCH_1):M_H_CPU1_SB_DQ'<17>:
 C_SIGNAL='@s9s_mb_2u_lib.s9s_mb_2u(sch_1):m_h_cpu1_sb_dq(17)';
NODE_NAME     U1 DK22
 '@S9S_MB_2U_LIB.S9S_MB_2U(SCH_1):PAGE58_I20@PURE_QUANTA.SOCKET4677_AZIF0045P001C01CS(CHIPS)':
 'DDR7_SB_DQ17': CDS_PINID='DDR7_SB_DQ17';
NODE_NAME     J31 124
 '@S9S_MB_2U_LIB.S9S_MB_2U(SCH_1):PAGE112_I180@PURE_QUANTA.SCONN288_ADR50017P130CC(CHIPS)':
 'DQ17_B': CDS_PINID='DQ17_B';
NODE_NAME     J32 124
 '@S9S_MB_2U_LIB.S9S_MB_2U(SCH_1):PAGE113_I179@PURE_QUANTA.SCONN288_ADR50017P087CC(CHIPS)':
 'DQ17_B': CDS_PINID='DQ17_B';
NET_NAME
'M_H_CPU1_SB_DQ<18>'
 '@S9S_MB_2U_LIB.S9S_MB_2U(SCH_1):M_H_CPU1_SB_DQ'<18>:
 C_SIGNAL='@s9s_mb_2u_lib.s9s_mb_2u(sch_1):m_h_cpu1_sb_dq(18)';
NODE_NAME     U1 DN23
 '@S9S_MB_2U_LIB.S9S_MB_2U(SCH_1):PAGE58_I20@PURE_QUANTA.SOCKET4677_AZIF0045P001C01CS(CHIPS)':
 'DDR7_SB_DQ18': CDS_PINID='DDR7_SB_DQ18';
NODE_NAME     J31 267
 '@S9S_MB_2U_LIB.S9S_MB_2U(SCH_1):PAGE112_I180@PURE_QUANTA.SCONN288_ADR50017P130CC(CHIPS)':
 'DQ18_B': CDS_PINID='DQ18_B';
NODE_NAME     J32 267
 '@S9S_MB_2U_LIB.S9S_MB_2U(SCH_1):PAGE113_I179@PURE_QUANTA.SCONN288_ADR50017P087CC(CHIPS)':
 'DQ18_B': CDS_PINID='DQ18_B';
NET_NAME
'M_H_CPU1_SB_DQ<19>'
 '@S9S_MB_2U_LIB.S9S_MB_2U(SCH_1):M_H_CPU1_SB_DQ'<19>:
 C_SIGNAL='@s9s_mb_2u_lib.s9s_mb_2u(sch_1):m_h_cpu1_sb_dq(19)';
NODE_NAME     U1 DP22
 '@S9S_MB_2U_LIB.S9S_MB_2U(SCH_1):PAGE58_I20@PURE_QUANTA.SOCKET4677_AZIF0045P001C01CS(CHIPS)':
 'DDR7_SB_DQ19': CDS_PINID='DDR7_SB_DQ19';
NODE_NAME     J31 269
 '@S9S_MB_2U_LIB.S9S_MB_2U(SCH_1):PAGE112_I180@PURE_QUANTA.SCONN288_ADR50017P130CC(CHIPS)':
 'DQ19_B': CDS_PINID='DQ19_B';
NODE_NAME     J32 269
 '@S9S_MB_2U_LIB.S9S_MB_2U(SCH_1):PAGE113_I179@PURE_QUANTA.SCONN288_ADR50017P087CC(CHIPS)':
 'DQ19_B': CDS_PINID='DQ19_B';
NET_NAME
'M_H_CPU1_SB_DQ<1>'
 '@S9S_MB_2U_LIB.S9S_MB_2U(SCH_1):M_H_CPU1_SB_DQ'<1>:
 C_SIGNAL='@s9s_mb_2u_lib.s9s_mb_2u(sch_1):m_h_cpu1_sb_dq(1)';
NODE_NAME     U1 DC31
 '@S9S_MB_2U_LIB.S9S_MB_2U(SCH_1):PAGE58_I20@PURE_QUANTA.SOCKET4677_AZIF0045P001C01CS(CHIPS)':
 'DDR7_SB_DQ1': CDS_PINID='DDR7_SB_DQ1';
NODE_NAME     J31 102
 '@S9S_MB_2U_LIB.S9S_MB_2U(SCH_1):PAGE112_I180@PURE_QUANTA.SCONN288_ADR50017P130CC(CHIPS)':
 'DQ1_B': CDS_PINID='DQ1_B';
NODE_NAME     J32 102
 '@S9S_MB_2U_LIB.S9S_MB_2U(SCH_1):PAGE113_I179@PURE_QUANTA.SCONN288_ADR50017P087CC(CHIPS)':
 'DQ1_B': CDS_PINID='DQ1_B';
NET_NAME
'M_H_CPU1_SB_DQ<20>'
 '@S9S_MB_2U_LIB.S9S_MB_2U(SCH_1):M_H_CPU1_SB_DQ'<20>:
 C_SIGNAL='@s9s_mb_2u_lib.s9s_mb_2u(sch_1):m_h_cpu1_sb_dq(20)';
NODE_NAME     U1 DK20
 '@S9S_MB_2U_LIB.S9S_MB_2U(SCH_1):PAGE58_I20@PURE_QUANTA.SOCKET4677_AZIF0045P001C01CS(CHIPS)':
 'DDR7_SB_DQ20': CDS_PINID='DDR7_SB_DQ20';
NODE_NAME     J31 129
 '@S9S_MB_2U_LIB.S9S_MB_2U(SCH_1):PAGE112_I180@PURE_QUANTA.SCONN288_ADR50017P130CC(CHIPS)':
 'DQ20_B': CDS_PINID='DQ20_B';
NODE_NAME     J32 129
 '@S9S_MB_2U_LIB.S9S_MB_2U(SCH_1):PAGE113_I179@PURE_QUANTA.SCONN288_ADR50017P087CC(CHIPS)':
 'DQ20_B': CDS_PINID='DQ20_B';
NET_NAME
'M_H_CPU1_SB_DQ<21>'
 '@S9S_MB_2U_LIB.S9S_MB_2U(SCH_1):M_H_CPU1_SB_DQ'<21>:
 C_SIGNAL='@s9s_mb_2u_lib.s9s_mb_2u(sch_1):m_h_cpu1_sb_dq(21)';
NODE_NAME     U1 DL19
 '@S9S_MB_2U_LIB.S9S_MB_2U(SCH_1):PAGE58_I20@PURE_QUANTA.SOCKET4677_AZIF0045P001C01CS(CHIPS)':
 'DDR7_SB_DQ21': CDS_PINID='DDR7_SB_DQ21';
NODE_NAME     J31 131
 '@S9S_MB_2U_LIB.S9S_MB_2U(SCH_1):PAGE112_I180@PURE_QUANTA.SCONN288_ADR50017P130CC(CHIPS)':
 'DQ21_B': CDS_PINID='DQ21_B';
NODE_NAME     J32 131
 '@S9S_MB_2U_LIB.S9S_MB_2U(SCH_1):PAGE113_I179@PURE_QUANTA.SCONN288_ADR50017P087CC(CHIPS)':
 'DQ21_B': CDS_PINID='DQ21_B';
NET_NAME
'M_H_CPU1_SB_DQ<22>'
 '@S9S_MB_2U_LIB.S9S_MB_2U(SCH_1):M_H_CPU1_SB_DQ'<22>:
 C_SIGNAL='@s9s_mb_2u_lib.s9s_mb_2u(sch_1):m_h_cpu1_sb_dq(22)';
NODE_NAME     U1 DP20
 '@S9S_MB_2U_LIB.S9S_MB_2U(SCH_1):PAGE58_I20@PURE_QUANTA.SOCKET4677_AZIF0045P001C01CS(CHIPS)':
 'DDR7_SB_DQ22': CDS_PINID='DDR7_SB_DQ22';
NODE_NAME     J31 274
 '@S9S_MB_2U_LIB.S9S_MB_2U(SCH_1):PAGE112_I180@PURE_QUANTA.SCONN288_ADR50017P130CC(CHIPS)':
 'DQ22_B': CDS_PINID='DQ22_B';
NODE_NAME     J32 274
 '@S9S_MB_2U_LIB.S9S_MB_2U(SCH_1):PAGE113_I179@PURE_QUANTA.SCONN288_ADR50017P087CC(CHIPS)':
 'DQ22_B': CDS_PINID='DQ22_B';
NET_NAME
'M_H_CPU1_SB_DQ<23>'
 '@S9S_MB_2U_LIB.S9S_MB_2U(SCH_1):M_H_CPU1_SB_DQ'<23>:
 C_SIGNAL='@s9s_mb_2u_lib.s9s_mb_2u(sch_1):m_h_cpu1_sb_dq(23)';
NODE_NAME     U1 DN19
 '@S9S_MB_2U_LIB.S9S_MB_2U(SCH_1):PAGE58_I20@PURE_QUANTA.SOCKET4677_AZIF0045P001C01CS(CHIPS)':
 'DDR7_SB_DQ23': CDS_PINID='DDR7_SB_DQ23';
NODE_NAME     J31 276
 '@S9S_MB_2U_LIB.S9S_MB_2U(SCH_1):PAGE112_I180@PURE_QUANTA.SCONN288_ADR50017P130CC(CHIPS)':
 'DQ23_B': CDS_PINID='DQ23_B';
NODE_NAME     J32 276
 '@S9S_MB_2U_LIB.S9S_MB_2U(SCH_1):PAGE113_I179@PURE_QUANTA.SCONN288_ADR50017P087CC(CHIPS)':
 'DQ23_B': CDS_PINID='DQ23_B';
NET_NAME
'M_H_CPU1_SB_DQ<24>'
 '@S9S_MB_2U_LIB.S9S_MB_2U(SCH_1):M_H_CPU1_SB_DQ'<24>:
 C_SIGNAL='@s9s_mb_2u_lib.s9s_mb_2u(sch_1):m_h_cpu1_sb_dq(24)';
NODE_NAME     U1 DD20
 '@S9S_MB_2U_LIB.S9S_MB_2U(SCH_1):PAGE58_I20@PURE_QUANTA.SOCKET4677_AZIF0045P001C01CS(CHIPS)':
 'DDR7_SB_DQ24': CDS_PINID='DDR7_SB_DQ24';
NODE_NAME     J31 133
 '@S9S_MB_2U_LIB.S9S_MB_2U(SCH_1):PAGE112_I180@PURE_QUANTA.SCONN288_ADR50017P130CC(CHIPS)':
 'DQ24_B': CDS_PINID='DQ24_B';
NODE_NAME     J32 133
 '@S9S_MB_2U_LIB.S9S_MB_2U(SCH_1):PAGE113_I179@PURE_QUANTA.SCONN288_ADR50017P087CC(CHIPS)':
 'DQ24_B': CDS_PINID='DQ24_B';
NET_NAME
'M_H_CPU1_SB_DQ<25>'
 '@S9S_MB_2U_LIB.S9S_MB_2U(SCH_1):M_H_CPU1_SB_DQ'<25>:
 C_SIGNAL='@s9s_mb_2u_lib.s9s_mb_2u(sch_1):m_h_cpu1_sb_dq(25)';
NODE_NAME     U1 DC19
 '@S9S_MB_2U_LIB.S9S_MB_2U(SCH_1):PAGE58_I20@PURE_QUANTA.SOCKET4677_AZIF0045P001C01CS(CHIPS)':
 'DDR7_SB_DQ25': CDS_PINID='DDR7_SB_DQ25';
NODE_NAME     J31 135
 '@S9S_MB_2U_LIB.S9S_MB_2U(SCH_1):PAGE112_I180@PURE_QUANTA.SCONN288_ADR50017P130CC(CHIPS)':
 'DQ25_B': CDS_PINID='DQ25_B';
NODE_NAME     J32 135
 '@S9S_MB_2U_LIB.S9S_MB_2U(SCH_1):PAGE113_I179@PURE_QUANTA.SCONN288_ADR50017P087CC(CHIPS)':
 'DQ25_B': CDS_PINID='DQ25_B';
NET_NAME
'M_H_CPU1_SB_DQ<26>'
 '@S9S_MB_2U_LIB.S9S_MB_2U(SCH_1):M_H_CPU1_SB_DQ'<26>:
 C_SIGNAL='@s9s_mb_2u_lib.s9s_mb_2u(sch_1):m_h_cpu1_sb_dq(26)';
NODE_NAME     U1 DF20
 '@S9S_MB_2U_LIB.S9S_MB_2U(SCH_1):PAGE58_I20@PURE_QUANTA.SOCKET4677_AZIF0045P001C01CS(CHIPS)':
 'DDR7_SB_DQ26': CDS_PINID='DDR7_SB_DQ26';
NODE_NAME     J31 278
 '@S9S_MB_2U_LIB.S9S_MB_2U(SCH_1):PAGE112_I180@PURE_QUANTA.SCONN288_ADR50017P130CC(CHIPS)':
 'DQ26_B': CDS_PINID='DQ26_B';
NODE_NAME     J32 278
 '@S9S_MB_2U_LIB.S9S_MB_2U(SCH_1):PAGE113_I179@PURE_QUANTA.SCONN288_ADR50017P087CC(CHIPS)':
 'DQ26_B': CDS_PINID='DQ26_B';
NET_NAME
'M_H_CPU1_SB_DQ<27>'
 '@S9S_MB_2U_LIB.S9S_MB_2U(SCH_1):M_H_CPU1_SB_DQ'<27>:
 C_SIGNAL='@s9s_mb_2u_lib.s9s_mb_2u(sch_1):m_h_cpu1_sb_dq(27)';
NODE_NAME     U1 DG19
 '@S9S_MB_2U_LIB.S9S_MB_2U(SCH_1):PAGE58_I20@PURE_QUANTA.SOCKET4677_AZIF0045P001C01CS(CHIPS)':
 'DDR7_SB_DQ27': CDS_PINID='DDR7_SB_DQ27';
NODE_NAME     J31 280
 '@S9S_MB_2U_LIB.S9S_MB_2U(SCH_1):PAGE112_I180@PURE_QUANTA.SCONN288_ADR50017P130CC(CHIPS)':
 'DQ27_B': CDS_PINID='DQ27_B';
NODE_NAME     J32 280
 '@S9S_MB_2U_LIB.S9S_MB_2U(SCH_1):PAGE113_I179@PURE_QUANTA.SCONN288_ADR50017P087CC(CHIPS)':
 'DQ27_B': CDS_PINID='DQ27_B';
NET_NAME
'M_H_CPU1_SB_DQ<28>'
 '@S9S_MB_2U_LIB.S9S_MB_2U(SCH_1):M_H_CPU1_SB_DQ'<28>:
 C_SIGNAL='@s9s_mb_2u_lib.s9s_mb_2u(sch_1):m_h_cpu1_sb_dq(28)';
NODE_NAME     U1 DG17
 '@S9S_MB_2U_LIB.S9S_MB_2U(SCH_1):PAGE58_I20@PURE_QUANTA.SOCKET4677_AZIF0045P001C01CS(CHIPS)':
 'DDR7_SB_DQ28': CDS_PINID='DDR7_SB_DQ28';
NODE_NAME     J31 140
 '@S9S_MB_2U_LIB.S9S_MB_2U(SCH_1):PAGE112_I180@PURE_QUANTA.SCONN288_ADR50017P130CC(CHIPS)':
 'DQ28_B': CDS_PINID='DQ28_B';
NODE_NAME     J32 140
 '@S9S_MB_2U_LIB.S9S_MB_2U(SCH_1):PAGE113_I179@PURE_QUANTA.SCONN288_ADR50017P087CC(CHIPS)':
 'DQ28_B': CDS_PINID='DQ28_B';
NET_NAME
'M_H_CPU1_SB_DQ<29>'
 '@S9S_MB_2U_LIB.S9S_MB_2U(SCH_1):M_H_CPU1_SB_DQ'<29>:
 C_SIGNAL='@s9s_mb_2u_lib.s9s_mb_2u(sch_1):m_h_cpu1_sb_dq(29)';
NODE_NAME     U1 DA17
 '@S9S_MB_2U_LIB.S9S_MB_2U(SCH_1):PAGE58_I20@PURE_QUANTA.SOCKET4677_AZIF0045P001C01CS(CHIPS)':
 'DDR7_SB_DQ29': CDS_PINID='DDR7_SB_DQ29';
NODE_NAME     J31 142
 '@S9S_MB_2U_LIB.S9S_MB_2U(SCH_1):PAGE112_I180@PURE_QUANTA.SCONN288_ADR50017P130CC(CHIPS)':
 'DQ29_B': CDS_PINID='DQ29_B';
NODE_NAME     J32 142
 '@S9S_MB_2U_LIB.S9S_MB_2U(SCH_1):PAGE113_I179@PURE_QUANTA.SCONN288_ADR50017P087CC(CHIPS)':
 'DQ29_B': CDS_PINID='DQ29_B';
NET_NAME
'M_H_CPU1_SB_DQ<2>'
 '@S9S_MB_2U_LIB.S9S_MB_2U(SCH_1):M_H_CPU1_SB_DQ'<2>:
 C_SIGNAL='@s9s_mb_2u_lib.s9s_mb_2u(sch_1):m_h_cpu1_sb_dq(2)';
NODE_NAME     U1 DF32
 '@S9S_MB_2U_LIB.S9S_MB_2U(SCH_1):PAGE58_I20@PURE_QUANTA.SOCKET4677_AZIF0045P001C01CS(CHIPS)':
 'DDR7_SB_DQ2': CDS_PINID='DDR7_SB_DQ2';
NODE_NAME     J31 245
 '@S9S_MB_2U_LIB.S9S_MB_2U(SCH_1):PAGE112_I180@PURE_QUANTA.SCONN288_ADR50017P130CC(CHIPS)':
 'DQ2_B': CDS_PINID='DQ2_B';
NODE_NAME     J32 245
 '@S9S_MB_2U_LIB.S9S_MB_2U(SCH_1):PAGE113_I179@PURE_QUANTA.SCONN288_ADR50017P087CC(CHIPS)':
 'DQ2_B': CDS_PINID='DQ2_B';
NET_NAME
'M_H_CPU1_SB_DQ<30>'
 '@S9S_MB_2U_LIB.S9S_MB_2U(SCH_1):M_H_CPU1_SB_DQ'<30>:
 C_SIGNAL='@s9s_mb_2u_lib.s9s_mb_2u(sch_1):m_h_cpu1_sb_dq(30)';
NODE_NAME     U1 DJ17
 '@S9S_MB_2U_LIB.S9S_MB_2U(SCH_1):PAGE58_I20@PURE_QUANTA.SOCKET4677_AZIF0045P001C01CS(CHIPS)':
 'DDR7_SB_DQ30': CDS_PINID='DDR7_SB_DQ30';
NODE_NAME     J31 285
 '@S9S_MB_2U_LIB.S9S_MB_2U(SCH_1):PAGE112_I180@PURE_QUANTA.SCONN288_ADR50017P130CC(CHIPS)':
 'DQ30_B': CDS_PINID='DQ30_B';
NODE_NAME     J32 285
 '@S9S_MB_2U_LIB.S9S_MB_2U(SCH_1):PAGE113_I179@PURE_QUANTA.SCONN288_ADR50017P087CC(CHIPS)':
 'DQ30_B': CDS_PINID='DQ30_B';
NET_NAME
'M_H_CPU1_SB_DQ<31>'
 '@S9S_MB_2U_LIB.S9S_MB_2U(SCH_1):M_H_CPU1_SB_DQ'<31>:
 C_SIGNAL='@s9s_mb_2u_lib.s9s_mb_2u(sch_1):m_h_cpu1_sb_dq(31)';
NODE_NAME     U1 DC17
 '@S9S_MB_2U_LIB.S9S_MB_2U(SCH_1):PAGE58_I20@PURE_QUANTA.SOCKET4677_AZIF0045P001C01CS(CHIPS)':
 'DDR7_SB_DQ31': CDS_PINID='DDR7_SB_DQ31';
NODE_NAME     J31 287
 '@S9S_MB_2U_LIB.S9S_MB_2U(SCH_1):PAGE112_I180@PURE_QUANTA.SCONN288_ADR50017P130CC(CHIPS)':
 'DQ31_B': CDS_PINID='DQ31_B';
NODE_NAME     J32 287
 '@S9S_MB_2U_LIB.S9S_MB_2U(SCH_1):PAGE113_I179@PURE_QUANTA.SCONN288_ADR50017P087CC(CHIPS)':
 'DQ31_B': CDS_PINID='DQ31_B';
NET_NAME
'M_H_CPU1_SB_DQ<3>'
 '@S9S_MB_2U_LIB.S9S_MB_2U(SCH_1):M_H_CPU1_SB_DQ'<3>:
 C_SIGNAL='@s9s_mb_2u_lib.s9s_mb_2u(sch_1):m_h_cpu1_sb_dq(3)';
NODE_NAME     U1 DG31
 '@S9S_MB_2U_LIB.S9S_MB_2U(SCH_1):PAGE58_I20@PURE_QUANTA.SOCKET4677_AZIF0045P001C01CS(CHIPS)':
 'DDR7_SB_DQ3': CDS_PINID='DDR7_SB_DQ3';
NODE_NAME     J31 247
 '@S9S_MB_2U_LIB.S9S_MB_2U(SCH_1):PAGE112_I180@PURE_QUANTA.SCONN288_ADR50017P130CC(CHIPS)':
 'DQ3_B': CDS_PINID='DQ3_B';
NODE_NAME     J32 247
 '@S9S_MB_2U_LIB.S9S_MB_2U(SCH_1):PAGE113_I179@PURE_QUANTA.SCONN288_ADR50017P087CC(CHIPS)':
 'DQ3_B': CDS_PINID='DQ3_B';
NET_NAME
'M_H_CPU1_SB_DQ<4>'
 '@S9S_MB_2U_LIB.S9S_MB_2U(SCH_1):M_H_CPU1_SB_DQ'<4>:
 C_SIGNAL='@s9s_mb_2u_lib.s9s_mb_2u(sch_1):m_h_cpu1_sb_dq(4)';
NODE_NAME     U1 DC29
 '@S9S_MB_2U_LIB.S9S_MB_2U(SCH_1):PAGE58_I20@PURE_QUANTA.SOCKET4677_AZIF0045P001C01CS(CHIPS)':
 'DDR7_SB_DQ4': CDS_PINID='DDR7_SB_DQ4';
NODE_NAME     J31 107
 '@S9S_MB_2U_LIB.S9S_MB_2U(SCH_1):PAGE112_I180@PURE_QUANTA.SCONN288_ADR50017P130CC(CHIPS)':
 'DQ4_B': CDS_PINID='DQ4_B';
NODE_NAME     J32 107
 '@S9S_MB_2U_LIB.S9S_MB_2U(SCH_1):PAGE113_I179@PURE_QUANTA.SCONN288_ADR50017P087CC(CHIPS)':
 'DQ4_B': CDS_PINID='DQ4_B';
NET_NAME
'M_H_CPU1_SB_DQ<5>'
 '@S9S_MB_2U_LIB.S9S_MB_2U(SCH_1):M_H_CPU1_SB_DQ'<5>:
 C_SIGNAL='@s9s_mb_2u_lib.s9s_mb_2u(sch_1):m_h_cpu1_sb_dq(5)';
NODE_NAME     U1 DF28
 '@S9S_MB_2U_LIB.S9S_MB_2U(SCH_1):PAGE58_I20@PURE_QUANTA.SOCKET4677_AZIF0045P001C01CS(CHIPS)':
 'DDR7_SB_DQ5': CDS_PINID='DDR7_SB_DQ5';
NODE_NAME     J31 109
 '@S9S_MB_2U_LIB.S9S_MB_2U(SCH_1):PAGE112_I180@PURE_QUANTA.SCONN288_ADR50017P130CC(CHIPS)':
 'DQ5_B': CDS_PINID='DQ5_B';
NODE_NAME     J32 109
 '@S9S_MB_2U_LIB.S9S_MB_2U(SCH_1):PAGE113_I179@PURE_QUANTA.SCONN288_ADR50017P087CC(CHIPS)':
 'DQ5_B': CDS_PINID='DQ5_B';
NET_NAME
'M_H_CPU1_SB_DQ<6>'
 '@S9S_MB_2U_LIB.S9S_MB_2U(SCH_1):M_H_CPU1_SB_DQ'<6>:
 C_SIGNAL='@s9s_mb_2u_lib.s9s_mb_2u(sch_1):m_h_cpu1_sb_dq(6)';
NODE_NAME     U1 DG29
 '@S9S_MB_2U_LIB.S9S_MB_2U(SCH_1):PAGE58_I20@PURE_QUANTA.SOCKET4677_AZIF0045P001C01CS(CHIPS)':
 'DDR7_SB_DQ6': CDS_PINID='DDR7_SB_DQ6';
NODE_NAME     J31 252
 '@S9S_MB_2U_LIB.S9S_MB_2U(SCH_1):PAGE112_I180@PURE_QUANTA.SCONN288_ADR50017P130CC(CHIPS)':
 'DQ6_B': CDS_PINID='DQ6_B';
NODE_NAME     J32 252
 '@S9S_MB_2U_LIB.S9S_MB_2U(SCH_1):PAGE113_I179@PURE_QUANTA.SCONN288_ADR50017P087CC(CHIPS)':
 'DQ6_B': CDS_PINID='DQ6_B';
NET_NAME
'M_H_CPU1_SB_DQ<7>'
 '@S9S_MB_2U_LIB.S9S_MB_2U(SCH_1):M_H_CPU1_SB_DQ'<7>:
 C_SIGNAL='@s9s_mb_2u_lib.s9s_mb_2u(sch_1):m_h_cpu1_sb_dq(7)';
NODE_NAME     U1 DD28
 '@S9S_MB_2U_LIB.S9S_MB_2U(SCH_1):PAGE58_I20@PURE_QUANTA.SOCKET4677_AZIF0045P001C01CS(CHIPS)':
 'DDR7_SB_DQ7': CDS_PINID='DDR7_SB_DQ7';
NODE_NAME     J31 254
 '@S9S_MB_2U_LIB.S9S_MB_2U(SCH_1):PAGE112_I180@PURE_QUANTA.SCONN288_ADR50017P130CC(CHIPS)':
 'DQ7_B': CDS_PINID='DQ7_B';
NODE_NAME     J32 254
 '@S9S_MB_2U_LIB.S9S_MB_2U(SCH_1):PAGE113_I179@PURE_QUANTA.SCONN288_ADR50017P087CC(CHIPS)':
 'DQ7_B': CDS_PINID='DQ7_B';
NET_NAME
'M_H_CPU1_SB_DQ<8>'
 '@S9S_MB_2U_LIB.S9S_MB_2U(SCH_1):M_H_CPU1_SB_DQ'<8>:
 C_SIGNAL='@s9s_mb_2u_lib.s9s_mb_2u(sch_1):m_h_cpu1_sb_dq(8)';
NODE_NAME     U1 DD26
 '@S9S_MB_2U_LIB.S9S_MB_2U(SCH_1):PAGE58_I20@PURE_QUANTA.SOCKET4677_AZIF0045P001C01CS(CHIPS)':
 'DDR7_SB_DQ8': CDS_PINID='DDR7_SB_DQ8';
NODE_NAME     J31 111
 '@S9S_MB_2U_LIB.S9S_MB_2U(SCH_1):PAGE112_I180@PURE_QUANTA.SCONN288_ADR50017P130CC(CHIPS)':
 'DQ8_B': CDS_PINID='DQ8_B';
NODE_NAME     J32 111
 '@S9S_MB_2U_LIB.S9S_MB_2U(SCH_1):PAGE113_I179@PURE_QUANTA.SCONN288_ADR50017P087CC(CHIPS)':
 'DQ8_B': CDS_PINID='DQ8_B';
NET_NAME
'M_H_CPU1_SB_DQ<9>'
 '@S9S_MB_2U_LIB.S9S_MB_2U(SCH_1):M_H_CPU1_SB_DQ'<9>:
 C_SIGNAL='@s9s_mb_2u_lib.s9s_mb_2u(sch_1):m_h_cpu1_sb_dq(9)';
NODE_NAME     U1 DC25
 '@S9S_MB_2U_LIB.S9S_MB_2U(SCH_1):PAGE58_I20@PURE_QUANTA.SOCKET4677_AZIF0045P001C01CS(CHIPS)':
 'DDR7_SB_DQ9': CDS_PINID='DDR7_SB_DQ9';
NODE_NAME     J31 113
 '@S9S_MB_2U_LIB.S9S_MB_2U(SCH_1):PAGE112_I180@PURE_QUANTA.SCONN288_ADR50017P130CC(CHIPS)':
 'DQ9_B': CDS_PINID='DQ9_B';
NODE_NAME     J32 113
 '@S9S_MB_2U_LIB.S9S_MB_2U(SCH_1):PAGE113_I179@PURE_QUANTA.SCONN288_ADR50017P087CC(CHIPS)':
 'DQ9_B': CDS_PINID='DQ9_B';
NET_NAME
'M_H_CPU1_SB_DQS_DN<0>'
 '@S9S_MB_2U_LIB.S9S_MB_2U(SCH_1):M_H_CPU1_SB_DQS_DN'<0>:
 C_SIGNAL='@s9s_mb_2u_lib.s9s_mb_2u(sch_1):m_h_cpu1_sb_dqs_dn(0)';
NODE_NAME     U1 DD30
 '@S9S_MB_2U_LIB.S9S_MB_2U(SCH_1):PAGE58_I20@PURE_QUANTA.SOCKET4677_AZIF0045P001C01CS(CHIPS)':
 'DDR7_SB_DQS_DN0': CDS_PINID='DDR7_SB_DQS_DN0';
NODE_NAME     J31 105
 '@S9S_MB_2U_LIB.S9S_MB_2U(SCH_1):PAGE112_I181@PURE_QUANTA.SCONN288_ADR50017P130CC(CHIPS)':
 'DQS0_B_C': CDS_PINID='DQS0_B_C';
NODE_NAME     J32 105
 '@S9S_MB_2U_LIB.S9S_MB_2U(SCH_1):PAGE113_I180@PURE_QUANTA.SCONN288_ADR50017P087CC(CHIPS)':
 'DQS0_B_C': CDS_PINID='DQS0_B_C';
NET_NAME
'M_H_CPU1_SB_DQS_DN<1>'
 '@S9S_MB_2U_LIB.S9S_MB_2U(SCH_1):M_H_CPU1_SB_DQS_DN'<1>:
 C_SIGNAL='@s9s_mb_2u_lib.s9s_mb_2u(sch_1):m_h_cpu1_sb_dqs_dn(1)';
NODE_NAME     U1 DD24
 '@S9S_MB_2U_LIB.S9S_MB_2U(SCH_1):PAGE58_I20@PURE_QUANTA.SOCKET4677_AZIF0045P001C01CS(CHIPS)':
 'DDR7_SB_DQS_DN1': CDS_PINID='DDR7_SB_DQS_DN1';
NODE_NAME     J31 116
 '@S9S_MB_2U_LIB.S9S_MB_2U(SCH_1):PAGE112_I181@PURE_QUANTA.SCONN288_ADR50017P130CC(CHIPS)':
 'DQS1_B_C': CDS_PINID='DQS1_B_C';
NODE_NAME     J32 116
 '@S9S_MB_2U_LIB.S9S_MB_2U(SCH_1):PAGE113_I180@PURE_QUANTA.SCONN288_ADR50017P087CC(CHIPS)':
 'DQS1_B_C': CDS_PINID='DQS1_B_C';
NET_NAME
'M_H_CPU1_SB_DQS_DN<2>'
 '@S9S_MB_2U_LIB.S9S_MB_2U(SCH_1):M_H_CPU1_SB_DQS_DN'<2>:
 C_SIGNAL='@s9s_mb_2u_lib.s9s_mb_2u(sch_1):m_h_cpu1_sb_dqs_dn(2)';
NODE_NAME     U1 DL21
 '@S9S_MB_2U_LIB.S9S_MB_2U(SCH_1):PAGE58_I20@PURE_QUANTA.SOCKET4677_AZIF0045P001C01CS(CHIPS)':
 'DDR7_SB_DQS_DN2': CDS_PINID='DDR7_SB_DQS_DN2';
NODE_NAME     J31 127
 '@S9S_MB_2U_LIB.S9S_MB_2U(SCH_1):PAGE112_I181@PURE_QUANTA.SCONN288_ADR50017P130CC(CHIPS)':
 'DQS2_B_C': CDS_PINID='DQS2_B_C';
NODE_NAME     J32 127
 '@S9S_MB_2U_LIB.S9S_MB_2U(SCH_1):PAGE113_I180@PURE_QUANTA.SCONN288_ADR50017P087CC(CHIPS)':
 'DQS2_B_C': CDS_PINID='DQS2_B_C';
NET_NAME
'M_H_CPU1_SB_DQS_DN<3>'
 '@S9S_MB_2U_LIB.S9S_MB_2U(SCH_1):M_H_CPU1_SB_DQS_DN'<3>:
 C_SIGNAL='@s9s_mb_2u_lib.s9s_mb_2u(sch_1):m_h_cpu1_sb_dqs_dn(3)';
NODE_NAME     U1 DB18
 '@S9S_MB_2U_LIB.S9S_MB_2U(SCH_1):PAGE58_I20@PURE_QUANTA.SOCKET4677_AZIF0045P001C01CS(CHIPS)':
 'DDR7_SB_DQS_DN3': CDS_PINID='DDR7_SB_DQS_DN3';
NODE_NAME     J31 138
 '@S9S_MB_2U_LIB.S9S_MB_2U(SCH_1):PAGE112_I181@PURE_QUANTA.SCONN288_ADR50017P130CC(CHIPS)':
 'DQS3_B_C': CDS_PINID='DQS3_B_C';
NODE_NAME     J32 138
 '@S9S_MB_2U_LIB.S9S_MB_2U(SCH_1):PAGE113_I180@PURE_QUANTA.SCONN288_ADR50017P087CC(CHIPS)':
 'DQS3_B_C': CDS_PINID='DQS3_B_C';
NET_NAME
'M_H_CPU1_SB_DQS_DN<4>'
 '@S9S_MB_2U_LIB.S9S_MB_2U(SCH_1):M_H_CPU1_SB_DQS_DN'<4>:
 C_SIGNAL='@s9s_mb_2u_lib.s9s_mb_2u(sch_1):m_h_cpu1_sb_dqs_dn(4)';
NODE_NAME     U1 DH36
 '@S9S_MB_2U_LIB.S9S_MB_2U(SCH_1):PAGE58_I20@PURE_QUANTA.SOCKET4677_AZIF0045P001C01CS(CHIPS)':
 'DDR7_SB_DQS_DN4': CDS_PINID='DDR7_SB_DQS_DN4';
NODE_NAME     J31 238
 '@S9S_MB_2U_LIB.S9S_MB_2U(SCH_1):PAGE112_I181@PURE_QUANTA.SCONN288_ADR50017P130CC(CHIPS)':
 'DQS4_B_C': CDS_PINID='DQS4_B_C';
NODE_NAME     J32 238
 '@S9S_MB_2U_LIB.S9S_MB_2U(SCH_1):PAGE113_I180@PURE_QUANTA.SCONN288_ADR50017P087CC(CHIPS)':
 'DQS4_B_C': CDS_PINID='DQS4_B_C';
NET_NAME
'M_H_CPU1_SB_DQS_DN<5>'
 '@S9S_MB_2U_LIB.S9S_MB_2U(SCH_1):M_H_CPU1_SB_DQS_DN'<5>:
 C_SIGNAL='@s9s_mb_2u_lib.s9s_mb_2u(sch_1):m_h_cpu1_sb_dqs_dn(5)';
NODE_NAME     U1 DH30
 '@S9S_MB_2U_LIB.S9S_MB_2U(SCH_1):PAGE58_I20@PURE_QUANTA.SOCKET4677_AZIF0045P001C01CS(CHIPS)':
 'DDR7_SB_DQS_DN5': CDS_PINID='DDR7_SB_DQS_DN5';
NODE_NAME     J31 249
 '@S9S_MB_2U_LIB.S9S_MB_2U(SCH_1):PAGE112_I181@PURE_QUANTA.SCONN288_ADR50017P130CC(CHIPS)':
 'DQS5_B_C||TDQS5_B_C': CDS_PINID='\dqs5_b_c||tdqs5_b_c\';
NODE_NAME     J32 249
 '@S9S_MB_2U_LIB.S9S_MB_2U(SCH_1):PAGE113_I180@PURE_QUANTA.SCONN288_ADR50017P087CC(CHIPS)':
 'DQS5_B_C||TDQS5_B_C': CDS_PINID='\dqs5_b_c||tdqs5_b_c\';
NET_NAME
'M_H_CPU1_SB_DQS_DN<6>'
 '@S9S_MB_2U_LIB.S9S_MB_2U(SCH_1):M_H_CPU1_SB_DQS_DN'<6>:
 C_SIGNAL='@s9s_mb_2u_lib.s9s_mb_2u(sch_1):m_h_cpu1_sb_dqs_dn(6)';
NODE_NAME     U1 DH24
 '@S9S_MB_2U_LIB.S9S_MB_2U(SCH_1):PAGE58_I20@PURE_QUANTA.SOCKET4677_AZIF0045P001C01CS(CHIPS)':
 'DDR7_SB_DQS_DN6': CDS_PINID='DDR7_SB_DQS_DN6';
NODE_NAME     J31 260
 '@S9S_MB_2U_LIB.S9S_MB_2U(SCH_1):PAGE112_I181@PURE_QUANTA.SCONN288_ADR50017P130CC(CHIPS)':
 'DQS6_B_C||TDQS6_B_C': CDS_PINID='\dqs6_b_c||tdqs6_b_c\';
NODE_NAME     J32 260
 '@S9S_MB_2U_LIB.S9S_MB_2U(SCH_1):PAGE113_I180@PURE_QUANTA.SCONN288_ADR50017P087CC(CHIPS)':
 'DQS6_B_C||TDQS6_B_C': CDS_PINID='\dqs6_b_c||tdqs6_b_c\';
NET_NAME
'M_H_CPU1_SB_DQS_DN<7>'
 '@S9S_MB_2U_LIB.S9S_MB_2U(SCH_1):M_H_CPU1_SB_DQS_DN'<7>:
 C_SIGNAL='@s9s_mb_2u_lib.s9s_mb_2u(sch_1):m_h_cpu1_sb_dqs_dn(7)';
NODE_NAME     U1 DR21
 '@S9S_MB_2U_LIB.S9S_MB_2U(SCH_1):PAGE58_I20@PURE_QUANTA.SOCKET4677_AZIF0045P001C01CS(CHIPS)':
 'DDR7_SB_DQS_DN7': CDS_PINID='DDR7_SB_DQS_DN7';
NODE_NAME     J31 271
 '@S9S_MB_2U_LIB.S9S_MB_2U(SCH_1):PAGE112_I181@PURE_QUANTA.SCONN288_ADR50017P130CC(CHIPS)':
 'DQS7_B_C||TDQS7_B_C': CDS_PINID='\dqs7_b_c||tdqs7_b_c\';
NODE_NAME     J32 271
 '@S9S_MB_2U_LIB.S9S_MB_2U(SCH_1):PAGE113_I180@PURE_QUANTA.SCONN288_ADR50017P087CC(CHIPS)':
 'DQS7_B_C||TDQS7_B_C': CDS_PINID='\dqs7_b_c||tdqs7_b_c\';
NET_NAME
'M_H_CPU1_SB_DQS_DN<8>'
 '@S9S_MB_2U_LIB.S9S_MB_2U(SCH_1):M_H_CPU1_SB_DQS_DN'<8>:
 C_SIGNAL='@s9s_mb_2u_lib.s9s_mb_2u(sch_1):m_h_cpu1_sb_dqs_dn(8)';
NODE_NAME     U1 DF18
 '@S9S_MB_2U_LIB.S9S_MB_2U(SCH_1):PAGE58_I20@PURE_QUANTA.SOCKET4677_AZIF0045P001C01CS(CHIPS)':
 'DDR7_SB_DQS_DN8': CDS_PINID='DDR7_SB_DQS_DN8';
NODE_NAME     J31 282
 '@S9S_MB_2U_LIB.S9S_MB_2U(SCH_1):PAGE112_I181@PURE_QUANTA.SCONN288_ADR50017P130CC(CHIPS)':
 'DQS8_B_C||TDQS8_B_C': CDS_PINID='\dqs8_b_c||tdqs8_b_c\';
NODE_NAME     J32 282
 '@S9S_MB_2U_LIB.S9S_MB_2U(SCH_1):PAGE113_I180@PURE_QUANTA.SCONN288_ADR50017P087CC(CHIPS)':
 'DQS8_B_C||TDQS8_B_C': CDS_PINID='\dqs8_b_c||tdqs8_b_c\';
NET_NAME
'M_H_CPU1_SB_DQS_DN<9>'
 '@S9S_MB_2U_LIB.S9S_MB_2U(SCH_1):M_H_CPU1_SB_DQS_DN'<9>:
 C_SIGNAL='@s9s_mb_2u_lib.s9s_mb_2u(sch_1):m_h_cpu1_sb_dqs_dn(9)';
NODE_NAME     U1 DD36
 '@S9S_MB_2U_LIB.S9S_MB_2U(SCH_1):PAGE58_I20@PURE_QUANTA.SOCKET4677_AZIF0045P001C01CS(CHIPS)':
 'DDR7_SB_DQS_DN9': CDS_PINID='DDR7_SB_DQS_DN9';
NODE_NAME     J31 94
 '@S9S_MB_2U_LIB.S9S_MB_2U(SCH_1):PAGE112_I181@PURE_QUANTA.SCONN288_ADR50017P130CC(CHIPS)':
 'DQS9_B_C||TDQS9_B_C': CDS_PINID='\dqs9_b_c||tdqs9_b_c\';
NODE_NAME     J32 94
 '@S9S_MB_2U_LIB.S9S_MB_2U(SCH_1):PAGE113_I180@PURE_QUANTA.SCONN288_ADR50017P087CC(CHIPS)':
 'DQS9_B_C||TDQS9_B_C': CDS_PINID='\dqs9_b_c||tdqs9_b_c\';
NET_NAME
'M_H_CPU1_SB_DQS_DP<0>'
 '@S9S_MB_2U_LIB.S9S_MB_2U(SCH_1):M_H_CPU1_SB_DQS_DP'<0>:
 C_SIGNAL='@s9s_mb_2u_lib.s9s_mb_2u(sch_1):m_h_cpu1_sb_dqs_dp(0)';
NODE_NAME     U1 DB30
 '@S9S_MB_2U_LIB.S9S_MB_2U(SCH_1):PAGE58_I20@PURE_QUANTA.SOCKET4677_AZIF0045P001C01CS(CHIPS)':
 'DDR7_SB_DQS_DP0': CDS_PINID='DDR7_SB_DQS_DP0';
NODE_NAME     J31 104
 '@S9S_MB_2U_LIB.S9S_MB_2U(SCH_1):PAGE112_I181@PURE_QUANTA.SCONN288_ADR50017P130CC(CHIPS)':
 'DQS0_B_T': CDS_PINID='DQS0_B_T';
NODE_NAME     J32 104
 '@S9S_MB_2U_LIB.S9S_MB_2U(SCH_1):PAGE113_I180@PURE_QUANTA.SCONN288_ADR50017P087CC(CHIPS)':
 'DQS0_B_T': CDS_PINID='DQS0_B_T';
NET_NAME
'M_H_CPU1_SB_DQS_DP<1>'
 '@S9S_MB_2U_LIB.S9S_MB_2U(SCH_1):M_H_CPU1_SB_DQS_DP'<1>:
 C_SIGNAL='@s9s_mb_2u_lib.s9s_mb_2u(sch_1):m_h_cpu1_sb_dqs_dp(1)';
NODE_NAME     U1 DB24
 '@S9S_MB_2U_LIB.S9S_MB_2U(SCH_1):PAGE58_I20@PURE_QUANTA.SOCKET4677_AZIF0045P001C01CS(CHIPS)':
 'DDR7_SB_DQS_DP1': CDS_PINID='DDR7_SB_DQS_DP1';
NODE_NAME     J31 115
 '@S9S_MB_2U_LIB.S9S_MB_2U(SCH_1):PAGE112_I181@PURE_QUANTA.SCONN288_ADR50017P130CC(CHIPS)':
 'DQS1_B_T': CDS_PINID='DQS1_B_T';
NODE_NAME     J32 115
 '@S9S_MB_2U_LIB.S9S_MB_2U(SCH_1):PAGE113_I180@PURE_QUANTA.SCONN288_ADR50017P087CC(CHIPS)':
 'DQS1_B_T': CDS_PINID='DQS1_B_T';
NET_NAME
'M_H_CPU1_SB_DQS_DP<2>'
 '@S9S_MB_2U_LIB.S9S_MB_2U(SCH_1):M_H_CPU1_SB_DQS_DP'<2>:
 C_SIGNAL='@s9s_mb_2u_lib.s9s_mb_2u(sch_1):m_h_cpu1_sb_dqs_dp(2)';
NODE_NAME     U1 DJ21
 '@S9S_MB_2U_LIB.S9S_MB_2U(SCH_1):PAGE58_I20@PURE_QUANTA.SOCKET4677_AZIF0045P001C01CS(CHIPS)':
 'DDR7_SB_DQS_DP2': CDS_PINID='DDR7_SB_DQS_DP2';
NODE_NAME     J31 126
 '@S9S_MB_2U_LIB.S9S_MB_2U(SCH_1):PAGE112_I181@PURE_QUANTA.SCONN288_ADR50017P130CC(CHIPS)':
 'DQS2_B_T': CDS_PINID='DQS2_B_T';
NODE_NAME     J32 126
 '@S9S_MB_2U_LIB.S9S_MB_2U(SCH_1):PAGE113_I180@PURE_QUANTA.SCONN288_ADR50017P087CC(CHIPS)':
 'DQS2_B_T': CDS_PINID='DQS2_B_T';
NET_NAME
'M_H_CPU1_SB_DQS_DP<3>'
 '@S9S_MB_2U_LIB.S9S_MB_2U(SCH_1):M_H_CPU1_SB_DQS_DP'<3>:
 C_SIGNAL='@s9s_mb_2u_lib.s9s_mb_2u(sch_1):m_h_cpu1_sb_dqs_dp(3)';
NODE_NAME     U1 DD18
 '@S9S_MB_2U_LIB.S9S_MB_2U(SCH_1):PAGE58_I20@PURE_QUANTA.SOCKET4677_AZIF0045P001C01CS(CHIPS)':
 'DDR7_SB_DQS_DP3': CDS_PINID='DDR7_SB_DQS_DP3';
NODE_NAME     J31 137
 '@S9S_MB_2U_LIB.S9S_MB_2U(SCH_1):PAGE112_I181@PURE_QUANTA.SCONN288_ADR50017P130CC(CHIPS)':
 'DQS3_B_T': CDS_PINID='DQS3_B_T';
NODE_NAME     J32 137
 '@S9S_MB_2U_LIB.S9S_MB_2U(SCH_1):PAGE113_I180@PURE_QUANTA.SCONN288_ADR50017P087CC(CHIPS)':
 'DQS3_B_T': CDS_PINID='DQS3_B_T';
NET_NAME
'M_H_CPU1_SB_DQS_DP<4>'
 '@S9S_MB_2U_LIB.S9S_MB_2U(SCH_1):M_H_CPU1_SB_DQS_DP'<4>:
 C_SIGNAL='@s9s_mb_2u_lib.s9s_mb_2u(sch_1):m_h_cpu1_sb_dqs_dp(4)';
NODE_NAME     U1 DF36
 '@S9S_MB_2U_LIB.S9S_MB_2U(SCH_1):PAGE58_I20@PURE_QUANTA.SOCKET4677_AZIF0045P001C01CS(CHIPS)':
 'DDR7_SB_DQS_DP4': CDS_PINID='DDR7_SB_DQS_DP4';
NODE_NAME     J31 239
 '@S9S_MB_2U_LIB.S9S_MB_2U(SCH_1):PAGE112_I181@PURE_QUANTA.SCONN288_ADR50017P130CC(CHIPS)':
 'DQS4_B_T': CDS_PINID='DQS4_B_T';
NODE_NAME     J32 239
 '@S9S_MB_2U_LIB.S9S_MB_2U(SCH_1):PAGE113_I180@PURE_QUANTA.SCONN288_ADR50017P087CC(CHIPS)':
 'DQS4_B_T': CDS_PINID='DQS4_B_T';
NET_NAME
'M_H_CPU1_SB_DQS_DP<5>'
 '@S9S_MB_2U_LIB.S9S_MB_2U(SCH_1):M_H_CPU1_SB_DQS_DP'<5>:
 C_SIGNAL='@s9s_mb_2u_lib.s9s_mb_2u(sch_1):m_h_cpu1_sb_dqs_dp(5)';
NODE_NAME     U1 DF30
 '@S9S_MB_2U_LIB.S9S_MB_2U(SCH_1):PAGE58_I20@PURE_QUANTA.SOCKET4677_AZIF0045P001C01CS(CHIPS)':
 'DDR7_SB_DQS_DP5': CDS_PINID='DDR7_SB_DQS_DP5';
NODE_NAME     J31 250
 '@S9S_MB_2U_LIB.S9S_MB_2U(SCH_1):PAGE112_I181@PURE_QUANTA.SCONN288_ADR50017P130CC(CHIPS)':
 'DQS5_B_T||TDQS5_B_T': CDS_PINID='\dqs5_b_t||tdqs5_b_t\';
NODE_NAME     J32 250
 '@S9S_MB_2U_LIB.S9S_MB_2U(SCH_1):PAGE113_I180@PURE_QUANTA.SCONN288_ADR50017P087CC(CHIPS)':
 'DQS5_B_T||TDQS5_B_T': CDS_PINID='\dqs5_b_t||tdqs5_b_t\';
NET_NAME
'M_H_CPU1_SB_DQS_DP<6>'
 '@S9S_MB_2U_LIB.S9S_MB_2U(SCH_1):M_H_CPU1_SB_DQS_DP'<6>:
 C_SIGNAL='@s9s_mb_2u_lib.s9s_mb_2u(sch_1):m_h_cpu1_sb_dqs_dp(6)';
NODE_NAME     U1 DF24
 '@S9S_MB_2U_LIB.S9S_MB_2U(SCH_1):PAGE58_I20@PURE_QUANTA.SOCKET4677_AZIF0045P001C01CS(CHIPS)':
 'DDR7_SB_DQS_DP6': CDS_PINID='DDR7_SB_DQS_DP6';
NODE_NAME     J31 261
 '@S9S_MB_2U_LIB.S9S_MB_2U(SCH_1):PAGE112_I181@PURE_QUANTA.SCONN288_ADR50017P130CC(CHIPS)':
 'DQS6_B_T||TDQS6_B_T': CDS_PINID='\dqs6_b_t||tdqs6_b_t\';
NODE_NAME     J32 261
 '@S9S_MB_2U_LIB.S9S_MB_2U(SCH_1):PAGE113_I180@PURE_QUANTA.SCONN288_ADR50017P087CC(CHIPS)':
 'DQS6_B_T||TDQS6_B_T': CDS_PINID='\dqs6_b_t||tdqs6_b_t\';
NET_NAME
'M_H_CPU1_SB_DQS_DP<7>'
 '@S9S_MB_2U_LIB.S9S_MB_2U(SCH_1):M_H_CPU1_SB_DQS_DP'<7>:
 C_SIGNAL='@s9s_mb_2u_lib.s9s_mb_2u(sch_1):m_h_cpu1_sb_dqs_dp(7)';
NODE_NAME     U1 DN21
 '@S9S_MB_2U_LIB.S9S_MB_2U(SCH_1):PAGE58_I20@PURE_QUANTA.SOCKET4677_AZIF0045P001C01CS(CHIPS)':
 'DDR7_SB_DQS_DP7': CDS_PINID='DDR7_SB_DQS_DP7';
NODE_NAME     J31 272
 '@S9S_MB_2U_LIB.S9S_MB_2U(SCH_1):PAGE112_I181@PURE_QUANTA.SCONN288_ADR50017P130CC(CHIPS)':
 'DQS7_B_T||TDQS7_B_T': CDS_PINID='\dqs7_b_t||tdqs7_b_t\';
NODE_NAME     J32 272
 '@S9S_MB_2U_LIB.S9S_MB_2U(SCH_1):PAGE113_I180@PURE_QUANTA.SCONN288_ADR50017P087CC(CHIPS)':
 'DQS7_B_T||TDQS7_B_T': CDS_PINID='\dqs7_b_t||tdqs7_b_t\';
NET_NAME
'M_H_CPU1_SB_DQS_DP<8>'
 '@S9S_MB_2U_LIB.S9S_MB_2U(SCH_1):M_H_CPU1_SB_DQS_DP'<8>:
 C_SIGNAL='@s9s_mb_2u_lib.s9s_mb_2u(sch_1):m_h_cpu1_sb_dqs_dp(8)';
NODE_NAME     U1 DH18
 '@S9S_MB_2U_LIB.S9S_MB_2U(SCH_1):PAGE58_I20@PURE_QUANTA.SOCKET4677_AZIF0045P001C01CS(CHIPS)':
 'DDR7_SB_DQS_DP8': CDS_PINID='DDR7_SB_DQS_DP8';
NODE_NAME     J31 283
 '@S9S_MB_2U_LIB.S9S_MB_2U(SCH_1):PAGE112_I181@PURE_QUANTA.SCONN288_ADR50017P130CC(CHIPS)':
 'DQS8_B_T||TDQS8_B_T': CDS_PINID='\dqs8_b_t||tdqs8_b_t\';
NODE_NAME     J32 283
 '@S9S_MB_2U_LIB.S9S_MB_2U(SCH_1):PAGE113_I180@PURE_QUANTA.SCONN288_ADR50017P087CC(CHIPS)':
 'DQS8_B_T||TDQS8_B_T': CDS_PINID='\dqs8_b_t||tdqs8_b_t\';
NET_NAME
'M_H_CPU1_SB_DQS_DP<9>'
 '@S9S_MB_2U_LIB.S9S_MB_2U(SCH_1):M_H_CPU1_SB_DQS_DP'<9>:
 C_SIGNAL='@s9s_mb_2u_lib.s9s_mb_2u(sch_1):m_h_cpu1_sb_dqs_dp(9)';
NODE_NAME     U1 DB36
 '@S9S_MB_2U_LIB.S9S_MB_2U(SCH_1):PAGE58_I20@PURE_QUANTA.SOCKET4677_AZIF0045P001C01CS(CHIPS)':
 'DDR7_SB_DQS_DP9': CDS_PINID='DDR7_SB_DQS_DP9';
NODE_NAME     J31 93
 '@S9S_MB_2U_LIB.S9S_MB_2U(SCH_1):PAGE112_I181@PURE_QUANTA.SCONN288_ADR50017P130CC(CHIPS)':
 'DQS9_B_T||TDQS9_B_T||DBI4_B_N': CDS_PINID='\dqs9_b_t||tdqs9_b_t||dbi4_b_n\';
NODE_NAME     J32 93
 '@S9S_MB_2U_LIB.S9S_MB_2U(SCH_1):PAGE113_I180@PURE_QUANTA.SCONN288_ADR50017P087CC(CHIPS)':
 'DQS9_B_T||TDQS9_B_T||DBI4_B_N': CDS_PINID='\dqs9_b_t||tdqs9_b_t||dbi4_b_n\';
NET_NAME
'M_H_CPU1_SB_PAR'
 '@S9S_MB_2U_LIB.S9S_MB_2U(SCH_1):M_H_CPU1_SB_PAR':
 C_SIGNAL='@s9s_mb_2u_lib.s9s_mb_2u(sch_1):m_h_cpu1_sb_par';
NODE_NAME     U1 DR39
 '@S9S_MB_2U_LIB.S9S_MB_2U(SCH_1):PAGE58_I20@PURE_QUANTA.SOCKET4677_AZIF0045P001C01CS(CHIPS)':
 'DDR7_SB_PAR': CDS_PINID='DDR7_SB_PAR';
NODE_NAME     J31 227
 '@S9S_MB_2U_LIB.S9S_MB_2U(SCH_1):PAGE112_I180@PURE_QUANTA.SCONN288_ADR50017P130CC(CHIPS)':
 'PAR_B': CDS_PINID='PAR_B';
NODE_NAME     J32 227
 '@S9S_MB_2U_LIB.S9S_MB_2U(SCH_1):PAGE113_I179@PURE_QUANTA.SCONN288_ADR50017P087CC(CHIPS)':
 'PAR_B': CDS_PINID='PAR_B';
NET_NAME
'M_H_CPU1_SB_RSP<0>'
 '@S9S_MB_2U_LIB.S9S_MB_2U(SCH_1):M_H_CPU1_SB_RSP'<0>:
 C_SIGNAL='@s9s_mb_2u_lib.s9s_mb_2u(sch_1):m_h_cpu1_sb_rsp(0)';
NODE_NAME     U1 EE48
 '@S9S_MB_2U_LIB.S9S_MB_2U(SCH_1):PAGE58_I20@PURE_QUANTA.SOCKET4677_AZIF0045P001C01CS(CHIPS)':
 'DDR7_B_RSP0': CDS_PINID='DDR7_B_RSP0';
NODE_NAME     J31 87
 '@S9S_MB_2U_LIB.S9S_MB_2U(SCH_1):PAGE112_I180@PURE_QUANTA.SCONN288_ADR50017P130CC(CHIPS)':
 'LBS||RSP_B_N': CDS_PINID='\lbs||rsp_b_n\';
NET_NAME
'M_H_CPU1_SB_RSP<1>'
 '@S9S_MB_2U_LIB.S9S_MB_2U(SCH_1):M_H_CPU1_SB_RSP'<1>:
 C_SIGNAL='@s9s_mb_2u_lib.s9s_mb_2u(sch_1):m_h_cpu1_sb_rsp(1)';
NODE_NAME     U1 ED47
 '@S9S_MB_2U_LIB.S9S_MB_2U(SCH_1):PAGE58_I20@PURE_QUANTA.SOCKET4677_AZIF0045P001C01CS(CHIPS)':
 'DDR7_B_RSP1': CDS_PINID='DDR7_B_RSP1';
NODE_NAME     J32 87
 '@S9S_MB_2U_LIB.S9S_MB_2U(SCH_1):PAGE113_I179@PURE_QUANTA.SCONN288_ADR50017P087CC(CHIPS)':
 'LBS||RSP_B_N': CDS_PINID='\lbs||rsp_b_n\';
NET_NAME
'NC'
 'NC':
 C_SIGNAL='NC';
NODE_NAME     U2 EH85
 '@S9S_MB_2U_LIB.S9S_MB_2U(SCH_1):PAGE35_I102@PURE_QUANTA.SOCKET4677_AZIF0045P001C01CS(CHIPS)':
 'UPI3_TX_DN0': CDS_PINID='UPI3_TX_DN0';
NODE_NAME     U2 EL84
 '@S9S_MB_2U_LIB.S9S_MB_2U(SCH_1):PAGE35_I102@PURE_QUANTA.SOCKET4677_AZIF0045P001C01CS(CHIPS)':
 'UPI3_TX_DN1': CDS_PINID='UPI3_TX_DN1';
NODE_NAME     U2 EP85
 '@S9S_MB_2U_LIB.S9S_MB_2U(SCH_1):PAGE35_I102@PURE_QUANTA.SOCKET4677_AZIF0045P001C01CS(CHIPS)':
 'UPI3_TX_DN2': CDS_PINID='UPI3_TX_DN2';
NODE_NAME     U2 EM87
 '@S9S_MB_2U_LIB.S9S_MB_2U(SCH_1):PAGE35_I102@PURE_QUANTA.SOCKET4677_AZIF0045P001C01CS(CHIPS)':
 'UPI3_TX_DN3': CDS_PINID='UPI3_TX_DN3';
NODE_NAME     U2 EJ86
 '@S9S_MB_2U_LIB.S9S_MB_2U(SCH_1):PAGE35_I102@PURE_QUANTA.SOCKET4677_AZIF0045P001C01CS(CHIPS)':
 'UPI3_TX_DN4': CDS_PINID='UPI3_TX_DN4';
NODE_NAME     U2 EK87
 '@S9S_MB_2U_LIB.S9S_MB_2U(SCH_1):PAGE35_I102@PURE_QUANTA.SOCKET4677_AZIF0045P001C01CS(CHIPS)':
 'UPI3_TX_DN5': CDS_PINID='UPI3_TX_DN5';
NODE_NAME     U2 DU80
 '@S9S_MB_2U_LIB.S9S_MB_2U(SCH_1):PAGE35_I102@PURE_QUANTA.SOCKET4677_AZIF0045P001C01CS(CHIPS)':
 'UPI3_TX_DN6': CDS_PINID='UPI3_TX_DN6';
NODE_NAME     U2 DR82
 '@S9S_MB_2U_LIB.S9S_MB_2U(SCH_1):PAGE35_I102@PURE_QUANTA.SOCKET4677_AZIF0045P001C01CS(CHIPS)':
 'UPI3_TX_DN7': CDS_PINID='UPI3_TX_DN7';
NODE_NAME     U2 DP79
 '@S9S_MB_2U_LIB.S9S_MB_2U(SCH_1):PAGE35_I102@PURE_QUANTA.SOCKET4677_AZIF0045P001C01CS(CHIPS)':
 'UPI3_TX_DN8': CDS_PINID='UPI3_TX_DN8';
NODE_NAME     U2 DN82
 '@S9S_MB_2U_LIB.S9S_MB_2U(SCH_1):PAGE35_I102@PURE_QUANTA.SOCKET4677_AZIF0045P001C01CS(CHIPS)':
 'UPI3_TX_DN9': CDS_PINID='UPI3_TX_DN9';
NODE_NAME     U2 DM81
 '@S9S_MB_2U_LIB.S9S_MB_2U(SCH_1):PAGE35_I102@PURE_QUANTA.SOCKET4677_AZIF0045P001C01CS(CHIPS)':
 'UPI3_TX_DN10': CDS_PINID='UPI3_TX_DN10';
NODE_NAME     U2 DL80
 '@S9S_MB_2U_LIB.S9S_MB_2U(SCH_1):PAGE35_I102@PURE_QUANTA.SOCKET4677_AZIF0045P001C01CS(CHIPS)':
 'UPI3_TX_DN11': CDS_PINID='UPI3_TX_DN11';
NODE_NAME     U2 CW76
 '@S9S_MB_2U_LIB.S9S_MB_2U(SCH_1):PAGE35_I102@PURE_QUANTA.SOCKET4677_AZIF0045P001C01CS(CHIPS)':
 'UPI3_TX_DN12': CDS_PINID='UPI3_TX_DN12';
NODE_NAME     U2 CU76
 '@S9S_MB_2U_LIB.S9S_MB_2U(SCH_1):PAGE35_I102@PURE_QUANTA.SOCKET4677_AZIF0045P001C01CS(CHIPS)':
 'UPI3_TX_DN13': CDS_PINID='UPI3_TX_DN13';
NODE_NAME     U2 CT75
 '@S9S_MB_2U_LIB.S9S_MB_2U(SCH_1):PAGE35_I102@PURE_QUANTA.SOCKET4677_AZIF0045P001C01CS(CHIPS)':
 'UPI3_TX_DN14': CDS_PINID='UPI3_TX_DN14';
NODE_NAME     U2 CR74
 '@S9S_MB_2U_LIB.S9S_MB_2U(SCH_1):PAGE35_I102@PURE_QUANTA.SOCKET4677_AZIF0045P001C01CS(CHIPS)':
 'UPI3_TX_DN15': CDS_PINID='UPI3_TX_DN15';
NODE_NAME     U2 CK77
 '@S9S_MB_2U_LIB.S9S_MB_2U(SCH_1):PAGE35_I102@PURE_QUANTA.SOCKET4677_AZIF0045P001C01CS(CHIPS)':
 'UPI3_TX_DN16': CDS_PINID='UPI3_TX_DN16';
NODE_NAME     U2 CH77
 '@S9S_MB_2U_LIB.S9S_MB_2U(SCH_1):PAGE35_I102@PURE_QUANTA.SOCKET4677_AZIF0045P001C01CS(CHIPS)':
 'UPI3_TX_DN17': CDS_PINID='UPI3_TX_DN17';
NODE_NAME     U2 CM75
 '@S9S_MB_2U_LIB.S9S_MB_2U(SCH_1):PAGE35_I102@PURE_QUANTA.SOCKET4677_AZIF0045P001C01CS(CHIPS)':
 'UPI3_TX_DN18': CDS_PINID='UPI3_TX_DN18';
NODE_NAME     U2 CG76
 '@S9S_MB_2U_LIB.S9S_MB_2U(SCH_1):PAGE35_I102@PURE_QUANTA.SOCKET4677_AZIF0045P001C01CS(CHIPS)':
 'UPI3_TX_DN19': CDS_PINID='UPI3_TX_DN19';
NODE_NAME     U2 CF75
 '@S9S_MB_2U_LIB.S9S_MB_2U(SCH_1):PAGE35_I102@PURE_QUANTA.SOCKET4677_AZIF0045P001C01CS(CHIPS)':
 'UPI3_TX_DN20': CDS_PINID='UPI3_TX_DN20';
NODE_NAME     U2 CJ74
 '@S9S_MB_2U_LIB.S9S_MB_2U(SCH_1):PAGE35_I102@PURE_QUANTA.SOCKET4677_AZIF0045P001C01CS(CHIPS)':
 'UPI3_TX_DN21': CDS_PINID='UPI3_TX_DN21';
NODE_NAME     U2 CV73
 '@S9S_MB_2U_LIB.S9S_MB_2U(SCH_1):PAGE35_I102@PURE_QUANTA.SOCKET4677_AZIF0045P001C01CS(CHIPS)':
 'UPI3_TX_DN22': CDS_PINID='UPI3_TX_DN22';
NODE_NAME     U2 CF73
 '@S9S_MB_2U_LIB.S9S_MB_2U(SCH_1):PAGE35_I102@PURE_QUANTA.SOCKET4677_AZIF0045P001C01CS(CHIPS)':
 'UPI3_TX_DN23': CDS_PINID='UPI3_TX_DN23';
NODE_NAME     U2 EK85
 '@S9S_MB_2U_LIB.S9S_MB_2U(SCH_1):PAGE35_I102@PURE_QUANTA.SOCKET4677_AZIF0045P001C01CS(CHIPS)':
 'UPI3_TX_DP0': CDS_PINID='UPI3_TX_DP0';
NODE_NAME     U2 EM85
 '@S9S_MB_2U_LIB.S9S_MB_2U(SCH_1):PAGE35_I102@PURE_QUANTA.SOCKET4677_AZIF0045P001C01CS(CHIPS)':
 'UPI3_TX_DP1': CDS_PINID='UPI3_TX_DP1';
NODE_NAME     U2 EN86
 '@S9S_MB_2U_LIB.S9S_MB_2U(SCH_1):PAGE35_I102@PURE_QUANTA.SOCKET4677_AZIF0045P001C01CS(CHIPS)':
 'UPI3_TX_DP2': CDS_PINID='UPI3_TX_DP2';
NODE_NAME     U2 EP87
 '@S9S_MB_2U_LIB.S9S_MB_2U(SCH_1):PAGE35_I102@PURE_QUANTA.SOCKET4677_AZIF0045P001C01CS(CHIPS)':
 'UPI3_TX_DP3': CDS_PINID='UPI3_TX_DP3';
NODE_NAME     U2 EH87
 '@S9S_MB_2U_LIB.S9S_MB_2U(SCH_1):PAGE35_I102@PURE_QUANTA.SOCKET4677_AZIF0045P001C01CS(CHIPS)':
 'UPI3_TX_DP4': CDS_PINID='UPI3_TX_DP4';
NODE_NAME     U2 EL88
 '@S9S_MB_2U_LIB.S9S_MB_2U(SCH_1):PAGE35_I102@PURE_QUANTA.SOCKET4677_AZIF0045P001C01CS(CHIPS)':
 'UPI3_TX_DP5': CDS_PINID='UPI3_TX_DP5';
NODE_NAME     U2 DT81
 '@S9S_MB_2U_LIB.S9S_MB_2U(SCH_1):PAGE35_I102@PURE_QUANTA.SOCKET4677_AZIF0045P001C01CS(CHIPS)':
 'UPI3_TX_DP6': CDS_PINID='UPI3_TX_DP6';
NODE_NAME     U2 DU82
 '@S9S_MB_2U_LIB.S9S_MB_2U(SCH_1):PAGE35_I102@PURE_QUANTA.SOCKET4677_AZIF0045P001C01CS(CHIPS)':
 'UPI3_TX_DP7': CDS_PINID='UPI3_TX_DP7';
NODE_NAME     U2 DR80
 '@S9S_MB_2U_LIB.S9S_MB_2U(SCH_1):PAGE35_I102@PURE_QUANTA.SOCKET4677_AZIF0045P001C01CS(CHIPS)':
 'UPI3_TX_DP8': CDS_PINID='UPI3_TX_DP8';
NODE_NAME     U2 DP83
 '@S9S_MB_2U_LIB.S9S_MB_2U(SCH_1):PAGE35_I102@PURE_QUANTA.SOCKET4677_AZIF0045P001C01CS(CHIPS)':
 'UPI3_TX_DP9': CDS_PINID='UPI3_TX_DP9';
NODE_NAME     U2 DL82
 '@S9S_MB_2U_LIB.S9S_MB_2U(SCH_1):PAGE35_I102@PURE_QUANTA.SOCKET4677_AZIF0045P001C01CS(CHIPS)':
 'UPI3_TX_DP10': CDS_PINID='UPI3_TX_DP10';
NODE_NAME     U2 DN80
 '@S9S_MB_2U_LIB.S9S_MB_2U(SCH_1):PAGE35_I102@PURE_QUANTA.SOCKET4677_AZIF0045P001C01CS(CHIPS)':
 'UPI3_TX_DP11': CDS_PINID='UPI3_TX_DP11';
NODE_NAME     U2 DA76
 '@S9S_MB_2U_LIB.S9S_MB_2U(SCH_1):PAGE35_I102@PURE_QUANTA.SOCKET4677_AZIF0045P001C01CS(CHIPS)':
 'UPI3_TX_DP12': CDS_PINID='UPI3_TX_DP12';
NODE_NAME     U2 CV77
 '@S9S_MB_2U_LIB.S9S_MB_2U(SCH_1):PAGE35_I102@PURE_QUANTA.SOCKET4677_AZIF0045P001C01CS(CHIPS)':
 'UPI3_TX_DP13': CDS_PINID='UPI3_TX_DP13';
NODE_NAME     U2 CR76
 '@S9S_MB_2U_LIB.S9S_MB_2U(SCH_1):PAGE35_I102@PURE_QUANTA.SOCKET4677_AZIF0045P001C01CS(CHIPS)':
 'UPI3_TX_DP14': CDS_PINID='UPI3_TX_DP14';
NODE_NAME     U2 CU74
 '@S9S_MB_2U_LIB.S9S_MB_2U(SCH_1):PAGE35_I102@PURE_QUANTA.SOCKET4677_AZIF0045P001C01CS(CHIPS)':
 'UPI3_TX_DP15': CDS_PINID='UPI3_TX_DP15';
NODE_NAME     U2 CM77
 '@S9S_MB_2U_LIB.S9S_MB_2U(SCH_1):PAGE35_I102@PURE_QUANTA.SOCKET4677_AZIF0045P001C01CS(CHIPS)':
 'UPI3_TX_DP16': CDS_PINID='UPI3_TX_DP16';
NODE_NAME     U2 CJ78
 '@S9S_MB_2U_LIB.S9S_MB_2U(SCH_1):PAGE35_I102@PURE_QUANTA.SOCKET4677_AZIF0045P001C01CS(CHIPS)':
 'UPI3_TX_DP17': CDS_PINID='UPI3_TX_DP17';
NODE_NAME     U2 CL76
 '@S9S_MB_2U_LIB.S9S_MB_2U(SCH_1):PAGE35_I102@PURE_QUANTA.SOCKET4677_AZIF0045P001C01CS(CHIPS)':
 'UPI3_TX_DP18': CDS_PINID='UPI3_TX_DP18';
NODE_NAME     U2 CF77
 '@S9S_MB_2U_LIB.S9S_MB_2U(SCH_1):PAGE35_I102@PURE_QUANTA.SOCKET4677_AZIF0045P001C01CS(CHIPS)':
 'UPI3_TX_DP19': CDS_PINID='UPI3_TX_DP19';
NODE_NAME     U2 CH75
 '@S9S_MB_2U_LIB.S9S_MB_2U(SCH_1):PAGE35_I102@PURE_QUANTA.SOCKET4677_AZIF0045P001C01CS(CHIPS)':
 'UPI3_TX_DP20': CDS_PINID='UPI3_TX_DP20';
NODE_NAME     U2 CK75
 '@S9S_MB_2U_LIB.S9S_MB_2U(SCH_1):PAGE35_I102@PURE_QUANTA.SOCKET4677_AZIF0045P001C01CS(CHIPS)':
 'UPI3_TX_DP21': CDS_PINID='UPI3_TX_DP21';
NODE_NAME     U2 CW74
 '@S9S_MB_2U_LIB.S9S_MB_2U(SCH_1):PAGE35_I102@PURE_QUANTA.SOCKET4677_AZIF0045P001C01CS(CHIPS)':
 'UPI3_TX_DP22': CDS_PINID='UPI3_TX_DP22';
NODE_NAME     U2 CD73
 '@S9S_MB_2U_LIB.S9S_MB_2U(SCH_1):PAGE35_I102@PURE_QUANTA.SOCKET4677_AZIF0045P001C01CS(CHIPS)':
 'UPI3_TX_DP23': CDS_PINID='UPI3_TX_DP23';
NODE_NAME     U1 EH85
 '@S9S_MB_2U_LIB.S9S_MB_2U(SCH_1):PAGE66_I16@PURE_QUANTA.SOCKET4677_AZIF0045P001C01CS(CHIPS)':
 'UPI3_TX_DN0': CDS_PINID='UPI3_TX_DN0';
NODE_NAME     U1 EL84
 '@S9S_MB_2U_LIB.S9S_MB_2U(SCH_1):PAGE66_I16@PURE_QUANTA.SOCKET4677_AZIF0045P001C01CS(CHIPS)':
 'UPI3_TX_DN1': CDS_PINID='UPI3_TX_DN1';
NODE_NAME     U1 EP85
 '@S9S_MB_2U_LIB.S9S_MB_2U(SCH_1):PAGE66_I16@PURE_QUANTA.SOCKET4677_AZIF0045P001C01CS(CHIPS)':
 'UPI3_TX_DN2': CDS_PINID='UPI3_TX_DN2';
NODE_NAME     U1 EM87
 '@S9S_MB_2U_LIB.S9S_MB_2U(SCH_1):PAGE66_I16@PURE_QUANTA.SOCKET4677_AZIF0045P001C01CS(CHIPS)':
 'UPI3_TX_DN3': CDS_PINID='UPI3_TX_DN3';
NODE_NAME     U1 EJ86
 '@S9S_MB_2U_LIB.S9S_MB_2U(SCH_1):PAGE66_I16@PURE_QUANTA.SOCKET4677_AZIF0045P001C01CS(CHIPS)':
 'UPI3_TX_DN4': CDS_PINID='UPI3_TX_DN4';
NODE_NAME     U1 EK87
 '@S9S_MB_2U_LIB.S9S_MB_2U(SCH_1):PAGE66_I16@PURE_QUANTA.SOCKET4677_AZIF0045P001C01CS(CHIPS)':
 'UPI3_TX_DN5': CDS_PINID='UPI3_TX_DN5';
NODE_NAME     U1 DU80
 '@S9S_MB_2U_LIB.S9S_MB_2U(SCH_1):PAGE66_I16@PURE_QUANTA.SOCKET4677_AZIF0045P001C01CS(CHIPS)':
 'UPI3_TX_DN6': CDS_PINID='UPI3_TX_DN6';
NODE_NAME     U1 DR82
 '@S9S_MB_2U_LIB.S9S_MB_2U(SCH_1):PAGE66_I16@PURE_QUANTA.SOCKET4677_AZIF0045P001C01CS(CHIPS)':
 'UPI3_TX_DN7': CDS_PINID='UPI3_TX_DN7';
NODE_NAME     U1 DP79
 '@S9S_MB_2U_LIB.S9S_MB_2U(SCH_1):PAGE66_I16@PURE_QUANTA.SOCKET4677_AZIF0045P001C01CS(CHIPS)':
 'UPI3_TX_DN8': CDS_PINID='UPI3_TX_DN8';
NODE_NAME     U1 DN82
 '@S9S_MB_2U_LIB.S9S_MB_2U(SCH_1):PAGE66_I16@PURE_QUANTA.SOCKET4677_AZIF0045P001C01CS(CHIPS)':
 'UPI3_TX_DN9': CDS_PINID='UPI3_TX_DN9';
NODE_NAME     U1 DM81
 '@S9S_MB_2U_LIB.S9S_MB_2U(SCH_1):PAGE66_I16@PURE_QUANTA.SOCKET4677_AZIF0045P001C01CS(CHIPS)':
 'UPI3_TX_DN10': CDS_PINID='UPI3_TX_DN10';
NODE_NAME     U1 DL80
 '@S9S_MB_2U_LIB.S9S_MB_2U(SCH_1):PAGE66_I16@PURE_QUANTA.SOCKET4677_AZIF0045P001C01CS(CHIPS)':
 'UPI3_TX_DN11': CDS_PINID='UPI3_TX_DN11';
NODE_NAME     U1 CW76
 '@S9S_MB_2U_LIB.S9S_MB_2U(SCH_1):PAGE66_I16@PURE_QUANTA.SOCKET4677_AZIF0045P001C01CS(CHIPS)':
 'UPI3_TX_DN12': CDS_PINID='UPI3_TX_DN12';
NODE_NAME     U1 CU76
 '@S9S_MB_2U_LIB.S9S_MB_2U(SCH_1):PAGE66_I16@PURE_QUANTA.SOCKET4677_AZIF0045P001C01CS(CHIPS)':
 'UPI3_TX_DN13': CDS_PINID='UPI3_TX_DN13';
NODE_NAME     U1 CT75
 '@S9S_MB_2U_LIB.S9S_MB_2U(SCH_1):PAGE66_I16@PURE_QUANTA.SOCKET4677_AZIF0045P001C01CS(CHIPS)':
 'UPI3_TX_DN14': CDS_PINID='UPI3_TX_DN14';
NODE_NAME     U1 CR74
 '@S9S_MB_2U_LIB.S9S_MB_2U(SCH_1):PAGE66_I16@PURE_QUANTA.SOCKET4677_AZIF0045P001C01CS(CHIPS)':
 'UPI3_TX_DN15': CDS_PINID='UPI3_TX_DN15';
NODE_NAME     U1 CK77
 '@S9S_MB_2U_LIB.S9S_MB_2U(SCH_1):PAGE66_I16@PURE_QUANTA.SOCKET4677_AZIF0045P001C01CS(CHIPS)':
 'UPI3_TX_DN16': CDS_PINID='UPI3_TX_DN16';
NODE_NAME     U1 CH77
 '@S9S_MB_2U_LIB.S9S_MB_2U(SCH_1):PAGE66_I16@PURE_QUANTA.SOCKET4677_AZIF0045P001C01CS(CHIPS)':
 'UPI3_TX_DN17': CDS_PINID='UPI3_TX_DN17';
NODE_NAME     U1 CM75
 '@S9S_MB_2U_LIB.S9S_MB_2U(SCH_1):PAGE66_I16@PURE_QUANTA.SOCKET4677_AZIF0045P001C01CS(CHIPS)':
 'UPI3_TX_DN18': CDS_PINID='UPI3_TX_DN18';
NODE_NAME     U1 CG76
 '@S9S_MB_2U_LIB.S9S_MB_2U(SCH_1):PAGE66_I16@PURE_QUANTA.SOCKET4677_AZIF0045P001C01CS(CHIPS)':
 'UPI3_TX_DN19': CDS_PINID='UPI3_TX_DN19';
NODE_NAME     U1 CF75
 '@S9S_MB_2U_LIB.S9S_MB_2U(SCH_1):PAGE66_I16@PURE_QUANTA.SOCKET4677_AZIF0045P001C01CS(CHIPS)':
 'UPI3_TX_DN20': CDS_PINID='UPI3_TX_DN20';
NODE_NAME     U1 CJ74
 '@S9S_MB_2U_LIB.S9S_MB_2U(SCH_1):PAGE66_I16@PURE_QUANTA.SOCKET4677_AZIF0045P001C01CS(CHIPS)':
 'UPI3_TX_DN21': CDS_PINID='UPI3_TX_DN21';
NODE_NAME     U1 CV73
 '@S9S_MB_2U_LIB.S9S_MB_2U(SCH_1):PAGE66_I16@PURE_QUANTA.SOCKET4677_AZIF0045P001C01CS(CHIPS)':
 'UPI3_TX_DN22': CDS_PINID='UPI3_TX_DN22';
NODE_NAME     U1 CF73
 '@S9S_MB_2U_LIB.S9S_MB_2U(SCH_1):PAGE66_I16@PURE_QUANTA.SOCKET4677_AZIF0045P001C01CS(CHIPS)':
 'UPI3_TX_DN23': CDS_PINID='UPI3_TX_DN23';
NODE_NAME     U1 EK85
 '@S9S_MB_2U_LIB.S9S_MB_2U(SCH_1):PAGE66_I16@PURE_QUANTA.SOCKET4677_AZIF0045P001C01CS(CHIPS)':
 'UPI3_TX_DP0': CDS_PINID='UPI3_TX_DP0';
NODE_NAME     U1 EM85
 '@S9S_MB_2U_LIB.S9S_MB_2U(SCH_1):PAGE66_I16@PURE_QUANTA.SOCKET4677_AZIF0045P001C01CS(CHIPS)':
 'UPI3_TX_DP1': CDS_PINID='UPI3_TX_DP1';
NODE_NAME     U1 EN86
 '@S9S_MB_2U_LIB.S9S_MB_2U(SCH_1):PAGE66_I16@PURE_QUANTA.SOCKET4677_AZIF0045P001C01CS(CHIPS)':
 'UPI3_TX_DP2': CDS_PINID='UPI3_TX_DP2';
NODE_NAME     U1 EP87
 '@S9S_MB_2U_LIB.S9S_MB_2U(SCH_1):PAGE66_I16@PURE_QUANTA.SOCKET4677_AZIF0045P001C01CS(CHIPS)':
 'UPI3_TX_DP3': CDS_PINID='UPI3_TX_DP3';
NODE_NAME     U1 EH87
 '@S9S_MB_2U_LIB.S9S_MB_2U(SCH_1):PAGE66_I16@PURE_QUANTA.SOCKET4677_AZIF0045P001C01CS(CHIPS)':
 'UPI3_TX_DP4': CDS_PINID='UPI3_TX_DP4';
NODE_NAME     U1 EL88
 '@S9S_MB_2U_LIB.S9S_MB_2U(SCH_1):PAGE66_I16@PURE_QUANTA.SOCKET4677_AZIF0045P001C01CS(CHIPS)':
 'UPI3_TX_DP5': CDS_PINID='UPI3_TX_DP5';
NODE_NAME     U1 DT81
 '@S9S_MB_2U_LIB.S9S_MB_2U(SCH_1):PAGE66_I16@PURE_QUANTA.SOCKET4677_AZIF0045P001C01CS(CHIPS)':
 'UPI3_TX_DP6': CDS_PINID='UPI3_TX_DP6';
NODE_NAME     U1 DU82
 '@S9S_MB_2U_LIB.S9S_MB_2U(SCH_1):PAGE66_I16@PURE_QUANTA.SOCKET4677_AZIF0045P001C01CS(CHIPS)':
 'UPI3_TX_DP7': CDS_PINID='UPI3_TX_DP7';
NODE_NAME     U1 DR80
 '@S9S_MB_2U_LIB.S9S_MB_2U(SCH_1):PAGE66_I16@PURE_QUANTA.SOCKET4677_AZIF0045P001C01CS(CHIPS)':
 'UPI3_TX_DP8': CDS_PINID='UPI3_TX_DP8';
NODE_NAME     U1 DP83
 '@S9S_MB_2U_LIB.S9S_MB_2U(SCH_1):PAGE66_I16@PURE_QUANTA.SOCKET4677_AZIF0045P001C01CS(CHIPS)':
 'UPI3_TX_DP9': CDS_PINID='UPI3_TX_DP9';
NODE_NAME     U1 DL82
 '@S9S_MB_2U_LIB.S9S_MB_2U(SCH_1):PAGE66_I16@PURE_QUANTA.SOCKET4677_AZIF0045P001C01CS(CHIPS)':
 'UPI3_TX_DP10': CDS_PINID='UPI3_TX_DP10';
NODE_NAME     U1 DN80
 '@S9S_MB_2U_LIB.S9S_MB_2U(SCH_1):PAGE66_I16@PURE_QUANTA.SOCKET4677_AZIF0045P001C01CS(CHIPS)':
 'UPI3_TX_DP11': CDS_PINID='UPI3_TX_DP11';
NODE_NAME     U1 DA76
 '@S9S_MB_2U_LIB.S9S_MB_2U(SCH_1):PAGE66_I16@PURE_QUANTA.SOCKET4677_AZIF0045P001C01CS(CHIPS)':
 'UPI3_TX_DP12': CDS_PINID='UPI3_TX_DP12';
NODE_NAME     U1 CV77
 '@S9S_MB_2U_LIB.S9S_MB_2U(SCH_1):PAGE66_I16@PURE_QUANTA.SOCKET4677_AZIF0045P001C01CS(CHIPS)':
 'UPI3_TX_DP13': CDS_PINID='UPI3_TX_DP13';
NODE_NAME     U1 CR76
 '@S9S_MB_2U_LIB.S9S_MB_2U(SCH_1):PAGE66_I16@PURE_QUANTA.SOCKET4677_AZIF0045P001C01CS(CHIPS)':
 'UPI3_TX_DP14': CDS_PINID='UPI3_TX_DP14';
NODE_NAME     U1 CU74
 '@S9S_MB_2U_LIB.S9S_MB_2U(SCH_1):PAGE66_I16@PURE_QUANTA.SOCKET4677_AZIF0045P001C01CS(CHIPS)':
 'UPI3_TX_DP15': CDS_PINID='UPI3_TX_DP15';
NODE_NAME     U1 CM77
 '@S9S_MB_2U_LIB.S9S_MB_2U(SCH_1):PAGE66_I16@PURE_QUANTA.SOCKET4677_AZIF0045P001C01CS(CHIPS)':
 'UPI3_TX_DP16': CDS_PINID='UPI3_TX_DP16';
NODE_NAME     U1 CJ78
 '@S9S_MB_2U_LIB.S9S_MB_2U(SCH_1):PAGE66_I16@PURE_QUANTA.SOCKET4677_AZIF0045P001C01CS(CHIPS)':
 'UPI3_TX_DP17': CDS_PINID='UPI3_TX_DP17';
NODE_NAME     U1 CL76
 '@S9S_MB_2U_LIB.S9S_MB_2U(SCH_1):PAGE66_I16@PURE_QUANTA.SOCKET4677_AZIF0045P001C01CS(CHIPS)':
 'UPI3_TX_DP18': CDS_PINID='UPI3_TX_DP18';
NODE_NAME     U1 CF77
 '@S9S_MB_2U_LIB.S9S_MB_2U(SCH_1):PAGE66_I16@PURE_QUANTA.SOCKET4677_AZIF0045P001C01CS(CHIPS)':
 'UPI3_TX_DP19': CDS_PINID='UPI3_TX_DP19';
NODE_NAME     U1 CH75
 '@S9S_MB_2U_LIB.S9S_MB_2U(SCH_1):PAGE66_I16@PURE_QUANTA.SOCKET4677_AZIF0045P001C01CS(CHIPS)':
 'UPI3_TX_DP20': CDS_PINID='UPI3_TX_DP20';
NODE_NAME     U1 CK75
 '@S9S_MB_2U_LIB.S9S_MB_2U(SCH_1):PAGE66_I16@PURE_QUANTA.SOCKET4677_AZIF0045P001C01CS(CHIPS)':
 'UPI3_TX_DP21': CDS_PINID='UPI3_TX_DP21';
NODE_NAME     U1 CW74
 '@S9S_MB_2U_LIB.S9S_MB_2U(SCH_1):PAGE66_I16@PURE_QUANTA.SOCKET4677_AZIF0045P001C01CS(CHIPS)':
 'UPI3_TX_DP22': CDS_PINID='UPI3_TX_DP22';
NODE_NAME     U1 CD73
 '@S9S_MB_2U_LIB.S9S_MB_2U(SCH_1):PAGE66_I16@PURE_QUANTA.SOCKET4677_AZIF0045P001C01CS(CHIPS)':
 'UPI3_TX_DP23': CDS_PINID='UPI3_TX_DP23';
NODE_NAME     U75 1
 '@S9S_MB_2U_LIB.S9S_MB_2U(SCH_1):PAGE152_I1@PURE_QUANTA.74LVC1G17GW(CHIPS)':
 'NC': CDS_PINID='NC';
NODE_NAME     PU13_P0_1 31
 '@S9S_MB_2U_LIB.S9S_MB_2U(SCH_1):PAGE253_I40@PURE_QUANTA.ISL99390FRZTR5935(CHIPS)':
 'DNC': CDS_PINID='DNC';
NODE_NAME     PU13_P0_1 6
 '@S9S_MB_2U_LIB.S9S_MB_2U(SCH_1):PAGE253_I40@PURE_QUANTA.ISL99390FRZTR5935(CHIPS)':
 'GL1': CDS_PINID='GL1';
NODE_NAME     PU13_P0_1 41
 '@S9S_MB_2U_LIB.S9S_MB_2U(SCH_1):PAGE253_I40@PURE_QUANTA.ISL99390FRZTR5935(CHIPS)':
 'GL2': CDS_PINID='GL2';
NODE_NAME     PU10_P0_4 31
 '@S9S_MB_2U_LIB.S9S_MB_2U(SCH_1):PAGE254_I13@PURE_QUANTA.ISL99390FRZTR5935(CHIPS)':
 'DNC': CDS_PINID='DNC';
NODE_NAME     PU10_P0_4 6
 '@S9S_MB_2U_LIB.S9S_MB_2U(SCH_1):PAGE254_I13@PURE_QUANTA.ISL99390FRZTR5935(CHIPS)':
 'GL1': CDS_PINID='GL1';
NODE_NAME     PU10_P0_4 41
 '@S9S_MB_2U_LIB.S9S_MB_2U(SCH_1):PAGE254_I13@PURE_QUANTA.ISL99390FRZTR5935(CHIPS)':
 'GL2': CDS_PINID='GL2';
NODE_NAME     PU8_P0_6 31
 '@S9S_MB_2U_LIB.S9S_MB_2U(SCH_1):PAGE255_I12@PURE_QUANTA.ISL99390FRZTR5935(CHIPS)':
 'DNC': CDS_PINID='DNC';
NODE_NAME     PU8_P0_6 6
 '@S9S_MB_2U_LIB.S9S_MB_2U(SCH_1):PAGE255_I12@PURE_QUANTA.ISL99390FRZTR5935(CHIPS)':
 'GL1': CDS_PINID='GL1';
NODE_NAME     PU8_P0_6 41
 '@S9S_MB_2U_LIB.S9S_MB_2U(SCH_1):PAGE255_I12@PURE_QUANTA.ISL99390FRZTR5935(CHIPS)':
 'GL2': CDS_PINID='GL2';
NODE_NAME     PU6_P0_8 31
 '@S9S_MB_2U_LIB.S9S_MB_2U(SCH_1):PAGE256_I2@PURE_QUANTA.ISL99390FRZTR5935(CHIPS)':
 'DNC': CDS_PINID='DNC';
NODE_NAME     PU6_P0_8 6
 '@S9S_MB_2U_LIB.S9S_MB_2U(SCH_1):PAGE256_I2@PURE_QUANTA.ISL99390FRZTR5935(CHIPS)':
 'GL1': CDS_PINID='GL1';
NODE_NAME     PU6_P0_8 41
 '@S9S_MB_2U_LIB.S9S_MB_2U(SCH_1):PAGE256_I2@PURE_QUANTA.ISL99390FRZTR5935(CHIPS)':
 'GL2': CDS_PINID='GL2';
NODE_NAME     PU26_P1_5 31
 '@S9S_MB_2U_LIB.S9S_MB_2U(SCH_1):PAGE273_I23@PURE_QUANTA.ISL99390FRZTR5935(CHIPS)':
 'DNC': CDS_PINID='DNC';
NODE_NAME     PU26_P1_5 6
 '@S9S_MB_2U_LIB.S9S_MB_2U(SCH_1):PAGE273_I23@PURE_QUANTA.ISL99390FRZTR5935(CHIPS)':
 'GL1': CDS_PINID='GL1';
NODE_NAME     PU26_P1_5 41
 '@S9S_MB_2U_LIB.S9S_MB_2U(SCH_1):PAGE273_I23@PURE_QUANTA.ISL99390FRZTR5935(CHIPS)':
 'GL2': CDS_PINID='GL2';
NODE_NAME     PU50_P1_1 31
 '@S9S_MB_2U_LIB.S9S_MB_2U(SCH_1):PAGE279_I38@PURE_QUANTA.ISL99390FRZTR5935(CHIPS)':
 'DNC': CDS_PINID='DNC';
NODE_NAME     PU50_P1_1 6
 '@S9S_MB_2U_LIB.S9S_MB_2U(SCH_1):PAGE279_I38@PURE_QUANTA.ISL99390FRZTR5935(CHIPS)':
 'GL1': CDS_PINID='GL1';
NODE_NAME     PU50_P1_1 41
 '@S9S_MB_2U_LIB.S9S_MB_2U(SCH_1):PAGE279_I38@PURE_QUANTA.ISL99390FRZTR5935(CHIPS)':
 'GL2': CDS_PINID='GL2';
NODE_NAME     PU49 27
 '@S9S_MB_2U_LIB.S9S_MB_2U(SCH_1):PAGE280_I14@PURE_QUANTA.RAA2213404GNPHB0(CHIPS)':
 'GL2': CDS_PINID='GL2';
NODE_NAME     H30 1
 '@S9S_MB_2U_LIB.S9S_MB_2U(SCH_1):PAGE289_I7@PURE_QUANTA.HOLE(CHIPS)':
 '1': CDS_PINID='\1\';
NODE_NAME     H29 1
 '@S9S_MB_2U_LIB.S9S_MB_2U(SCH_1):PAGE289_I8@PURE_QUANTA.HOLE(CHIPS)':
 '1': CDS_PINID='\1\';
NODE_NAME     H38 1
 '@S9S_MB_2U_LIB.S9S_MB_2U(SCH_1):PAGE289_I9@PURE_QUANTA.HOLE(CHIPS)':
 '1': CDS_PINID='\1\';
NODE_NAME     H36 1
 '@S9S_MB_2U_LIB.S9S_MB_2U(SCH_1):PAGE289_I10@PURE_QUANTA.HOLE(CHIPS)':
 '1': CDS_PINID='\1\';
NODE_NAME     H28 1
 '@S9S_MB_2U_LIB.S9S_MB_2U(SCH_1):PAGE289_I11@PURE_QUANTA.HOLE(CHIPS)':
 '1': CDS_PINID='\1\';
NODE_NAME     H27 1
 '@S9S_MB_2U_LIB.S9S_MB_2U(SCH_1):PAGE289_I12@PURE_QUANTA.HOLE(CHIPS)':
 '1': CDS_PINID='\1\';
NODE_NAME     H26 1
 '@S9S_MB_2U_LIB.S9S_MB_2U(SCH_1):PAGE289_I19@PURE_QUANTA.HOLE(CHIPS)':
 '1': CDS_PINID='\1\';
NODE_NAME     H24 1
 '@S9S_MB_2U_LIB.S9S_MB_2U(SCH_1):PAGE289_I20@PURE_QUANTA.HOLE(CHIPS)':
 '1': CDS_PINID='\1\';
NODE_NAME     H22 1
 '@S9S_MB_2U_LIB.S9S_MB_2U(SCH_1):PAGE289_I21@PURE_QUANTA.HOLE(CHIPS)':
 '1': CDS_PINID='\1\';
NODE_NAME     H75 1
 '@S9S_MB_2U_LIB.S9S_MB_2U(SCH_1):PAGE289_I57@PURE_QUANTA.HOLE(CHIPS)':
 '1': CDS_PINID='\1\';
NODE_NAME     H74 1
 '@S9S_MB_2U_LIB.S9S_MB_2U(SCH_1):PAGE289_I58@PURE_QUANTA.HOLE(CHIPS)':
 '1': CDS_PINID='\1\';
NODE_NAME     H20 1
 '@S9S_MB_2U_LIB.S9S_MB_2U(SCH_1):PAGE289_I60@PURE_QUANTA.HOLE(CHIPS)':
 '1': CDS_PINID='\1\';
NODE_NAME     H18 1
 '@S9S_MB_2U_LIB.S9S_MB_2U(SCH_1):PAGE289_I61@PURE_QUANTA.HOLE(CHIPS)':
 '1': CDS_PINID='\1\';
NODE_NAME     H16 1
 '@S9S_MB_2U_LIB.S9S_MB_2U(SCH_1):PAGE289_I63@PURE_QUANTA.HOLE(CHIPS)':
 '1': CDS_PINID='\1\';
NODE_NAME     H25 1
 '@S9S_MB_2U_LIB.S9S_MB_2U(SCH_1):PAGE289_I64@PURE_QUANTA.HOLE(CHIPS)':
 '1': CDS_PINID='\1\';
NODE_NAME     H23 1
 '@S9S_MB_2U_LIB.S9S_MB_2U(SCH_1):PAGE289_I72@PURE_QUANTA.HOLE(CHIPS)':
 '1': CDS_PINID='\1\';
NODE_NAME     H21 1
 '@S9S_MB_2U_LIB.S9S_MB_2U(SCH_1):PAGE289_I73@PURE_QUANTA.HOLE(CHIPS)':
 '1': CDS_PINID='\1\';
NODE_NAME     H19 1
 '@S9S_MB_2U_LIB.S9S_MB_2U(SCH_1):PAGE289_I74@PURE_QUANTA.HOLE(CHIPS)':
 '1': CDS_PINID='\1\';
NODE_NAME     H17 1
 '@S9S_MB_2U_LIB.S9S_MB_2U(SCH_1):PAGE289_I75@PURE_QUANTA.HOLE(CHIPS)':
 '1': CDS_PINID='\1\';
NODE_NAME     H15 1
 '@S9S_MB_2U_LIB.S9S_MB_2U(SCH_1):PAGE289_I83@PURE_QUANTA.HOLE(CHIPS)':
 '1': CDS_PINID='\1\';
NODE_NAME     DM13 1
 '@S9S_MB_2U_LIB.S9S_MB_2U(SCH_1):PAGE290_I17@PURE_QUANTA.DUMMY_SYMBOL(CHIPS)':
 '1': CDS_PINID='\1\';
NODE_NAME     DM9 1
 '@S9S_MB_2U_LIB.S9S_MB_2U(SCH_1):PAGE290_I23@PURE_QUANTA.DUMMY_SYMBOL(CHIPS)':
 '1': CDS_PINID='\1\';
NODE_NAME     U1_BL 1
 '@S9S_MB_2U_LIB.S9S_MB_2U(SCH_1):PAGE290_I40@PURE_QUANTA.TP(CHIPS)':
 'TP': CDS_PINID='TP';
NODE_NAME     U2_BL 1
 '@S9S_MB_2U_LIB.S9S_MB_2U(SCH_1):PAGE290_I41@PURE_QUANTA.TP(CHIPS)':
 'TP': CDS_PINID='TP';
NODE_NAME     U2_BP 1
 '@S9S_MB_2U_LIB.S9S_MB_2U(SCH_1):PAGE290_I42@PURE_QUANTA.TP(CHIPS)':
 'TP': CDS_PINID='TP';
NODE_NAME     U1_BP 1
 '@S9S_MB_2U_LIB.S9S_MB_2U(SCH_1):PAGE290_I43@PURE_QUANTA.TP(CHIPS)':
 'TP': CDS_PINID='TP';
NODE_NAME     U2_DC 1
 '@S9S_MB_2U_LIB.S9S_MB_2U(SCH_1):PAGE290_I45@PURE_QUANTA.TP(CHIPS)':
 'TP': CDS_PINID='TP';
NODE_NAME     U1_DC 1
 '@S9S_MB_2U_LIB.S9S_MB_2U(SCH_1):PAGE290_I47@PURE_QUANTA.TP(CHIPS)':
 'TP': CDS_PINID='TP';
NODE_NAME     J100 14
 '@S9S_MB_2U_LIB.S9S_MB_2U(SCH_1):PAGE215_I32@PURE_QUANTA.SCONN20_513860200CV01(CHIPS)':
 '14': CDS_PINID='\14\';
NODE_NAME     J100 20
 '@S9S_MB_2U_LIB.S9S_MB_2U(SCH_1):PAGE215_I32@PURE_QUANTA.SCONN20_513860200CV01(CHIPS)':
 '20': CDS_PINID='\20\';
NODE_NAME     U207 1
 '@S9S_MB_2U_LIB.S9S_MB_2U(SCH_1):PAGE156_I35@PURE_QUANTA.74LVC1G17GW(CHIPS)':
 'NC': CDS_PINID='NC';
NODE_NAME     U249 E1
 '@S9S_MB_2U_LIB.S9S_MB_2U(SCH_1):PAGE311_I33@PURE_QUANTA.LCMXO3LF9400C5BG484C(CHIPS)':
 'PL6A': CDS_PINID='PL6A';
NODE_NAME     U249 F1
 '@S9S_MB_2U_LIB.S9S_MB_2U(SCH_1):PAGE311_I33@PURE_QUANTA.LCMXO3LF9400C5BG484C(CHIPS)':
 'PL6B': CDS_PINID='PL6B';
NODE_NAME     U249 G3
 '@S9S_MB_2U_LIB.S9S_MB_2U(SCH_1):PAGE311_I33@PURE_QUANTA.LCMXO3LF9400C5BG484C(CHIPS)':
 'PL6C': CDS_PINID='PL6C';
NODE_NAME     U249 G4
 '@S9S_MB_2U_LIB.S9S_MB_2U(SCH_1):PAGE311_I33@PURE_QUANTA.LCMXO3LF9400C5BG484C(CHIPS)':
 'PL6D': CDS_PINID='PL6D';
NODE_NAME     U249 L1
 '@S9S_MB_2U_LIB.S9S_MB_2U(SCH_1):PAGE311_I33@PURE_QUANTA.LCMXO3LF9400C5BG484C(CHIPS)':
 'PL16A||PCLKT4_0': CDS_PINID='\pl16a||pclkt4_0\';
NODE_NAME     U249 M2
 '@S9S_MB_2U_LIB.S9S_MB_2U(SCH_1):PAGE311_I33@PURE_QUANTA.LCMXO3LF9400C5BG484C(CHIPS)':
 'PL16B||PCLKC4_0': CDS_PINID='\pl16b||pclkc4_0\';
NODE_NAME     U249 L3
 '@S9S_MB_2U_LIB.S9S_MB_2U(SCH_1):PAGE311_I33@PURE_QUANTA.LCMXO3LF9400C5BG484C(CHIPS)':
 'PL16C': CDS_PINID='PL16C';
NODE_NAME     U249 L4
 '@S9S_MB_2U_LIB.S9S_MB_2U(SCH_1):PAGE311_I33@PURE_QUANTA.LCMXO3LF9400C5BG484C(CHIPS)':
 'PL16D': CDS_PINID='PL16D';
NODE_NAME     U249 M1
 '@S9S_MB_2U_LIB.S9S_MB_2U(SCH_1):PAGE311_I33@PURE_QUANTA.LCMXO3LF9400C5BG484C(CHIPS)':
 'PL17A': CDS_PINID='PL17A';
NODE_NAME     U249 N1
 '@S9S_MB_2U_LIB.S9S_MB_2U(SCH_1):PAGE311_I33@PURE_QUANTA.LCMXO3LF9400C5BG484C(CHIPS)':
 'PL17B': CDS_PINID='PL17B';
NODE_NAME     U249 M6
 '@S9S_MB_2U_LIB.S9S_MB_2U(SCH_1):PAGE311_I33@PURE_QUANTA.LCMXO3LF9400C5BG484C(CHIPS)':
 'PL17C': CDS_PINID='PL17C';
NODE_NAME     U249 M5
 '@S9S_MB_2U_LIB.S9S_MB_2U(SCH_1):PAGE311_I33@PURE_QUANTA.LCMXO3LF9400C5BG484C(CHIPS)':
 'PL17D': CDS_PINID='PL17D';
NODE_NAME     U249 N2
 '@S9S_MB_2U_LIB.S9S_MB_2U(SCH_1):PAGE311_I33@PURE_QUANTA.LCMXO3LF9400C5BG484C(CHIPS)':
 'PL18A': CDS_PINID='PL18A';
NODE_NAME     U249 P1
 '@S9S_MB_2U_LIB.S9S_MB_2U(SCH_1):PAGE311_I33@PURE_QUANTA.LCMXO3LF9400C5BG484C(CHIPS)':
 'PL18B': CDS_PINID='PL18B';
NODE_NAME     U249 N3
 '@S9S_MB_2U_LIB.S9S_MB_2U(SCH_1):PAGE311_I33@PURE_QUANTA.LCMXO3LF9400C5BG484C(CHIPS)':
 'PL18C': CDS_PINID='PL18C';
NODE_NAME     U249 N4
 '@S9S_MB_2U_LIB.S9S_MB_2U(SCH_1):PAGE311_I33@PURE_QUANTA.LCMXO3LF9400C5BG484C(CHIPS)':
 'PL18D': CDS_PINID='PL18D';
NODE_NAME     U249 P2
 '@S9S_MB_2U_LIB.S9S_MB_2U(SCH_1):PAGE311_I33@PURE_QUANTA.LCMXO3LF9400C5BG484C(CHIPS)':
 'PL19A': CDS_PINID='PL19A';
NODE_NAME     U249 R1
 '@S9S_MB_2U_LIB.S9S_MB_2U(SCH_1):PAGE311_I33@PURE_QUANTA.LCMXO3LF9400C5BG484C(CHIPS)':
 'PL19B': CDS_PINID='PL19B';
NODE_NAME     U249 P3
 '@S9S_MB_2U_LIB.S9S_MB_2U(SCH_1):PAGE311_I33@PURE_QUANTA.LCMXO3LF9400C5BG484C(CHIPS)':
 'PL19C': CDS_PINID='PL19C';
NODE_NAME     U249 M7
 '@S9S_MB_2U_LIB.S9S_MB_2U(SCH_1):PAGE311_I33@PURE_QUANTA.LCMXO3LF9400C5BG484C(CHIPS)':
 'PL19D': CDS_PINID='PL19D';
NODE_NAME     U249 P4
 '@S9S_MB_2U_LIB.S9S_MB_2U(SCH_1):PAGE311_I33@PURE_QUANTA.LCMXO3LF9400C5BG484C(CHIPS)':
 'PL20A': CDS_PINID='PL20A';
NODE_NAME     U249 N5
 '@S9S_MB_2U_LIB.S9S_MB_2U(SCH_1):PAGE311_I33@PURE_QUANTA.LCMXO3LF9400C5BG484C(CHIPS)':
 'PL20B': CDS_PINID='PL20B';
NODE_NAME     U249 N6
 '@S9S_MB_2U_LIB.S9S_MB_2U(SCH_1):PAGE311_I33@PURE_QUANTA.LCMXO3LF9400C5BG484C(CHIPS)':
 'PL20C': CDS_PINID='PL20C';
NODE_NAME     U249 N7
 '@S9S_MB_2U_LIB.S9S_MB_2U(SCH_1):PAGE311_I33@PURE_QUANTA.LCMXO3LF9400C5BG484C(CHIPS)':
 'PL20D': CDS_PINID='PL20D';
NODE_NAME     U249 R2
 '@S9S_MB_2U_LIB.S9S_MB_2U(SCH_1):PAGE311_I33@PURE_QUANTA.LCMXO3LF9400C5BG484C(CHIPS)':
 'PL21A': CDS_PINID='PL21A';
NODE_NAME     U249 T1
 '@S9S_MB_2U_LIB.S9S_MB_2U(SCH_1):PAGE311_I33@PURE_QUANTA.LCMXO3LF9400C5BG484C(CHIPS)':
 'PL21B': CDS_PINID='PL21B';
NODE_NAME     U249 P6
 '@S9S_MB_2U_LIB.S9S_MB_2U(SCH_1):PAGE311_I33@PURE_QUANTA.LCMXO3LF9400C5BG484C(CHIPS)':
 'PL21D': CDS_PINID='PL21D';
NODE_NAME     U249 R3
 '@S9S_MB_2U_LIB.S9S_MB_2U(SCH_1):PAGE311_I33@PURE_QUANTA.LCMXO3LF9400C5BG484C(CHIPS)':
 'PL24A': CDS_PINID='PL24A';
NODE_NAME     U249 R4
 '@S9S_MB_2U_LIB.S9S_MB_2U(SCH_1):PAGE311_I33@PURE_QUANTA.LCMXO3LF9400C5BG484C(CHIPS)':
 'PL24B': CDS_PINID='PL24B';
NODE_NAME     U249 R5
 '@S9S_MB_2U_LIB.S9S_MB_2U(SCH_1):PAGE311_I33@PURE_QUANTA.LCMXO3LF9400C5BG484C(CHIPS)':
 'PL24C': CDS_PINID='PL24C';
NODE_NAME     U249 U2
 '@S9S_MB_2U_LIB.S9S_MB_2U(SCH_1):PAGE311_I33@PURE_QUANTA.LCMXO3LF9400C5BG484C(CHIPS)':
 'PL27A||PCLKT3_0': CDS_PINID='\pl27a||pclkt3_0\';
NODE_NAME     U249 V1
 '@S9S_MB_2U_LIB.S9S_MB_2U(SCH_1):PAGE311_I33@PURE_QUANTA.LCMXO3LF9400C5BG484C(CHIPS)':
 'PL27B||PCLKC3_0': CDS_PINID='\pl27b||pclkc3_0\';
NODE_NAME     U249 U3
 '@S9S_MB_2U_LIB.S9S_MB_2U(SCH_1):PAGE311_I33@PURE_QUANTA.LCMXO3LF9400C5BG484C(CHIPS)':
 'PL27C': CDS_PINID='PL27C';
NODE_NAME     U249 U4
 '@S9S_MB_2U_LIB.S9S_MB_2U(SCH_1):PAGE311_I33@PURE_QUANTA.LCMXO3LF9400C5BG484C(CHIPS)':
 'PL27D': CDS_PINID='PL27D';
NODE_NAME     PU76_P1_2 31
 '@S9S_MB_2U_LIB.S9S_MB_2U(SCH_1):PAGE275_I9@PURE_QUANTA.ISL99390FRZTR5935(CHIPS)':
 'DNC': CDS_PINID='DNC';
NODE_NAME     PU76_P1_2 6
 '@S9S_MB_2U_LIB.S9S_MB_2U(SCH_1):PAGE275_I9@PURE_QUANTA.ISL99390FRZTR5935(CHIPS)':
 'GL1': CDS_PINID='GL1';
NODE_NAME     PU76_P1_2 41
 '@S9S_MB_2U_LIB.S9S_MB_2U(SCH_1):PAGE275_I9@PURE_QUANTA.ISL99390FRZTR5935(CHIPS)':
 'GL2': CDS_PINID='GL2';
NODE_NAME     PU11_P0_3 31
 '@S9S_MB_2U_LIB.S9S_MB_2U(SCH_1):PAGE254_I20@PURE_QUANTA.ISL99390FRZTR5935(CHIPS)':
 'DNC': CDS_PINID='DNC';
NODE_NAME     PU11_P0_3 6
 '@S9S_MB_2U_LIB.S9S_MB_2U(SCH_1):PAGE254_I20@PURE_QUANTA.ISL99390FRZTR5935(CHIPS)':
 'GL1': CDS_PINID='GL1';
NODE_NAME     PU11_P0_3 41
 '@S9S_MB_2U_LIB.S9S_MB_2U(SCH_1):PAGE254_I20@PURE_QUANTA.ISL99390FRZTR5935(CHIPS)':
 'GL2': CDS_PINID='GL2';
NODE_NAME     PU9_P0_5 31
 '@S9S_MB_2U_LIB.S9S_MB_2U(SCH_1):PAGE255_I66@PURE_QUANTA.ISL99390FRZTR5935(CHIPS)':
 'DNC': CDS_PINID='DNC';
NODE_NAME     PU9_P0_5 6
 '@S9S_MB_2U_LIB.S9S_MB_2U(SCH_1):PAGE255_I66@PURE_QUANTA.ISL99390FRZTR5935(CHIPS)':
 'GL1': CDS_PINID='GL1';
NODE_NAME     PU9_P0_5 41
 '@S9S_MB_2U_LIB.S9S_MB_2U(SCH_1):PAGE255_I66@PURE_QUANTA.ISL99390FRZTR5935(CHIPS)':
 'GL2': CDS_PINID='GL2';
NODE_NAME     PU7_P0_7 31
 '@S9S_MB_2U_LIB.S9S_MB_2U(SCH_1):PAGE256_I32@PURE_QUANTA.ISL99390FRZTR5935(CHIPS)':
 'DNC': CDS_PINID='DNC';
NODE_NAME     PU7_P0_7 6
 '@S9S_MB_2U_LIB.S9S_MB_2U(SCH_1):PAGE256_I32@PURE_QUANTA.ISL99390FRZTR5935(CHIPS)':
 'GL1': CDS_PINID='GL1';
NODE_NAME     PU7_P0_7 41
 '@S9S_MB_2U_LIB.S9S_MB_2U(SCH_1):PAGE256_I32@PURE_QUANTA.ISL99390FRZTR5935(CHIPS)':
 'GL2': CDS_PINID='GL2';
NODE_NAME     PU44_P0_2 31
 '@S9S_MB_2U_LIB.S9S_MB_2U(SCH_1):PAGE261_I12@PURE_QUANTA.ISL99390FRZTR5935(CHIPS)':
 'DNC': CDS_PINID='DNC';
NODE_NAME     PU44_P0_2 6
 '@S9S_MB_2U_LIB.S9S_MB_2U(SCH_1):PAGE261_I12@PURE_QUANTA.ISL99390FRZTR5935(CHIPS)':
 'GL1': CDS_PINID='GL1';
NODE_NAME     PU44_P0_2 41
 '@S9S_MB_2U_LIB.S9S_MB_2U(SCH_1):PAGE261_I12@PURE_QUANTA.ISL99390FRZTR5935(CHIPS)':
 'GL2': CDS_PINID='GL2';
NODE_NAME     PU36 31
 '@S9S_MB_2U_LIB.S9S_MB_2U(SCH_1):PAGE265_I8@PURE_QUANTA.ISL99390FRZTR5935(CHIPS)':
 'DNC': CDS_PINID='DNC';
NODE_NAME     PU36 6
 '@S9S_MB_2U_LIB.S9S_MB_2U(SCH_1):PAGE265_I8@PURE_QUANTA.ISL99390FRZTR5935(CHIPS)':
 'GL1': CDS_PINID='GL1';
NODE_NAME     PU36 41
 '@S9S_MB_2U_LIB.S9S_MB_2U(SCH_1):PAGE265_I8@PURE_QUANTA.ISL99390FRZTR5935(CHIPS)':
 'GL2': CDS_PINID='GL2';
NODE_NAME     PU27_P1_4 31
 '@S9S_MB_2U_LIB.S9S_MB_2U(SCH_1):PAGE272_I10@PURE_QUANTA.ISL99390FRZTR5935(CHIPS)':
 'DNC': CDS_PINID='DNC';
NODE_NAME     PU27_P1_4 6
 '@S9S_MB_2U_LIB.S9S_MB_2U(SCH_1):PAGE272_I10@PURE_QUANTA.ISL99390FRZTR5935(CHIPS)':
 'GL1': CDS_PINID='GL1';
NODE_NAME     PU27_P1_4 41
 '@S9S_MB_2U_LIB.S9S_MB_2U(SCH_1):PAGE272_I10@PURE_QUANTA.ISL99390FRZTR5935(CHIPS)':
 'GL2': CDS_PINID='GL2';
NODE_NAME     PU28_P1_3 31
 '@S9S_MB_2U_LIB.S9S_MB_2U(SCH_1):PAGE272_I66@PURE_QUANTA.ISL99390FRZTR5935(CHIPS)':
 'DNC': CDS_PINID='DNC';
NODE_NAME     PU28_P1_3 6
 '@S9S_MB_2U_LIB.S9S_MB_2U(SCH_1):PAGE272_I66@PURE_QUANTA.ISL99390FRZTR5935(CHIPS)':
 'GL1': CDS_PINID='GL1';
NODE_NAME     PU28_P1_3 41
 '@S9S_MB_2U_LIB.S9S_MB_2U(SCH_1):PAGE272_I66@PURE_QUANTA.ISL99390FRZTR5935(CHIPS)':
 'GL2': CDS_PINID='GL2';
NODE_NAME     PU25_P1_6 31
 '@S9S_MB_2U_LIB.S9S_MB_2U(SCH_1):PAGE273_I16@PURE_QUANTA.ISL99390FRZTR5935(CHIPS)':
 'DNC': CDS_PINID='DNC';
NODE_NAME     PU25_P1_6 6
 '@S9S_MB_2U_LIB.S9S_MB_2U(SCH_1):PAGE273_I16@PURE_QUANTA.ISL99390FRZTR5935(CHIPS)':
 'GL1': CDS_PINID='GL1';
NODE_NAME     PU25_P1_6 41
 '@S9S_MB_2U_LIB.S9S_MB_2U(SCH_1):PAGE273_I16@PURE_QUANTA.ISL99390FRZTR5935(CHIPS)':
 'GL2': CDS_PINID='GL2';
NODE_NAME     PU23_P1_8 31
 '@S9S_MB_2U_LIB.S9S_MB_2U(SCH_1):PAGE274_I11@PURE_QUANTA.ISL99390FRZTR5935(CHIPS)':
 'DNC': CDS_PINID='DNC';
NODE_NAME     PU23_P1_8 6
 '@S9S_MB_2U_LIB.S9S_MB_2U(SCH_1):PAGE274_I11@PURE_QUANTA.ISL99390FRZTR5935(CHIPS)':
 'GL1': CDS_PINID='GL1';
NODE_NAME     PU23_P1_8 41
 '@S9S_MB_2U_LIB.S9S_MB_2U(SCH_1):PAGE274_I11@PURE_QUANTA.ISL99390FRZTR5935(CHIPS)':
 'GL2': CDS_PINID='GL2';
NODE_NAME     PU24_P1_7 31
 '@S9S_MB_2U_LIB.S9S_MB_2U(SCH_1):PAGE274_I20@PURE_QUANTA.ISL99390FRZTR5935(CHIPS)':
 'DNC': CDS_PINID='DNC';
NODE_NAME     PU24_P1_7 6
 '@S9S_MB_2U_LIB.S9S_MB_2U(SCH_1):PAGE274_I20@PURE_QUANTA.ISL99390FRZTR5935(CHIPS)':
 'GL1': CDS_PINID='GL1';
NODE_NAME     PU24_P1_7 41
 '@S9S_MB_2U_LIB.S9S_MB_2U(SCH_1):PAGE274_I20@PURE_QUANTA.ISL99390FRZTR5935(CHIPS)':
 'GL2': CDS_PINID='GL2';
NODE_NAME     PU78_P1_4 31
 '@S9S_MB_2U_LIB.S9S_MB_2U(SCH_1):PAGE276_I15@PURE_QUANTA.ISL99390FRZTR5935(CHIPS)':
 'DNC': CDS_PINID='DNC';
NODE_NAME     PU78_P1_4 6
 '@S9S_MB_2U_LIB.S9S_MB_2U(SCH_1):PAGE276_I15@PURE_QUANTA.ISL99390FRZTR5935(CHIPS)':
 'GL1': CDS_PINID='GL1';
NODE_NAME     PU78_P1_4 41
 '@S9S_MB_2U_LIB.S9S_MB_2U(SCH_1):PAGE276_I15@PURE_QUANTA.ISL99390FRZTR5935(CHIPS)':
 'GL2': CDS_PINID='GL2';
NODE_NAME     PU51_P1_2 31
 '@S9S_MB_2U_LIB.S9S_MB_2U(SCH_1):PAGE279_I29@PURE_QUANTA.ISL99390FRZTR5935(CHIPS)':
 'DNC': CDS_PINID='DNC';
NODE_NAME     PU51_P1_2 6
 '@S9S_MB_2U_LIB.S9S_MB_2U(SCH_1):PAGE279_I29@PURE_QUANTA.ISL99390FRZTR5935(CHIPS)':
 'GL1': CDS_PINID='GL1';
NODE_NAME     PU51_P1_2 41
 '@S9S_MB_2U_LIB.S9S_MB_2U(SCH_1):PAGE279_I29@PURE_QUANTA.ISL99390FRZTR5935(CHIPS)':
 'GL2': CDS_PINID='GL2';
NODE_NAME     PU70_P0_2 31
 '@S9S_MB_2U_LIB.S9S_MB_2U(SCH_1):PAGE257_I16@PURE_QUANTA.ISL99390FRZTR5935(CHIPS)':
 'DNC': CDS_PINID='DNC';
NODE_NAME     PU70_P0_2 6
 '@S9S_MB_2U_LIB.S9S_MB_2U(SCH_1):PAGE257_I16@PURE_QUANTA.ISL99390FRZTR5935(CHIPS)':
 'GL1': CDS_PINID='GL1';
NODE_NAME     PU70_P0_2 41
 '@S9S_MB_2U_LIB.S9S_MB_2U(SCH_1):PAGE257_I16@PURE_QUANTA.ISL99390FRZTR5935(CHIPS)':
 'GL2': CDS_PINID='GL2';
NODE_NAME     PU43_P0_1 31
 '@S9S_MB_2U_LIB.S9S_MB_2U(SCH_1):PAGE261_I79@PURE_QUANTA.ISL99390FRZTR5935(CHIPS)':
 'DNC': CDS_PINID='DNC';
NODE_NAME     PU43_P0_1 6
 '@S9S_MB_2U_LIB.S9S_MB_2U(SCH_1):PAGE261_I79@PURE_QUANTA.ISL99390FRZTR5935(CHIPS)':
 'GL1': CDS_PINID='GL1';
NODE_NAME     PU43_P0_1 41
 '@S9S_MB_2U_LIB.S9S_MB_2U(SCH_1):PAGE261_I79@PURE_QUANTA.ISL99390FRZTR5935(CHIPS)':
 'GL2': CDS_PINID='GL2';
NODE_NAME     PU31_P1_1 31
 '@S9S_MB_2U_LIB.S9S_MB_2U(SCH_1):PAGE271_I40@PURE_QUANTA.ISL99390FRZTR5935(CHIPS)':
 'DNC': CDS_PINID='DNC';
NODE_NAME     PU31_P1_1 6
 '@S9S_MB_2U_LIB.S9S_MB_2U(SCH_1):PAGE271_I40@PURE_QUANTA.ISL99390FRZTR5935(CHIPS)':
 'GL1': CDS_PINID='GL1';
NODE_NAME     PU31_P1_1 41
 '@S9S_MB_2U_LIB.S9S_MB_2U(SCH_1):PAGE271_I40@PURE_QUANTA.ISL99390FRZTR5935(CHIPS)':
 'GL2': CDS_PINID='GL2';
NODE_NAME     U308 3
 '@S9S_MB_2U_LIB.S9S_MB_2U(SCH_1):PAGE230_I37@PURE_QUANTA.74LVC2G07DW7(CHIPS)':
 '2A': CDS_PINID='\2a\';
NODE_NAME     U308 4
 '@S9S_MB_2U_LIB.S9S_MB_2U(SCH_1):PAGE230_I37@PURE_QUANTA.74LVC2G07DW7(CHIPS)':
 '2Y': CDS_PINID='\2y\';
NODE_NAME     PU17 31
 '@S9S_MB_2U_LIB.S9S_MB_2U(SCH_1):PAGE283_I10@PURE_QUANTA.ISL99390FRZTR5935(CHIPS)':
 'DNC': CDS_PINID='DNC';
NODE_NAME     PU17 6
 '@S9S_MB_2U_LIB.S9S_MB_2U(SCH_1):PAGE283_I10@PURE_QUANTA.ISL99390FRZTR5935(CHIPS)':
 'GL1': CDS_PINID='GL1';
NODE_NAME     PU17 41
 '@S9S_MB_2U_LIB.S9S_MB_2U(SCH_1):PAGE283_I10@PURE_QUANTA.ISL99390FRZTR5935(CHIPS)':
 'GL2': CDS_PINID='GL2';
NODE_NAME     H120 1
 '@S9S_MB_2U_LIB.S9S_MB_2U(SCH_1):PAGE289_I224@PURE_QUANTA.HOLE(CHIPS)':
 '1': CDS_PINID='\1\';
NODE_NAME     H122 1
 '@S9S_MB_2U_LIB.S9S_MB_2U(SCH_1):PAGE289_I225@PURE_QUANTA.HOLE(CHIPS)':
 '1': CDS_PINID='\1\';
NODE_NAME     H124 1
 '@S9S_MB_2U_LIB.S9S_MB_2U(SCH_1):PAGE289_I226@PURE_QUANTA.HOLE(CHIPS)':
 '1': CDS_PINID='\1\';
NODE_NAME     H126 1
 '@S9S_MB_2U_LIB.S9S_MB_2U(SCH_1):PAGE289_I227@PURE_QUANTA.HOLE(CHIPS)':
 '1': CDS_PINID='\1\';
NODE_NAME     H127 1
 '@S9S_MB_2U_LIB.S9S_MB_2U(SCH_1):PAGE289_I228@PURE_QUANTA.HOLE(CHIPS)':
 '1': CDS_PINID='\1\';
NODE_NAME     H125 1
 '@S9S_MB_2U_LIB.S9S_MB_2U(SCH_1):PAGE289_I229@PURE_QUANTA.HOLE(CHIPS)':
 '1': CDS_PINID='\1\';
NODE_NAME     J90_CON 1
 '@S9S_MB_2U_LIB.S9S_MB_2U(SCH_1):PAGE290_I69@PURE_QUANTA.TP(CHIPS)':
 'TP': CDS_PINID='TP';
NODE_NAME     JP4003_12 1
 '@S9S_MB_2U_LIB.S9S_MB_2U(SCH_1):PAGE290_I70@PURE_QUANTA.TP(CHIPS)':
 'TP': CDS_PINID='TP';
NODE_NAME     J122 SCR_H1
 '@S9S_MB_2U_LIB.S9S_MB_2U(SCH_1):PAGE289_I238@PURE_QUANTA.CONN1_10165288101LF(CHIPS)':
 'NC1': CDS_PINID='NC1';
NODE_NAME     J123 SCR_H1
 '@S9S_MB_2U_LIB.S9S_MB_2U(SCH_1):PAGE289_I239@PURE_QUANTA.CONN1_10165288101LF(CHIPS)':
 'NC1': CDS_PINID='NC1';
NODE_NAME     PU71_P0_3 31
 '@S9S_MB_2U_LIB.S9S_MB_2U(SCH_1):PAGE258_I82@PURE_QUANTA.ISL99390FRZTR5935(CHIPS)':
 'DNC': CDS_PINID='DNC';
NODE_NAME     PU71_P0_3 6
 '@S9S_MB_2U_LIB.S9S_MB_2U(SCH_1):PAGE258_I82@PURE_QUANTA.ISL99390FRZTR5935(CHIPS)':
 'GL1': CDS_PINID='GL1';
NODE_NAME     PU71_P0_3 41
 '@S9S_MB_2U_LIB.S9S_MB_2U(SCH_1):PAGE258_I82@PURE_QUANTA.ISL99390FRZTR5935(CHIPS)':
 'GL2': CDS_PINID='GL2';
NODE_NAME     PU77_P1_3 31
 '@S9S_MB_2U_LIB.S9S_MB_2U(SCH_1):PAGE276_I24@PURE_QUANTA.ISL99390FRZTR5935(CHIPS)':
 'DNC': CDS_PINID='DNC';
NODE_NAME     PU77_P1_3 6
 '@S9S_MB_2U_LIB.S9S_MB_2U(SCH_1):PAGE276_I24@PURE_QUANTA.ISL99390FRZTR5935(CHIPS)':
 'GL1': CDS_PINID='GL1';
NODE_NAME     PU77_P1_3 41
 '@S9S_MB_2U_LIB.S9S_MB_2U(SCH_1):PAGE276_I24@PURE_QUANTA.ISL99390FRZTR5935(CHIPS)':
 'GL2': CDS_PINID='GL2';
NODE_NAME     U39 16
 '@S9S_MB_2U_LIB.S9S_MB_2U(SCH_1):PAGE221_I103@PURE_QUANTA.TCA9548APWR(CHIPS)':
 'SC5': CDS_PINID='SC5';
NODE_NAME     U39 18
 '@S9S_MB_2U_LIB.S9S_MB_2U(SCH_1):PAGE221_I103@PURE_QUANTA.TCA9548APWR(CHIPS)':
 'SC6': CDS_PINID='SC6';
NODE_NAME     U39 20
 '@S9S_MB_2U_LIB.S9S_MB_2U(SCH_1):PAGE221_I103@PURE_QUANTA.TCA9548APWR(CHIPS)':
 'SC7': CDS_PINID='SC7';
NODE_NAME     U39 15
 '@S9S_MB_2U_LIB.S9S_MB_2U(SCH_1):PAGE221_I103@PURE_QUANTA.TCA9548APWR(CHIPS)':
 'SD5': CDS_PINID='SD5';
NODE_NAME     U39 17
 '@S9S_MB_2U_LIB.S9S_MB_2U(SCH_1):PAGE221_I103@PURE_QUANTA.TCA9548APWR(CHIPS)':
 'SD6': CDS_PINID='SD6';
NODE_NAME     U39 19
 '@S9S_MB_2U_LIB.S9S_MB_2U(SCH_1):PAGE221_I103@PURE_QUANTA.TCA9548APWR(CHIPS)':
 'SD7': CDS_PINID='SD7';
NODE_NAME     JP15_23 1
 '@S9S_MB_2U_LIB.S9S_MB_2U(SCH_1):PAGE290_I71@PURE_QUANTA.TP(CHIPS)':
 'TP': CDS_PINID='TP';
NODE_NAME     PU75_P1_1 31
 '@S9S_MB_2U_LIB.S9S_MB_2U(SCH_1):PAGE275_I89@PURE_QUANTA.ISL99390FRZTR5935(CHIPS)':
 'DNC': CDS_PINID='DNC';
NODE_NAME     PU75_P1_1 6
 '@S9S_MB_2U_LIB.S9S_MB_2U(SCH_1):PAGE275_I89@PURE_QUANTA.ISL99390FRZTR5935(CHIPS)':
 'GL1': CDS_PINID='GL1';
NODE_NAME     PU75_P1_1 41
 '@S9S_MB_2U_LIB.S9S_MB_2U(SCH_1):PAGE275_I89@PURE_QUANTA.ISL99390FRZTR5935(CHIPS)':
 'GL2': CDS_PINID='GL2';
NODE_NAME     PU42 27
 '@S9S_MB_2U_LIB.S9S_MB_2U(SCH_1):PAGE262_I14@PURE_QUANTA.RAA2213404GNPHB0(CHIPS)':
 'GL2': CDS_PINID='GL2';
NODE_NAME     PU12_P0_2 31
 '@S9S_MB_2U_LIB.S9S_MB_2U(SCH_1):PAGE253_I6@PURE_QUANTA.ISL99390FRZTR5935(CHIPS)':
 'DNC': CDS_PINID='DNC';
NODE_NAME     PU12_P0_2 6
 '@S9S_MB_2U_LIB.S9S_MB_2U(SCH_1):PAGE253_I6@PURE_QUANTA.ISL99390FRZTR5935(CHIPS)':
 'GL1': CDS_PINID='GL1';
NODE_NAME     PU12_P0_2 41
 '@S9S_MB_2U_LIB.S9S_MB_2U(SCH_1):PAGE253_I6@PURE_QUANTA.ISL99390FRZTR5935(CHIPS)':
 'GL2': CDS_PINID='GL2';
NODE_NAME     PU69_P0_1 31
 '@S9S_MB_2U_LIB.S9S_MB_2U(SCH_1):PAGE257_I25@PURE_QUANTA.ISL99390FRZTR5935(CHIPS)':
 'DNC': CDS_PINID='DNC';
NODE_NAME     PU69_P0_1 6
 '@S9S_MB_2U_LIB.S9S_MB_2U(SCH_1):PAGE257_I25@PURE_QUANTA.ISL99390FRZTR5935(CHIPS)':
 'GL1': CDS_PINID='GL1';
NODE_NAME     PU69_P0_1 41
 '@S9S_MB_2U_LIB.S9S_MB_2U(SCH_1):PAGE257_I25@PURE_QUANTA.ISL99390FRZTR5935(CHIPS)':
 'GL2': CDS_PINID='GL2';
NODE_NAME     PU72_P0_4 31
 '@S9S_MB_2U_LIB.S9S_MB_2U(SCH_1):PAGE258_I10@PURE_QUANTA.ISL99390FRZTR5935(CHIPS)':
 'DNC': CDS_PINID='DNC';
NODE_NAME     PU72_P0_4 6
 '@S9S_MB_2U_LIB.S9S_MB_2U(SCH_1):PAGE258_I10@PURE_QUANTA.ISL99390FRZTR5935(CHIPS)':
 'GL1': CDS_PINID='GL1';
NODE_NAME     PU72_P0_4 41
 '@S9S_MB_2U_LIB.S9S_MB_2U(SCH_1):PAGE258_I10@PURE_QUANTA.ISL99390FRZTR5935(CHIPS)':
 'GL2': CDS_PINID='GL2';
NODE_NAME     PU30_P1_2 31
 '@S9S_MB_2U_LIB.S9S_MB_2U(SCH_1):PAGE271_I7@PURE_QUANTA.ISL99390FRZTR5935(CHIPS)':
 'DNC': CDS_PINID='DNC';
NODE_NAME     PU30_P1_2 6
 '@S9S_MB_2U_LIB.S9S_MB_2U(SCH_1):PAGE271_I7@PURE_QUANTA.ISL99390FRZTR5935(CHIPS)':
 'GL1': CDS_PINID='GL1';
NODE_NAME     PU30_P1_2 41
 '@S9S_MB_2U_LIB.S9S_MB_2U(SCH_1):PAGE271_I7@PURE_QUANTA.ISL99390FRZTR5935(CHIPS)':
 'GL2': CDS_PINID='GL2';
NODE_NAME     JP16_23 1
 '@S9S_MB_2U_LIB.S9S_MB_2U(SCH_1):PAGE290_I72@PURE_QUANTA.TP(CHIPS)':
 'TP': CDS_PINID='TP';
NODE_NAME     JP4003 1
 '@S9S_MB_2U_LIB.S9S_MB_2U(SCH_1):PAGE303_I12@PURE_QUANTA.CONN3_210HP1030BR1(CHIPS)':
 '1': CDS_PINID='\1\';
NODE_NAME     U337 3
 '@S9S_MB_2U_LIB.S9S_MB_2U(SCH_1):PAGE329_I3@PURE_QUANTA.LM4040AIM3X25NOPB(CHIPS)':
 '3': CDS_PINID='\3\';
NODE_NAME     U338 3
 '@S9S_MB_2U_LIB.S9S_MB_2U(SCH_1):PAGE329_I43@PURE_QUANTA.LM4040AIM3X25NOPB(CHIPS)':
 '3': CDS_PINID='\3\';
NODE_NAME     U341 3
 '@S9S_MB_2U_LIB.S9S_MB_2U(SCH_1):PAGE329_I63@PURE_QUANTA.LM4040AIM3X25NOPB(CHIPS)':
 '3': CDS_PINID='\3\';
NODE_NAME     U343 3
 '@S9S_MB_2U_LIB.S9S_MB_2U(SCH_1):PAGE326_I56@PURE_QUANTA.LM4040AIM3X25NOPB(CHIPS)':
 '3': CDS_PINID='\3\';
NODE_NAME     H90 1
 '@S9S_MB_2U_LIB.S9S_MB_2U(SCH_1):PAGE289_I254@PURE_QUANTA.HOLE(CHIPS)':
 '1': CDS_PINID='\1\';
NODE_NAME     U95 1
 '@S9S_MB_2U_LIB.S9S_MB_2U(SCH_1):PAGE232_I11@PURE_QUANTA.74LVC1G07SE7(CHIPS)':
 'NC1': CDS_PINID='NC1';
NODE_NAME     U192 5
 '@S9S_MB_2U_LIB.S9S_MB_2U(SCH_1):PAGE233_I16@PURE_QUANTA.LTC4307CMS8(CHIPS)':
 'READY': CDS_PINID='READY';
NODE_NAME     U200 5
 '@S9S_MB_2U_LIB.S9S_MB_2U(SCH_1):PAGE222_I11@PURE_QUANTA.LTC4307CMS8(CHIPS)':
 'READY': CDS_PINID='READY';
NODE_NAME     U176 5
 '@S9S_MB_2U_LIB.S9S_MB_2U(SCH_1):PAGE222_I31@PURE_QUANTA.LTC4307CMS8(CHIPS)':
 'READY': CDS_PINID='READY';
NODE_NAME     U175 5
 '@S9S_MB_2U_LIB.S9S_MB_2U(SCH_1):PAGE222_I50@PURE_QUANTA.LTC4307CMS8(CHIPS)':
 'READY': CDS_PINID='READY';
NODE_NAME     U194 5
 '@S9S_MB_2U_LIB.S9S_MB_2U(SCH_1):PAGE222_I63@PURE_QUANTA.LTC4307CMS8(CHIPS)':
 'READY': CDS_PINID='READY';
NODE_NAME     U36 5
 '@S9S_MB_2U_LIB.S9S_MB_2U(SCH_1):PAGE219_I45@PURE_QUANTA.TCA9548APWR(CHIPS)':
 'SC0': CDS_PINID='SC0';
NODE_NAME     U36 20
 '@S9S_MB_2U_LIB.S9S_MB_2U(SCH_1):PAGE219_I45@PURE_QUANTA.TCA9548APWR(CHIPS)':
 'SC7': CDS_PINID='SC7';
NODE_NAME     U36 4
 '@S9S_MB_2U_LIB.S9S_MB_2U(SCH_1):PAGE219_I45@PURE_QUANTA.TCA9548APWR(CHIPS)':
 'SD0': CDS_PINID='SD0';
NODE_NAME     U36 19
 '@S9S_MB_2U_LIB.S9S_MB_2U(SCH_1):PAGE219_I45@PURE_QUANTA.TCA9548APWR(CHIPS)':
 'SD7': CDS_PINID='SD7';
NET_NAME
'NCSI_BMC_CRS_DV_R'
 '@S9S_MB_2U_LIB.S9S_MB_2U(SCH_1):NCSI_BMC_CRS_DV_R':
 C_SIGNAL='@s9s_mb_2u_lib.s9s_mb_2u(sch_1):ncsi_bmc_crs_dv_r';
NODE_NAME     U67 9
 '@S9S_MB_2U_LIB.S9S_MB_2U(SCH_1):PAGE151_I39@PURE_QUANTA.74CBTLV3126PW(CHIPS)':
 '3A': CDS_PINID='\3a\';
NODE_NAME     R1291 1
 '@S9S_MB_2U_LIB.S9S_MB_2U(SCH_1):PAGE151_I69@PURE_QUANTA.Q_RES(CHIPS)':
 'A': CDS_PINID='A';
NET_NAME
'NCSI_BMC_CRS_DV_R1'
 '@S9S_MB_2U_LIB.S9S_MB_2U(SCH_1):NCSI_BMC_CRS_DV_R1':
 C_SIGNAL='@s9s_mb_2u_lib.s9s_mb_2u(sch_1):ncsi_bmc_crs_dv_r1';
NODE_NAME     U222 9
 '@S9S_MB_2U_LIB.S9S_MB_2U(SCH_1):PAGE307_I32@PURE_QUANTA.74CBTLV3126PW(CHIPS)':
 '3A': CDS_PINID='\3a\';
NODE_NAME     R3210 1
 '@S9S_MB_2U_LIB.S9S_MB_2U(SCH_1):PAGE307_I65@PURE_QUANTA.Q_RES(CHIPS)':
 'A': CDS_PINID='A';
NET_NAME
'NCSI_BMC_RXD0_R'
 '@S9S_MB_2U_LIB.S9S_MB_2U(SCH_1):NCSI_BMC_RXD0_R':
 C_SIGNAL='@s9s_mb_2u_lib.s9s_mb_2u(sch_1):ncsi_bmc_rxd0_r';
NODE_NAME     U67 5
 '@S9S_MB_2U_LIB.S9S_MB_2U(SCH_1):PAGE151_I39@PURE_QUANTA.74CBTLV3126PW(CHIPS)':
 '2A': CDS_PINID='\2a\';
NODE_NAME     R1292 1
 '@S9S_MB_2U_LIB.S9S_MB_2U(SCH_1):PAGE151_I68@PURE_QUANTA.Q_RES(CHIPS)':
 'A': CDS_PINID='A';
NET_NAME
'NCSI_BMC_RXD0_R1'
 '@S9S_MB_2U_LIB.S9S_MB_2U(SCH_1):NCSI_BMC_RXD0_R1':
 C_SIGNAL='@s9s_mb_2u_lib.s9s_mb_2u(sch_1):ncsi_bmc_rxd0_r1';
NODE_NAME     U222 5
 '@S9S_MB_2U_LIB.S9S_MB_2U(SCH_1):PAGE307_I32@PURE_QUANTA.74CBTLV3126PW(CHIPS)':
 '2A': CDS_PINID='\2a\';
NODE_NAME     R3211 1
 '@S9S_MB_2U_LIB.S9S_MB_2U(SCH_1):PAGE307_I63@PURE_QUANTA.Q_RES(CHIPS)':
 'A': CDS_PINID='A';
NET_NAME
'NCSI_BMC_RXD1_R'
 '@S9S_MB_2U_LIB.S9S_MB_2U(SCH_1):NCSI_BMC_RXD1_R':
 C_SIGNAL='@s9s_mb_2u_lib.s9s_mb_2u(sch_1):ncsi_bmc_rxd1_r';
NODE_NAME     U67 2
 '@S9S_MB_2U_LIB.S9S_MB_2U(SCH_1):PAGE151_I39@PURE_QUANTA.74CBTLV3126PW(CHIPS)':
 '1A': CDS_PINID='\1a\';
NODE_NAME     R1293 1
 '@S9S_MB_2U_LIB.S9S_MB_2U(SCH_1):PAGE151_I67@PURE_QUANTA.Q_RES(CHIPS)':
 'A': CDS_PINID='A';
NET_NAME
'NCSI_BMC_RXD1_R1'
 '@S9S_MB_2U_LIB.S9S_MB_2U(SCH_1):NCSI_BMC_RXD1_R1':
 C_SIGNAL='@s9s_mb_2u_lib.s9s_mb_2u(sch_1):ncsi_bmc_rxd1_r1';
NODE_NAME     U222 2
 '@S9S_MB_2U_LIB.S9S_MB_2U(SCH_1):PAGE307_I32@PURE_QUANTA.74CBTLV3126PW(CHIPS)':
 '1A': CDS_PINID='\1a\';
NODE_NAME     R3212 1
 '@S9S_MB_2U_LIB.S9S_MB_2U(SCH_1):PAGE307_I62@PURE_QUANTA.Q_RES(CHIPS)':
 'A': CDS_PINID='A';
NET_NAME
'NCSI_BMC_TXD0_R'
 '@S9S_MB_2U_LIB.S9S_MB_2U(SCH_1):NCSI_BMC_TXD0_R':
 C_SIGNAL='@s9s_mb_2u_lib.s9s_mb_2u(sch_1):ncsi_bmc_txd0_r';
NODE_NAME     U68 5
 '@S9S_MB_2U_LIB.S9S_MB_2U(SCH_1):PAGE151_I30@PURE_QUANTA.74CBTLV3126PW(CHIPS)':
 '2A': CDS_PINID='\2a\';
NODE_NAME     R1295 1
 '@S9S_MB_2U_LIB.S9S_MB_2U(SCH_1):PAGE151_I65@PURE_QUANTA.Q_RES(CHIPS)':
 'A': CDS_PINID='A';
NET_NAME
'NCSI_BMC_TXD0_R1'
 '@S9S_MB_2U_LIB.S9S_MB_2U(SCH_1):NCSI_BMC_TXD0_R1':
 C_SIGNAL='@s9s_mb_2u_lib.s9s_mb_2u(sch_1):ncsi_bmc_txd0_r1';
NODE_NAME     R3214 1
 '@S9S_MB_2U_LIB.S9S_MB_2U(SCH_1):PAGE307_I60@PURE_QUANTA.Q_RES(CHIPS)':
 'A': CDS_PINID='A';
NODE_NAME     U223 5
 '@S9S_MB_2U_LIB.S9S_MB_2U(SCH_1):PAGE307_I78@PURE_QUANTA.74CBTLV3126PW(CHIPS)':
 '2A': CDS_PINID='\2a\';
NET_NAME
'NCSI_BMC_TXD1_R'
 '@S9S_MB_2U_LIB.S9S_MB_2U(SCH_1):NCSI_BMC_TXD1_R':
 C_SIGNAL='@s9s_mb_2u_lib.s9s_mb_2u(sch_1):ncsi_bmc_txd1_r';
NODE_NAME     U68 2
 '@S9S_MB_2U_LIB.S9S_MB_2U(SCH_1):PAGE151_I30@PURE_QUANTA.74CBTLV3126PW(CHIPS)':
 '1A': CDS_PINID='\1a\';
NODE_NAME     R1296 1
 '@S9S_MB_2U_LIB.S9S_MB_2U(SCH_1):PAGE151_I61@PURE_QUANTA.Q_RES(CHIPS)':
 'A': CDS_PINID='A';
NET_NAME
'NCSI_BMC_TXD1_R1'
 '@S9S_MB_2U_LIB.S9S_MB_2U(SCH_1):NCSI_BMC_TXD1_R1':
 C_SIGNAL='@s9s_mb_2u_lib.s9s_mb_2u(sch_1):ncsi_bmc_txd1_r1';
NODE_NAME     R3215 1
 '@S9S_MB_2U_LIB.S9S_MB_2U(SCH_1):PAGE307_I56@PURE_QUANTA.Q_RES(CHIPS)':
 'A': CDS_PINID='A';
NODE_NAME     U223 2
 '@S9S_MB_2U_LIB.S9S_MB_2U(SCH_1):PAGE307_I78@PURE_QUANTA.74CBTLV3126PW(CHIPS)':
 '1A': CDS_PINID='\1a\';
NET_NAME
'NCSI_BMC_TX_EN_R'
 '@S9S_MB_2U_LIB.S9S_MB_2U(SCH_1):NCSI_BMC_TX_EN_R':
 C_SIGNAL='@s9s_mb_2u_lib.s9s_mb_2u(sch_1):ncsi_bmc_tx_en_r';
NODE_NAME     U68 9
 '@S9S_MB_2U_LIB.S9S_MB_2U(SCH_1):PAGE151_I30@PURE_QUANTA.74CBTLV3126PW(CHIPS)':
 '3A': CDS_PINID='\3a\';
NODE_NAME     R1294 1
 '@S9S_MB_2U_LIB.S9S_MB_2U(SCH_1):PAGE151_I66@PURE_QUANTA.Q_RES(CHIPS)':
 'A': CDS_PINID='A';
NET_NAME
'NCSI_BMC_TX_EN_R1'
 '@S9S_MB_2U_LIB.S9S_MB_2U(SCH_1):NCSI_BMC_TX_EN_R1':
 C_SIGNAL='@s9s_mb_2u_lib.s9s_mb_2u(sch_1):ncsi_bmc_tx_en_r1';
NODE_NAME     R3213 1
 '@S9S_MB_2U_LIB.S9S_MB_2U(SCH_1):PAGE307_I61@PURE_QUANTA.Q_RES(CHIPS)':
 'A': CDS_PINID='A';
NODE_NAME     U223 9
 '@S9S_MB_2U_LIB.S9S_MB_2U(SCH_1):PAGE307_I78@PURE_QUANTA.74CBTLV3126PW(CHIPS)':
 '3A': CDS_PINID='\3a\';
NET_NAME
'NCSI_OCP_SFF_CRS_DV'
 '@S9S_MB_2U_LIB.S9S_MB_2U(SCH_1):NCSI_OCP_SFF_CRS_DV':
 C_SIGNAL='@s9s_mb_2u_lib.s9s_mb_2u(sch_1):ncsi_ocp_sff_crs_dv';
NODE_NAME     J37 OB14
 '@S9S_MB_2U_LIB.S9S_MB_2U(SCH_1):PAGE150_I199@PURE_QUANTA.SCONN168_ME1016810202011(CHIPS)':
 'RBT_CRS_DV': CDS_PINID='RBT_CRS_DV';
NODE_NAME     U67 8
 '@S9S_MB_2U_LIB.S9S_MB_2U(SCH_1):PAGE151_I39@PURE_QUANTA.74CBTLV3126PW(CHIPS)':
 '3B': CDS_PINID='\3b\';
NET_NAME
'NCSI_OCP_SFF_RXD0'
 '@S9S_MB_2U_LIB.S9S_MB_2U(SCH_1):NCSI_OCP_SFF_RXD0':
 C_SIGNAL='@s9s_mb_2u_lib.s9s_mb_2u(sch_1):ncsi_ocp_sff_rxd0';
NODE_NAME     J37 OB9
 '@S9S_MB_2U_LIB.S9S_MB_2U(SCH_1):PAGE150_I199@PURE_QUANTA.SCONN168_ME1016810202011(CHIPS)':
 'RBT_RXD0': CDS_PINID='RBT_RXD0';
NODE_NAME     U67 6
 '@S9S_MB_2U_LIB.S9S_MB_2U(SCH_1):PAGE151_I39@PURE_QUANTA.74CBTLV3126PW(CHIPS)':
 '2B': CDS_PINID='\2b\';
NET_NAME
'NCSI_OCP_SFF_RXD1'
 '@S9S_MB_2U_LIB.S9S_MB_2U(SCH_1):NCSI_OCP_SFF_RXD1':
 C_SIGNAL='@s9s_mb_2u_lib.s9s_mb_2u(sch_1):ncsi_ocp_sff_rxd1';
NODE_NAME     J37 OB8
 '@S9S_MB_2U_LIB.S9S_MB_2U(SCH_1):PAGE150_I199@PURE_QUANTA.SCONN168_ME1016810202011(CHIPS)':
 'RBT_RXD1': CDS_PINID='RBT_RXD1';
NODE_NAME     U67 3
 '@S9S_MB_2U_LIB.S9S_MB_2U(SCH_1):PAGE151_I39@PURE_QUANTA.74CBTLV3126PW(CHIPS)':
 '1B': CDS_PINID='\1b\';
NET_NAME
'NCSI_OCP_SFF_TXD0'
 '@S9S_MB_2U_LIB.S9S_MB_2U(SCH_1):NCSI_OCP_SFF_TXD0':
 C_SIGNAL='@s9s_mb_2u_lib.s9s_mb_2u(sch_1):ncsi_ocp_sff_txd0';
NODE_NAME     J37 OA9
 '@S9S_MB_2U_LIB.S9S_MB_2U(SCH_1):PAGE150_I199@PURE_QUANTA.SCONN168_ME1016810202011(CHIPS)':
 'RBT_TXD0': CDS_PINID='RBT_TXD0';
NODE_NAME     U68 6
 '@S9S_MB_2U_LIB.S9S_MB_2U(SCH_1):PAGE151_I30@PURE_QUANTA.74CBTLV3126PW(CHIPS)':
 '2B': CDS_PINID='\2b\';
NET_NAME
'NCSI_OCP_SFF_TXD1'
 '@S9S_MB_2U_LIB.S9S_MB_2U(SCH_1):NCSI_OCP_SFF_TXD1':
 C_SIGNAL='@s9s_mb_2u_lib.s9s_mb_2u(sch_1):ncsi_ocp_sff_txd1';
NODE_NAME     J37 OA8
 '@S9S_MB_2U_LIB.S9S_MB_2U(SCH_1):PAGE150_I199@PURE_QUANTA.SCONN168_ME1016810202011(CHIPS)':
 'RBT_TXD1': CDS_PINID='RBT_TXD1';
NODE_NAME     U68 3
 '@S9S_MB_2U_LIB.S9S_MB_2U(SCH_1):PAGE151_I30@PURE_QUANTA.74CBTLV3126PW(CHIPS)':
 '1B': CDS_PINID='\1b\';
NET_NAME
'NCSI_OCP_SFF_TX_EN'
 '@S9S_MB_2U_LIB.S9S_MB_2U(SCH_1):NCSI_OCP_SFF_TX_EN':
 C_SIGNAL='@s9s_mb_2u_lib.s9s_mb_2u(sch_1):ncsi_ocp_sff_tx_en';
NODE_NAME     J37 OA7
 '@S9S_MB_2U_LIB.S9S_MB_2U(SCH_1):PAGE150_I199@PURE_QUANTA.SCONN168_ME1016810202011(CHIPS)':
 'RBT_TX_EN': CDS_PINID='RBT_TX_EN';
NODE_NAME     U68 8
 '@S9S_MB_2U_LIB.S9S_MB_2U(SCH_1):PAGE151_I30@PURE_QUANTA.74CBTLV3126PW(CHIPS)':
 '3B': CDS_PINID='\3b\';
NET_NAME
'NCSI_OCP_V3_2_CRS_DV'
 '@S9S_MB_2U_LIB.S9S_MB_2U(SCH_1):NCSI_OCP_V3_2_CRS_DV':
 C_SIGNAL='@s9s_mb_2u_lib.s9s_mb_2u(sch_1):ncsi_ocp_v3_2_crs_dv';
NODE_NAME     U222 8
 '@S9S_MB_2U_LIB.S9S_MB_2U(SCH_1):PAGE307_I32@PURE_QUANTA.74CBTLV3126PW(CHIPS)':
 '3B': CDS_PINID='\3b\';
NODE_NAME     J35 OB14
 '@S9S_MB_2U_LIB.S9S_MB_2U(SCH_1):PAGE146_I303@PURE_QUANTA.SCONN168_ME1016810202011(CHIPS)':
 'RBT_CRS_DV': CDS_PINID='RBT_CRS_DV';
NET_NAME
'NCSI_OCP_V3_2_RXD0'
 '@S9S_MB_2U_LIB.S9S_MB_2U(SCH_1):NCSI_OCP_V3_2_RXD0':
 C_SIGNAL='@s9s_mb_2u_lib.s9s_mb_2u(sch_1):ncsi_ocp_v3_2_rxd0';
NODE_NAME     U222 6
 '@S9S_MB_2U_LIB.S9S_MB_2U(SCH_1):PAGE307_I32@PURE_QUANTA.74CBTLV3126PW(CHIPS)':
 '2B': CDS_PINID='\2b\';
NODE_NAME     J35 OB9
 '@S9S_MB_2U_LIB.S9S_MB_2U(SCH_1):PAGE146_I303@PURE_QUANTA.SCONN168_ME1016810202011(CHIPS)':
 'RBT_RXD0': CDS_PINID='RBT_RXD0';
NET_NAME
'NCSI_OCP_V3_2_RXD1'
 '@S9S_MB_2U_LIB.S9S_MB_2U(SCH_1):NCSI_OCP_V3_2_RXD1':
 C_SIGNAL='@s9s_mb_2u_lib.s9s_mb_2u(sch_1):ncsi_ocp_v3_2_rxd1';
NODE_NAME     U222 3
 '@S9S_MB_2U_LIB.S9S_MB_2U(SCH_1):PAGE307_I32@PURE_QUANTA.74CBTLV3126PW(CHIPS)':
 '1B': CDS_PINID='\1b\';
NODE_NAME     J35 OB8
 '@S9S_MB_2U_LIB.S9S_MB_2U(SCH_1):PAGE146_I303@PURE_QUANTA.SCONN168_ME1016810202011(CHIPS)':
 'RBT_RXD1': CDS_PINID='RBT_RXD1';
NET_NAME
'NCSI_OCP_V3_2_TXD0'
 '@S9S_MB_2U_LIB.S9S_MB_2U(SCH_1):NCSI_OCP_V3_2_TXD0':
 C_SIGNAL='@s9s_mb_2u_lib.s9s_mb_2u(sch_1):ncsi_ocp_v3_2_txd0';
NODE_NAME     U223 6
 '@S9S_MB_2U_LIB.S9S_MB_2U(SCH_1):PAGE307_I78@PURE_QUANTA.74CBTLV3126PW(CHIPS)':
 '2B': CDS_PINID='\2b\';
NODE_NAME     J35 OA9
 '@S9S_MB_2U_LIB.S9S_MB_2U(SCH_1):PAGE146_I303@PURE_QUANTA.SCONN168_ME1016810202011(CHIPS)':
 'RBT_TXD0': CDS_PINID='RBT_TXD0';
NET_NAME
'NCSI_OCP_V3_2_TXD1'
 '@S9S_MB_2U_LIB.S9S_MB_2U(SCH_1):NCSI_OCP_V3_2_TXD1':
 C_SIGNAL='@s9s_mb_2u_lib.s9s_mb_2u(sch_1):ncsi_ocp_v3_2_txd1';
NODE_NAME     U223 3
 '@S9S_MB_2U_LIB.S9S_MB_2U(SCH_1):PAGE307_I78@PURE_QUANTA.74CBTLV3126PW(CHIPS)':
 '1B': CDS_PINID='\1b\';
NODE_NAME     J35 OA8
 '@S9S_MB_2U_LIB.S9S_MB_2U(SCH_1):PAGE146_I303@PURE_QUANTA.SCONN168_ME1016810202011(CHIPS)':
 'RBT_TXD1': CDS_PINID='RBT_TXD1';
NET_NAME
'NCSI_OCP_V3_2_TX_EN'
 '@S9S_MB_2U_LIB.S9S_MB_2U(SCH_1):NCSI_OCP_V3_2_TX_EN':
 C_SIGNAL='@s9s_mb_2u_lib.s9s_mb_2u(sch_1):ncsi_ocp_v3_2_tx_en';
NODE_NAME     U223 8
 '@S9S_MB_2U_LIB.S9S_MB_2U(SCH_1):PAGE307_I78@PURE_QUANTA.74CBTLV3126PW(CHIPS)':
 '3B': CDS_PINID='\3b\';
NODE_NAME     J35 OA7
 '@S9S_MB_2U_LIB.S9S_MB_2U(SCH_1):PAGE146_I303@PURE_QUANTA.SCONN168_ME1016810202011(CHIPS)':
 'RBT_TX_EN': CDS_PINID='RBT_TX_EN';
NET_NAME
'NC_CK440_A15'
 '@S9S_MB_2U_LIB.S9S_MB_2U(SCH_1):NC_CK440_A15':
 C_SIGNAL='@s9s_mb_2u_lib.s9s_mb_2u(sch_1):nc_ck440_a15';
NODE_NAME     U13 A15
 '@S9S_MB_2U_LIB.S9S_MB_2U(SCH_1):PAGE197_I288@PURE_QUANTA.9SQ440NQQI8(CHIPS)':
 'NC_A15': CDS_PINID='NC_A15';
NET_NAME
'NC_CK440_B13'
 '@S9S_MB_2U_LIB.S9S_MB_2U(SCH_1):NC_CK440_B13':
 C_SIGNAL='@s9s_mb_2u_lib.s9s_mb_2u(sch_1):nc_ck440_b13';
NODE_NAME     U13 B13
 '@S9S_MB_2U_LIB.S9S_MB_2U(SCH_1):PAGE197_I288@PURE_QUANTA.9SQ440NQQI8(CHIPS)':
 'NC_B13': CDS_PINID='NC_B13';
NET_NAME
'NC_CK440_B16'
 '@S9S_MB_2U_LIB.S9S_MB_2U(SCH_1):NC_CK440_B16':
 C_SIGNAL='@s9s_mb_2u_lib.s9s_mb_2u(sch_1):nc_ck440_b16';
NODE_NAME     U13 B16
 '@S9S_MB_2U_LIB.S9S_MB_2U(SCH_1):PAGE197_I288@PURE_QUANTA.9SQ440NQQI8(CHIPS)':
 'NC_B16': CDS_PINID='NC_B16';
NET_NAME
'NC_CK440_B18'
 '@S9S_MB_2U_LIB.S9S_MB_2U(SCH_1):NC_CK440_B18':
 C_SIGNAL='@s9s_mb_2u_lib.s9s_mb_2u(sch_1):nc_ck440_b18';
NODE_NAME     U13 B18
 '@S9S_MB_2U_LIB.S9S_MB_2U(SCH_1):PAGE197_I288@PURE_QUANTA.9SQ440NQQI8(CHIPS)':
 'NC_B18': CDS_PINID='NC_B18';
NET_NAME
'NC_CK440_B2'
 '@S9S_MB_2U_LIB.S9S_MB_2U(SCH_1):NC_CK440_B2':
 C_SIGNAL='@s9s_mb_2u_lib.s9s_mb_2u(sch_1):nc_ck440_b2';
NODE_NAME     U13 B2
 '@S9S_MB_2U_LIB.S9S_MB_2U(SCH_1):PAGE197_I288@PURE_QUANTA.9SQ440NQQI8(CHIPS)':
 'NC_B2': CDS_PINID='NC_B2';
NET_NAME
'NC_CK440_B20'
 '@S9S_MB_2U_LIB.S9S_MB_2U(SCH_1):NC_CK440_B20':
 C_SIGNAL='@s9s_mb_2u_lib.s9s_mb_2u(sch_1):nc_ck440_b20';
NODE_NAME     U13 B20
 '@S9S_MB_2U_LIB.S9S_MB_2U(SCH_1):PAGE197_I288@PURE_QUANTA.9SQ440NQQI8(CHIPS)':
 'NC_B20': CDS_PINID='NC_B20';
NET_NAME
'NC_CK440_B22'
 '@S9S_MB_2U_LIB.S9S_MB_2U(SCH_1):NC_CK440_B22':
 C_SIGNAL='@s9s_mb_2u_lib.s9s_mb_2u(sch_1):nc_ck440_b22';
NODE_NAME     U13 B22
 '@S9S_MB_2U_LIB.S9S_MB_2U(SCH_1):PAGE197_I288@PURE_QUANTA.9SQ440NQQI8(CHIPS)':
 'NC_B22': CDS_PINID='NC_B22';
NET_NAME
'NC_CK440_B24'
 '@S9S_MB_2U_LIB.S9S_MB_2U(SCH_1):NC_CK440_B24':
 C_SIGNAL='@s9s_mb_2u_lib.s9s_mb_2u(sch_1):nc_ck440_b24';
NODE_NAME     U13 B24
 '@S9S_MB_2U_LIB.S9S_MB_2U(SCH_1):PAGE197_I288@PURE_QUANTA.9SQ440NQQI8(CHIPS)':
 'NC_B24': CDS_PINID='NC_B24';
NET_NAME
'NC_CK440_B25'
 '@S9S_MB_2U_LIB.S9S_MB_2U(SCH_1):NC_CK440_B25':
 C_SIGNAL='@s9s_mb_2u_lib.s9s_mb_2u(sch_1):nc_ck440_b25';
NODE_NAME     U13 B25
 '@S9S_MB_2U_LIB.S9S_MB_2U(SCH_1):PAGE197_I288@PURE_QUANTA.9SQ440NQQI8(CHIPS)':
 'NC_B25': CDS_PINID='NC_B25';
NET_NAME
'NC_CK440_B26'
 '@S9S_MB_2U_LIB.S9S_MB_2U(SCH_1):NC_CK440_B26':
 C_SIGNAL='@s9s_mb_2u_lib.s9s_mb_2u(sch_1):nc_ck440_b26';
NODE_NAME     U13 B26
 '@S9S_MB_2U_LIB.S9S_MB_2U(SCH_1):PAGE197_I288@PURE_QUANTA.9SQ440NQQI8(CHIPS)':
 'NC_B26': CDS_PINID='NC_B26';
NET_NAME
'NC_CK440_B28'
 '@S9S_MB_2U_LIB.S9S_MB_2U(SCH_1):NC_CK440_B28':
 C_SIGNAL='@s9s_mb_2u_lib.s9s_mb_2u(sch_1):nc_ck440_b28';
NODE_NAME     U13 B28
 '@S9S_MB_2U_LIB.S9S_MB_2U(SCH_1):PAGE197_I288@PURE_QUANTA.9SQ440NQQI8(CHIPS)':
 'NC_B28': CDS_PINID='NC_B28';
NET_NAME
'NC_CK440_B3'
 '@S9S_MB_2U_LIB.S9S_MB_2U(SCH_1):NC_CK440_B3':
 C_SIGNAL='@s9s_mb_2u_lib.s9s_mb_2u(sch_1):nc_ck440_b3';
NODE_NAME     U13 B3
 '@S9S_MB_2U_LIB.S9S_MB_2U(SCH_1):PAGE197_I288@PURE_QUANTA.9SQ440NQQI8(CHIPS)':
 'NC_B3': CDS_PINID='NC_B3';
NET_NAME
'NC_CK440_B30'
 '@S9S_MB_2U_LIB.S9S_MB_2U(SCH_1):NC_CK440_B30':
 C_SIGNAL='@s9s_mb_2u_lib.s9s_mb_2u(sch_1):nc_ck440_b30';
NODE_NAME     U13 B30
 '@S9S_MB_2U_LIB.S9S_MB_2U(SCH_1):PAGE197_I288@PURE_QUANTA.9SQ440NQQI8(CHIPS)':
 'NC_B30': CDS_PINID='NC_B30';
NET_NAME
'NC_CK440_B31'
 '@S9S_MB_2U_LIB.S9S_MB_2U(SCH_1):NC_CK440_B31':
 C_SIGNAL='@s9s_mb_2u_lib.s9s_mb_2u(sch_1):nc_ck440_b31';
NODE_NAME     U13 B31
 '@S9S_MB_2U_LIB.S9S_MB_2U(SCH_1):PAGE197_I288@PURE_QUANTA.9SQ440NQQI8(CHIPS)':
 'NC_B31': CDS_PINID='NC_B31';
NET_NAME
'NC_CK440_B33'
 '@S9S_MB_2U_LIB.S9S_MB_2U(SCH_1):NC_CK440_B33':
 C_SIGNAL='@s9s_mb_2u_lib.s9s_mb_2u(sch_1):nc_ck440_b33';
NODE_NAME     U13 B33
 '@S9S_MB_2U_LIB.S9S_MB_2U(SCH_1):PAGE197_I288@PURE_QUANTA.9SQ440NQQI8(CHIPS)':
 'NC_B33': CDS_PINID='NC_B33';
NET_NAME
'NC_CK440_B34'
 '@S9S_MB_2U_LIB.S9S_MB_2U(SCH_1):NC_CK440_B34':
 C_SIGNAL='@s9s_mb_2u_lib.s9s_mb_2u(sch_1):nc_ck440_b34';
NODE_NAME     U13 B34
 '@S9S_MB_2U_LIB.S9S_MB_2U(SCH_1):PAGE197_I288@PURE_QUANTA.9SQ440NQQI8(CHIPS)':
 'NC_B34': CDS_PINID='NC_B34';
NET_NAME
'NC_CK440_B36'
 '@S9S_MB_2U_LIB.S9S_MB_2U(SCH_1):NC_CK440_B36':
 C_SIGNAL='@s9s_mb_2u_lib.s9s_mb_2u(sch_1):nc_ck440_b36';
NODE_NAME     U13 B36
 '@S9S_MB_2U_LIB.S9S_MB_2U(SCH_1):PAGE197_I288@PURE_QUANTA.9SQ440NQQI8(CHIPS)':
 'NC_B36': CDS_PINID='NC_B36';
NET_NAME
'NC_CK440_B37'
 '@S9S_MB_2U_LIB.S9S_MB_2U(SCH_1):NC_CK440_B37':
 C_SIGNAL='@s9s_mb_2u_lib.s9s_mb_2u(sch_1):nc_ck440_b37';
NODE_NAME     U13 B37
 '@S9S_MB_2U_LIB.S9S_MB_2U(SCH_1):PAGE197_I288@PURE_QUANTA.9SQ440NQQI8(CHIPS)':
 'NC_B37': CDS_PINID='NC_B37';
NET_NAME
'NC_CK440_B39'
 '@S9S_MB_2U_LIB.S9S_MB_2U(SCH_1):NC_CK440_B39':
 C_SIGNAL='@s9s_mb_2u_lib.s9s_mb_2u(sch_1):nc_ck440_b39';
NODE_NAME     U13 B39
 '@S9S_MB_2U_LIB.S9S_MB_2U(SCH_1):PAGE197_I288@PURE_QUANTA.9SQ440NQQI8(CHIPS)':
 'NC_B39': CDS_PINID='NC_B39';
NET_NAME
'NC_CK440_B41'
 '@S9S_MB_2U_LIB.S9S_MB_2U(SCH_1):NC_CK440_B41':
 C_SIGNAL='@s9s_mb_2u_lib.s9s_mb_2u(sch_1):nc_ck440_b41';
NODE_NAME     U13 B41
 '@S9S_MB_2U_LIB.S9S_MB_2U(SCH_1):PAGE197_I288@PURE_QUANTA.9SQ440NQQI8(CHIPS)':
 'NC_B41': CDS_PINID='NC_B41';
NET_NAME
'NC_CK440_B44'
 '@S9S_MB_2U_LIB.S9S_MB_2U(SCH_1):NC_CK440_B44':
 C_SIGNAL='@s9s_mb_2u_lib.s9s_mb_2u(sch_1):nc_ck440_b44';
NODE_NAME     U13 B44
 '@S9S_MB_2U_LIB.S9S_MB_2U(SCH_1):PAGE197_I288@PURE_QUANTA.9SQ440NQQI8(CHIPS)':
 'NC_B44': CDS_PINID='NC_B44';
NET_NAME
'NC_CK440_B5'
 '@S9S_MB_2U_LIB.S9S_MB_2U(SCH_1):NC_CK440_B5':
 C_SIGNAL='@s9s_mb_2u_lib.s9s_mb_2u(sch_1):nc_ck440_b5';
NODE_NAME     U13 B5
 '@S9S_MB_2U_LIB.S9S_MB_2U(SCH_1):PAGE197_I288@PURE_QUANTA.9SQ440NQQI8(CHIPS)':
 'NC_B5': CDS_PINID='NC_B5';
NET_NAME
'NC_CK440_B7'
 '@S9S_MB_2U_LIB.S9S_MB_2U(SCH_1):NC_CK440_B7':
 C_SIGNAL='@s9s_mb_2u_lib.s9s_mb_2u(sch_1):nc_ck440_b7';
NODE_NAME     U13 B7
 '@S9S_MB_2U_LIB.S9S_MB_2U(SCH_1):PAGE197_I288@PURE_QUANTA.9SQ440NQQI8(CHIPS)':
 'NC_B7': CDS_PINID='NC_B7';
NET_NAME
'NC_CLK_100M_DB2000_NC1'
 '@S9S_MB_2U_LIB.S9S_MB_2U(SCH_1):NC_CLK_100M_DB2000_NC1':
 C_SIGNAL='@s9s_mb_2u_lib.s9s_mb_2u(sch_1):nc_clk_100m_db2000_nc1';
NODE_NAME     U38 B3
 '@S9S_MB_2U_LIB.S9S_MB_2U(SCH_1):PAGE195_I119@PURE_QUANTA.9QXL2001BNHGI8(CHIPS)':
 'NC1': CDS_PINID='NC1';
NET_NAME
'NC_CLK_100M_DB2000_NC10'
 '@S9S_MB_2U_LIB.S9S_MB_2U(SCH_1):NC_CLK_100M_DB2000_NC10':
 C_SIGNAL='@s9s_mb_2u_lib.s9s_mb_2u(sch_1):nc_clk_100m_db2000_nc10';
NODE_NAME     U38 G2
 '@S9S_MB_2U_LIB.S9S_MB_2U(SCH_1):PAGE195_I119@PURE_QUANTA.9QXL2001BNHGI8(CHIPS)':
 'NC10': CDS_PINID='NC10';
NET_NAME
'NC_CLK_100M_DB2000_NC11'
 '@S9S_MB_2U_LIB.S9S_MB_2U(SCH_1):NC_CLK_100M_DB2000_NC11':
 C_SIGNAL='@s9s_mb_2u_lib.s9s_mb_2u(sch_1):nc_clk_100m_db2000_nc11';
NODE_NAME     U38 G11
 '@S9S_MB_2U_LIB.S9S_MB_2U(SCH_1):PAGE195_I119@PURE_QUANTA.9QXL2001BNHGI8(CHIPS)':
 'NC11': CDS_PINID='NC11';
NET_NAME
'NC_CLK_100M_DB2000_NC12'
 '@S9S_MB_2U_LIB.S9S_MB_2U(SCH_1):NC_CLK_100M_DB2000_NC12':
 C_SIGNAL='@s9s_mb_2u_lib.s9s_mb_2u(sch_1):nc_clk_100m_db2000_nc12';
NODE_NAME     U38 J2
 '@S9S_MB_2U_LIB.S9S_MB_2U(SCH_1):PAGE195_I119@PURE_QUANTA.9QXL2001BNHGI8(CHIPS)':
 'NC12': CDS_PINID='NC12';
NET_NAME
'NC_CLK_100M_DB2000_NC13'
 '@S9S_MB_2U_LIB.S9S_MB_2U(SCH_1):NC_CLK_100M_DB2000_NC13':
 C_SIGNAL='@s9s_mb_2u_lib.s9s_mb_2u(sch_1):nc_clk_100m_db2000_nc13';
NODE_NAME     U38 J11
 '@S9S_MB_2U_LIB.S9S_MB_2U(SCH_1):PAGE195_I119@PURE_QUANTA.9QXL2001BNHGI8(CHIPS)':
 'NC13': CDS_PINID='NC13';
NET_NAME
'NC_CLK_100M_DB2000_NC14'
 '@S9S_MB_2U_LIB.S9S_MB_2U(SCH_1):NC_CLK_100M_DB2000_NC14':
 C_SIGNAL='@s9s_mb_2u_lib.s9s_mb_2u(sch_1):nc_clk_100m_db2000_nc14';
NODE_NAME     U38 K2
 '@S9S_MB_2U_LIB.S9S_MB_2U(SCH_1):PAGE195_I119@PURE_QUANTA.9QXL2001BNHGI8(CHIPS)':
 'NC14': CDS_PINID='NC14';
NET_NAME
'NC_CLK_100M_DB2000_NC15'
 '@S9S_MB_2U_LIB.S9S_MB_2U(SCH_1):NC_CLK_100M_DB2000_NC15':
 C_SIGNAL='@s9s_mb_2u_lib.s9s_mb_2u(sch_1):nc_clk_100m_db2000_nc15';
NODE_NAME     U38 L6
 '@S9S_MB_2U_LIB.S9S_MB_2U(SCH_1):PAGE195_I119@PURE_QUANTA.9QXL2001BNHGI8(CHIPS)':
 'NC15': CDS_PINID='NC15';
NET_NAME
'NC_CLK_100M_DB2000_NC16'
 '@S9S_MB_2U_LIB.S9S_MB_2U(SCH_1):NC_CLK_100M_DB2000_NC16':
 C_SIGNAL='@s9s_mb_2u_lib.s9s_mb_2u(sch_1):nc_clk_100m_db2000_nc16';
NODE_NAME     U38 L7
 '@S9S_MB_2U_LIB.S9S_MB_2U(SCH_1):PAGE195_I119@PURE_QUANTA.9QXL2001BNHGI8(CHIPS)':
 'NC16': CDS_PINID='NC16';
NET_NAME
'NC_CLK_100M_DB2000_NC17'
 '@S9S_MB_2U_LIB.S9S_MB_2U(SCH_1):NC_CLK_100M_DB2000_NC17':
 C_SIGNAL='@s9s_mb_2u_lib.s9s_mb_2u(sch_1):nc_clk_100m_db2000_nc17';
NODE_NAME     U38 L3
 '@S9S_MB_2U_LIB.S9S_MB_2U(SCH_1):PAGE195_I119@PURE_QUANTA.9QXL2001BNHGI8(CHIPS)':
 'NC17': CDS_PINID='NC17';
NET_NAME
'NC_CLK_100M_DB2000_NC18'
 '@S9S_MB_2U_LIB.S9S_MB_2U(SCH_1):NC_CLK_100M_DB2000_NC18':
 C_SIGNAL='@s9s_mb_2u_lib.s9s_mb_2u(sch_1):nc_clk_100m_db2000_nc18';
NODE_NAME     U38 L9
 '@S9S_MB_2U_LIB.S9S_MB_2U(SCH_1):PAGE195_I119@PURE_QUANTA.9QXL2001BNHGI8(CHIPS)':
 'NC18': CDS_PINID='NC18';
NET_NAME
'NC_CLK_100M_DB2000_NC2'
 '@S9S_MB_2U_LIB.S9S_MB_2U(SCH_1):NC_CLK_100M_DB2000_NC2':
 C_SIGNAL='@s9s_mb_2u_lib.s9s_mb_2u(sch_1):nc_clk_100m_db2000_nc2';
NODE_NAME     U38 B5
 '@S9S_MB_2U_LIB.S9S_MB_2U(SCH_1):PAGE195_I119@PURE_QUANTA.9QXL2001BNHGI8(CHIPS)':
 'NC2': CDS_PINID='NC2';
NET_NAME
'NC_CLK_100M_DB2000_NC3'
 '@S9S_MB_2U_LIB.S9S_MB_2U(SCH_1):NC_CLK_100M_DB2000_NC3':
 C_SIGNAL='@s9s_mb_2u_lib.s9s_mb_2u(sch_1):nc_clk_100m_db2000_nc3';
NODE_NAME     U38 B7
 '@S9S_MB_2U_LIB.S9S_MB_2U(SCH_1):PAGE195_I119@PURE_QUANTA.9QXL2001BNHGI8(CHIPS)':
 'NC3': CDS_PINID='NC3';
NET_NAME
'NC_CLK_100M_DB2000_NC4'
 '@S9S_MB_2U_LIB.S9S_MB_2U(SCH_1):NC_CLK_100M_DB2000_NC4':
 C_SIGNAL='@s9s_mb_2u_lib.s9s_mb_2u(sch_1):nc_clk_100m_db2000_nc4';
NODE_NAME     U38 B9
 '@S9S_MB_2U_LIB.S9S_MB_2U(SCH_1):PAGE195_I119@PURE_QUANTA.9QXL2001BNHGI8(CHIPS)':
 'NC4': CDS_PINID='NC4';
NET_NAME
'NC_CLK_100M_DB2000_NC5'
 '@S9S_MB_2U_LIB.S9S_MB_2U(SCH_1):NC_CLK_100M_DB2000_NC5':
 C_SIGNAL='@s9s_mb_2u_lib.s9s_mb_2u(sch_1):nc_clk_100m_db2000_nc5';
NODE_NAME     U38 C2
 '@S9S_MB_2U_LIB.S9S_MB_2U(SCH_1):PAGE195_I119@PURE_QUANTA.9QXL2001BNHGI8(CHIPS)':
 'NC5': CDS_PINID='NC5';
NET_NAME
'NC_CLK_100M_DB2000_NC6'
 '@S9S_MB_2U_LIB.S9S_MB_2U(SCH_1):NC_CLK_100M_DB2000_NC6':
 C_SIGNAL='@s9s_mb_2u_lib.s9s_mb_2u(sch_1):nc_clk_100m_db2000_nc6';
NODE_NAME     U38 D2
 '@S9S_MB_2U_LIB.S9S_MB_2U(SCH_1):PAGE195_I119@PURE_QUANTA.9QXL2001BNHGI8(CHIPS)':
 'NC6': CDS_PINID='NC6';
NET_NAME
'NC_CLK_100M_DB2000_NC7'
 '@S9S_MB_2U_LIB.S9S_MB_2U(SCH_1):NC_CLK_100M_DB2000_NC7':
 C_SIGNAL='@s9s_mb_2u_lib.s9s_mb_2u(sch_1):nc_clk_100m_db2000_nc7';
NODE_NAME     U38 D11
 '@S9S_MB_2U_LIB.S9S_MB_2U(SCH_1):PAGE195_I119@PURE_QUANTA.9QXL2001BNHGI8(CHIPS)':
 'NC7': CDS_PINID='NC7';
NET_NAME
'NC_CLK_100M_DB2000_NC8'
 '@S9S_MB_2U_LIB.S9S_MB_2U(SCH_1):NC_CLK_100M_DB2000_NC8':
 C_SIGNAL='@s9s_mb_2u_lib.s9s_mb_2u(sch_1):nc_clk_100m_db2000_nc8';
NODE_NAME     U38 F2
 '@S9S_MB_2U_LIB.S9S_MB_2U(SCH_1):PAGE195_I119@PURE_QUANTA.9QXL2001BNHGI8(CHIPS)':
 'NC8': CDS_PINID='NC8';
NET_NAME
'NC_CLK_100M_DB2000_NC9'
 '@S9S_MB_2U_LIB.S9S_MB_2U(SCH_1):NC_CLK_100M_DB2000_NC9':
 C_SIGNAL='@s9s_mb_2u_lib.s9s_mb_2u(sch_1):nc_clk_100m_db2000_nc9';
NODE_NAME     U38 F11
 '@S9S_MB_2U_LIB.S9S_MB_2U(SCH_1):PAGE195_I119@PURE_QUANTA.9QXL2001BNHGI8(CHIPS)':
 'NC9': CDS_PINID='NC9';
NET_NAME
'NC_CLK_CK440_100M1_DN'
 '@S9S_MB_2U_LIB.S9S_MB_2U(SCH_1):NC_CLK_CK440_100M1_DN':
 C_SIGNAL='@s9s_mb_2u_lib.s9s_mb_2u(sch_1):nc_clk_ck440_100m1_dn';
NODE_NAME     U13 A31
 '@S9S_MB_2U_LIB.S9S_MB_2U(SCH_1):PAGE197_I180@PURE_QUANTA.9SQ440NQQI8(CHIPS)':
 '100M1#': CDS_PINID='\100m1#\';
NET_NAME
'NC_CLK_CK440_100M1_DP'
 '@S9S_MB_2U_LIB.S9S_MB_2U(SCH_1):NC_CLK_CK440_100M1_DP':
 C_SIGNAL='@s9s_mb_2u_lib.s9s_mb_2u(sch_1):nc_clk_ck440_100m1_dp';
NODE_NAME     U13 A32
 '@S9S_MB_2U_LIB.S9S_MB_2U(SCH_1):PAGE197_I180@PURE_QUANTA.9SQ440NQQI8(CHIPS)':
 '100M1': CDS_PINID='\100m1\';
NET_NAME
'NC_CLK_CK440_100M2_DN'
 '@S9S_MB_2U_LIB.S9S_MB_2U(SCH_1):NC_CLK_CK440_100M2_DN':
 C_SIGNAL='@s9s_mb_2u_lib.s9s_mb_2u(sch_1):nc_clk_ck440_100m2_dn';
NODE_NAME     U13 A27
 '@S9S_MB_2U_LIB.S9S_MB_2U(SCH_1):PAGE197_I180@PURE_QUANTA.9SQ440NQQI8(CHIPS)':
 '100M2#': CDS_PINID='\100m2#\';
NET_NAME
'NC_CLK_CK440_100M2_DP'
 '@S9S_MB_2U_LIB.S9S_MB_2U(SCH_1):NC_CLK_CK440_100M2_DP':
 C_SIGNAL='@s9s_mb_2u_lib.s9s_mb_2u(sch_1):nc_clk_ck440_100m2_dp';
NODE_NAME     U13 A28
 '@S9S_MB_2U_LIB.S9S_MB_2U(SCH_1):PAGE197_I180@PURE_QUANTA.9SQ440NQQI8(CHIPS)':
 '100M2': CDS_PINID='\100m2\';
NET_NAME
'NC_CLK_CK440_100M3_DN'
 '@S9S_MB_2U_LIB.S9S_MB_2U(SCH_1):NC_CLK_CK440_100M3_DN':
 C_SIGNAL='@s9s_mb_2u_lib.s9s_mb_2u(sch_1):nc_clk_ck440_100m3_dn';
NODE_NAME     U13 A24
 '@S9S_MB_2U_LIB.S9S_MB_2U(SCH_1):PAGE197_I180@PURE_QUANTA.9SQ440NQQI8(CHIPS)':
 '100M3#': CDS_PINID='\100m3#\';
NET_NAME
'NC_CLK_CK440_100M3_DP'
 '@S9S_MB_2U_LIB.S9S_MB_2U(SCH_1):NC_CLK_CK440_100M3_DP':
 C_SIGNAL='@s9s_mb_2u_lib.s9s_mb_2u(sch_1):nc_clk_ck440_100m3_dp';
NODE_NAME     U13 A25
 '@S9S_MB_2U_LIB.S9S_MB_2U(SCH_1):PAGE197_I180@PURE_QUANTA.9SQ440NQQI8(CHIPS)':
 '100M3': CDS_PINID='\100m3\';
NET_NAME
'NC_CLK_CK440_100M4_DN'
 '@S9S_MB_2U_LIB.S9S_MB_2U(SCH_1):NC_CLK_CK440_100M4_DN':
 C_SIGNAL='@s9s_mb_2u_lib.s9s_mb_2u(sch_1):nc_clk_ck440_100m4_dn';
NODE_NAME     U13 A22
 '@S9S_MB_2U_LIB.S9S_MB_2U(SCH_1):PAGE197_I180@PURE_QUANTA.9SQ440NQQI8(CHIPS)':
 '100M4#': CDS_PINID='\100m4#\';
NET_NAME
'NC_CLK_CK440_100M4_DP'
 '@S9S_MB_2U_LIB.S9S_MB_2U(SCH_1):NC_CLK_CK440_100M4_DP':
 C_SIGNAL='@s9s_mb_2u_lib.s9s_mb_2u(sch_1):nc_clk_ck440_100m4_dp';
NODE_NAME     U13 A23
 '@S9S_MB_2U_LIB.S9S_MB_2U(SCH_1):PAGE197_I180@PURE_QUANTA.9SQ440NQQI8(CHIPS)':
 '100M4': CDS_PINID='\100m4\';
NET_NAME
'NC_CLK_CK440_100M5_DN'
 '@S9S_MB_2U_LIB.S9S_MB_2U(SCH_1):NC_CLK_CK440_100M5_DN':
 C_SIGNAL='@s9s_mb_2u_lib.s9s_mb_2u(sch_1):nc_clk_ck440_100m5_dn';
NODE_NAME     U13 A20
 '@S9S_MB_2U_LIB.S9S_MB_2U(SCH_1):PAGE197_I180@PURE_QUANTA.9SQ440NQQI8(CHIPS)':
 '100M5#': CDS_PINID='\100m5#\';
NET_NAME
'NC_CLK_CK440_100M5_DP'
 '@S9S_MB_2U_LIB.S9S_MB_2U(SCH_1):NC_CLK_CK440_100M5_DP':
 C_SIGNAL='@s9s_mb_2u_lib.s9s_mb_2u(sch_1):nc_clk_ck440_100m5_dp';
NODE_NAME     U13 A21
 '@S9S_MB_2U_LIB.S9S_MB_2U(SCH_1):PAGE197_I180@PURE_QUANTA.9SQ440NQQI8(CHIPS)':
 '100M5': CDS_PINID='\100m5\';
NET_NAME
'NC_CLK_CK440_100M6_DN'
 '@S9S_MB_2U_LIB.S9S_MB_2U(SCH_1):NC_CLK_CK440_100M6_DN':
 C_SIGNAL='@s9s_mb_2u_lib.s9s_mb_2u(sch_1):nc_clk_ck440_100m6_dn';
NODE_NAME     U13 A18
 '@S9S_MB_2U_LIB.S9S_MB_2U(SCH_1):PAGE197_I180@PURE_QUANTA.9SQ440NQQI8(CHIPS)':
 '100M6#': CDS_PINID='\100m6#\';
NET_NAME
'NC_CLK_CK440_100M6_DP'
 '@S9S_MB_2U_LIB.S9S_MB_2U(SCH_1):NC_CLK_CK440_100M6_DP':
 C_SIGNAL='@s9s_mb_2u_lib.s9s_mb_2u(sch_1):nc_clk_ck440_100m6_dp';
NODE_NAME     U13 A19
 '@S9S_MB_2U_LIB.S9S_MB_2U(SCH_1):PAGE197_I180@PURE_QUANTA.9SQ440NQQI8(CHIPS)':
 '100M6': CDS_PINID='\100m6\';
NET_NAME
'NC_CLK_CK440_MXCK0_DN'
 '@S9S_MB_2U_LIB.S9S_MB_2U(SCH_1):NC_CLK_CK440_MXCK0_DN':
 C_SIGNAL='@s9s_mb_2u_lib.s9s_mb_2u(sch_1):nc_clk_ck440_mxck0_dn';
NODE_NAME     U13 A51
 '@S9S_MB_2U_LIB.S9S_MB_2U(SCH_1):PAGE197_I180@PURE_QUANTA.9SQ440NQQI8(CHIPS)':
 'MXCK0#': CDS_PINID='\mxck0#\';
NET_NAME
'NC_CLK_CK440_MXCK0_DP'
 '@S9S_MB_2U_LIB.S9S_MB_2U(SCH_1):NC_CLK_CK440_MXCK0_DP':
 C_SIGNAL='@s9s_mb_2u_lib.s9s_mb_2u(sch_1):nc_clk_ck440_mxck0_dp';
NODE_NAME     U13 A52
 '@S9S_MB_2U_LIB.S9S_MB_2U(SCH_1):PAGE197_I180@PURE_QUANTA.9SQ440NQQI8(CHIPS)':
 'MXCK0': CDS_PINID='MXCK0';
NET_NAME
'NC_CLK_CK440_MXCK1_DN'
 '@S9S_MB_2U_LIB.S9S_MB_2U(SCH_1):NC_CLK_CK440_MXCK1_DN':
 C_SIGNAL='@s9s_mb_2u_lib.s9s_mb_2u(sch_1):nc_clk_ck440_mxck1_dn';
NODE_NAME     U13 A49
 '@S9S_MB_2U_LIB.S9S_MB_2U(SCH_1):PAGE197_I180@PURE_QUANTA.9SQ440NQQI8(CHIPS)':
 'MXCK1#': CDS_PINID='\mxck1#\';
NET_NAME
'NC_CLK_CK440_MXCK1_DP'
 '@S9S_MB_2U_LIB.S9S_MB_2U(SCH_1):NC_CLK_CK440_MXCK1_DP':
 C_SIGNAL='@s9s_mb_2u_lib.s9s_mb_2u(sch_1):nc_clk_ck440_mxck1_dp';
NODE_NAME     U13 A50
 '@S9S_MB_2U_LIB.S9S_MB_2U(SCH_1):PAGE197_I180@PURE_QUANTA.9SQ440NQQI8(CHIPS)':
 'MXCK1': CDS_PINID='MXCK1';
NET_NAME
'NC_CLK_CK440_MXCK3_DN'
 '@S9S_MB_2U_LIB.S9S_MB_2U(SCH_1):NC_CLK_CK440_MXCK3_DN':
 C_SIGNAL='@s9s_mb_2u_lib.s9s_mb_2u(sch_1):nc_clk_ck440_mxck3_dn';
NODE_NAME     U13 A45
 '@S9S_MB_2U_LIB.S9S_MB_2U(SCH_1):PAGE197_I180@PURE_QUANTA.9SQ440NQQI8(CHIPS)':
 'MXCK3#': CDS_PINID='\mxck3#\';
NET_NAME
'NC_CLK_CK440_MXCK3_DP'
 '@S9S_MB_2U_LIB.S9S_MB_2U(SCH_1):NC_CLK_CK440_MXCK3_DP':
 C_SIGNAL='@s9s_mb_2u_lib.s9s_mb_2u(sch_1):nc_clk_ck440_mxck3_dp';
NODE_NAME     U13 A46
 '@S9S_MB_2U_LIB.S9S_MB_2U(SCH_1):PAGE197_I180@PURE_QUANTA.9SQ440NQQI8(CHIPS)':
 'MXCK3': CDS_PINID='MXCK3';
NET_NAME
'NC_CLK_CK440_MXCK4_DN'
 '@S9S_MB_2U_LIB.S9S_MB_2U(SCH_1):NC_CLK_CK440_MXCK4_DN':
 C_SIGNAL='@s9s_mb_2u_lib.s9s_mb_2u(sch_1):nc_clk_ck440_mxck4_dn';
NODE_NAME     U13 A43
 '@S9S_MB_2U_LIB.S9S_MB_2U(SCH_1):PAGE197_I180@PURE_QUANTA.9SQ440NQQI8(CHIPS)':
 'MXCK4#': CDS_PINID='\mxck4#\';
NET_NAME
'NC_CLK_CK440_MXCK4_DP'
 '@S9S_MB_2U_LIB.S9S_MB_2U(SCH_1):NC_CLK_CK440_MXCK4_DP':
 C_SIGNAL='@s9s_mb_2u_lib.s9s_mb_2u(sch_1):nc_clk_ck440_mxck4_dp';
NODE_NAME     U13 A44
 '@S9S_MB_2U_LIB.S9S_MB_2U(SCH_1):PAGE197_I180@PURE_QUANTA.9SQ440NQQI8(CHIPS)':
 'MXCK4': CDS_PINID='MXCK4';
NET_NAME
'NC_CLK_CK440_MXCK5_DN'
 '@S9S_MB_2U_LIB.S9S_MB_2U(SCH_1):NC_CLK_CK440_MXCK5_DN':
 C_SIGNAL='@s9s_mb_2u_lib.s9s_mb_2u(sch_1):nc_clk_ck440_mxck5_dn';
NODE_NAME     U13 A41
 '@S9S_MB_2U_LIB.S9S_MB_2U(SCH_1):PAGE197_I180@PURE_QUANTA.9SQ440NQQI8(CHIPS)':
 'MXCK5#': CDS_PINID='\mxck5#\';
NET_NAME
'NC_CLK_CK440_MXCK5_DP'
 '@S9S_MB_2U_LIB.S9S_MB_2U(SCH_1):NC_CLK_CK440_MXCK5_DP':
 C_SIGNAL='@s9s_mb_2u_lib.s9s_mb_2u(sch_1):nc_clk_ck440_mxck5_dp';
NODE_NAME     U13 A42
 '@S9S_MB_2U_LIB.S9S_MB_2U(SCH_1):PAGE197_I180@PURE_QUANTA.9SQ440NQQI8(CHIPS)':
 'MXCK5': CDS_PINID='MXCK5';
NET_NAME
'NC_CLK_CK440_MXCK6_DN'
 '@S9S_MB_2U_LIB.S9S_MB_2U(SCH_1):NC_CLK_CK440_MXCK6_DN':
 C_SIGNAL='@s9s_mb_2u_lib.s9s_mb_2u(sch_1):nc_clk_ck440_mxck6_dn';
NODE_NAME     U13 A39
 '@S9S_MB_2U_LIB.S9S_MB_2U(SCH_1):PAGE197_I180@PURE_QUANTA.9SQ440NQQI8(CHIPS)':
 'MXCK6#': CDS_PINID='\mxck6#\';
NET_NAME
'NC_CLK_CK440_MXCK6_DP'
 '@S9S_MB_2U_LIB.S9S_MB_2U(SCH_1):NC_CLK_CK440_MXCK6_DP':
 C_SIGNAL='@s9s_mb_2u_lib.s9s_mb_2u(sch_1):nc_clk_ck440_mxck6_dp';
NODE_NAME     U13 A40
 '@S9S_MB_2U_LIB.S9S_MB_2U(SCH_1):PAGE197_I180@PURE_QUANTA.9SQ440NQQI8(CHIPS)':
 'MXCK6': CDS_PINID='MXCK6';
NET_NAME
'NC_CLK_CK440_MXCK7_DN'
 '@S9S_MB_2U_LIB.S9S_MB_2U(SCH_1):NC_CLK_CK440_MXCK7_DN':
 C_SIGNAL='@s9s_mb_2u_lib.s9s_mb_2u(sch_1):nc_clk_ck440_mxck7_dn';
NODE_NAME     U13 A37
 '@S9S_MB_2U_LIB.S9S_MB_2U(SCH_1):PAGE197_I180@PURE_QUANTA.9SQ440NQQI8(CHIPS)':
 'MXCK7#': CDS_PINID='\mxck7#\';
NET_NAME
'NC_CLK_CK440_MXCK7_DP'
 '@S9S_MB_2U_LIB.S9S_MB_2U(SCH_1):NC_CLK_CK440_MXCK7_DP':
 C_SIGNAL='@s9s_mb_2u_lib.s9s_mb_2u(sch_1):nc_clk_ck440_mxck7_dp';
NODE_NAME     U13 A38
 '@S9S_MB_2U_LIB.S9S_MB_2U(SCH_1):PAGE197_I180@PURE_QUANTA.9SQ440NQQI8(CHIPS)':
 'MXCK7': CDS_PINID='MXCK7';
NET_NAME
'NC_CLK_CK440_MXCK8_DN'
 '@S9S_MB_2U_LIB.S9S_MB_2U(SCH_1):NC_CLK_CK440_MXCK8_DN':
 C_SIGNAL='@s9s_mb_2u_lib.s9s_mb_2u(sch_1):nc_clk_ck440_mxck8_dn';
NODE_NAME     U13 A35
 '@S9S_MB_2U_LIB.S9S_MB_2U(SCH_1):PAGE197_I180@PURE_QUANTA.9SQ440NQQI8(CHIPS)':
 'MXCK8#': CDS_PINID='\mxck8#\';
NET_NAME
'NC_CLK_CK440_MXCK8_DP'
 '@S9S_MB_2U_LIB.S9S_MB_2U(SCH_1):NC_CLK_CK440_MXCK8_DP':
 C_SIGNAL='@s9s_mb_2u_lib.s9s_mb_2u(sch_1):nc_clk_ck440_mxck8_dp';
NODE_NAME     U13 A36
 '@S9S_MB_2U_LIB.S9S_MB_2U(SCH_1):PAGE197_I180@PURE_QUANTA.9SQ440NQQI8(CHIPS)':
 'MXCK8': CDS_PINID='MXCK8';
NET_NAME
'NC_CLK_PFT_OUT_CPU0_DN'
 '@S9S_MB_2U_LIB.S9S_MB_2U(SCH_1):NC_CLK_PFT_OUT_CPU0_DN':
 C_SIGNAL='@s9s_mb_2u_lib.s9s_mb_2u(sch_1):nc_clk_pft_out_cpu0_dn';
NODE_NAME     U2 CE70
 '@S9S_MB_2U_LIB.S9S_MB_2U(SCH_1):PAGE13_I57@PURE_QUANTA.SOCKET4677_AZIF0045P001C01CS(CHIPS)':
 'RSVD91': CDS_PINID='RSVD91';
NET_NAME
'NC_CLK_PFT_OUT_CPU0_DP'
 '@S9S_MB_2U_LIB.S9S_MB_2U(SCH_1):NC_CLK_PFT_OUT_CPU0_DP':
 C_SIGNAL='@s9s_mb_2u_lib.s9s_mb_2u(sch_1):nc_clk_pft_out_cpu0_dp';
NODE_NAME     U2 CD71
 '@S9S_MB_2U_LIB.S9S_MB_2U(SCH_1):PAGE13_I57@PURE_QUANTA.SOCKET4677_AZIF0045P001C01CS(CHIPS)':
 'RSVD88': CDS_PINID='RSVD88';
NET_NAME
'NC_CPU0_DDR01_VIEWDIG0'
 '@S9S_MB_2U_LIB.S9S_MB_2U(SCH_1):NC_CPU0_DDR01_VIEWDIG0':
 C_SIGNAL='@s9s_mb_2u_lib.s9s_mb_2u(sch_1):nc_cpu0_ddr01_viewdig0';
NODE_NAME     U2 AU58
 '@S9S_MB_2U_LIB.S9S_MB_2U(SCH_1):PAGE16_I1@PURE_QUANTA.SOCKET4677_AZIF0045P001C01CS(CHIPS)':
 'RSVD10': CDS_PINID='RSVD10';
NET_NAME
'NC_CPU0_DDR01_VIEWDIG1'
 '@S9S_MB_2U_LIB.S9S_MB_2U(SCH_1):NC_CPU0_DDR01_VIEWDIG1':
 C_SIGNAL='@s9s_mb_2u_lib.s9s_mb_2u(sch_1):nc_cpu0_ddr01_viewdig1';
NODE_NAME     U2 AU56
 '@S9S_MB_2U_LIB.S9S_MB_2U(SCH_1):PAGE16_I1@PURE_QUANTA.SOCKET4677_AZIF0045P001C01CS(CHIPS)':
 'RSVD9': CDS_PINID='RSVD9';
NET_NAME
'NC_CPU0_DDR23_VIEWDIG0'
 '@S9S_MB_2U_LIB.S9S_MB_2U(SCH_1):NC_CPU0_DDR23_VIEWDIG0':
 C_SIGNAL='@s9s_mb_2u_lib.s9s_mb_2u(sch_1):nc_cpu0_ddr23_viewdig0';
NODE_NAME     U2 AV32
 '@S9S_MB_2U_LIB.S9S_MB_2U(SCH_1):PAGE16_I1@PURE_QUANTA.SOCKET4677_AZIF0045P001C01CS(CHIPS)':
 'RSVD16': CDS_PINID='RSVD16';
NET_NAME
'NC_CPU0_DDR23_VIEWDIG1'
 '@S9S_MB_2U_LIB.S9S_MB_2U(SCH_1):NC_CPU0_DDR23_VIEWDIG1':
 C_SIGNAL='@s9s_mb_2u_lib.s9s_mb_2u(sch_1):nc_cpu0_ddr23_viewdig1';
NODE_NAME     U2 AU33
 '@S9S_MB_2U_LIB.S9S_MB_2U(SCH_1):PAGE16_I1@PURE_QUANTA.SOCKET4677_AZIF0045P001C01CS(CHIPS)':
 'RSVD7': CDS_PINID='RSVD7';
NET_NAME
'NC_CPU0_DDR45_VIEWDIG0'
 '@S9S_MB_2U_LIB.S9S_MB_2U(SCH_1):NC_CPU0_DDR45_VIEWDIG0':
 C_SIGNAL='@s9s_mb_2u_lib.s9s_mb_2u(sch_1):nc_cpu0_ddr45_viewdig0';
NODE_NAME     U2 CY24
 '@S9S_MB_2U_LIB.S9S_MB_2U(SCH_1):PAGE16_I1@PURE_QUANTA.SOCKET4677_AZIF0045P001C01CS(CHIPS)':
 'RSVD151': CDS_PINID='RSVD151';
NET_NAME
'NC_CPU0_DDR45_VIEWDIG1'
 '@S9S_MB_2U_LIB.S9S_MB_2U(SCH_1):NC_CPU0_DDR45_VIEWDIG1':
 C_SIGNAL='@s9s_mb_2u_lib.s9s_mb_2u(sch_1):nc_cpu0_ddr45_viewdig1';
NODE_NAME     U2 CY38
 '@S9S_MB_2U_LIB.S9S_MB_2U(SCH_1):PAGE16_I1@PURE_QUANTA.SOCKET4677_AZIF0045P001C01CS(CHIPS)':
 'RSVD152': CDS_PINID='RSVD152';
NET_NAME
'NC_CPU0_DDR67_VIEWDIG0'
 '@S9S_MB_2U_LIB.S9S_MB_2U(SCH_1):NC_CPU0_DDR67_VIEWDIG0':
 C_SIGNAL='@s9s_mb_2u_lib.s9s_mb_2u(sch_1):nc_cpu0_ddr67_viewdig0';
NODE_NAME     U2 DA45
 '@S9S_MB_2U_LIB.S9S_MB_2U(SCH_1):PAGE16_I1@PURE_QUANTA.SOCKET4677_AZIF0045P001C01CS(CHIPS)':
 'RSVD158': CDS_PINID='RSVD158';
NET_NAME
'NC_CPU0_DDR67_VIEWDIG1'
 '@S9S_MB_2U_LIB.S9S_MB_2U(SCH_1):NC_CPU0_DDR67_VIEWDIG1':
 C_SIGNAL='@s9s_mb_2u_lib.s9s_mb_2u(sch_1):nc_cpu0_ddr67_viewdig1';
NODE_NAME     U2 CY49
 '@S9S_MB_2U_LIB.S9S_MB_2U(SCH_1):PAGE16_I1@PURE_QUANTA.SOCKET4677_AZIF0045P001C01CS(CHIPS)':
 'RSVD153': CDS_PINID='RSVD153';
NET_NAME
'NC_CPU0_DMI_APROBE<0>'
 '@S9S_MB_2U_LIB.S9S_MB_2U(SCH_1):NC_CPU0_DMI_APROBE'<0>:
 C_SIGNAL='@s9s_mb_2u_lib.s9s_mb_2u(sch_1):nc_cpu0_dmi_aprobe(0)';
NODE_NAME     U2 CA21
 '@S9S_MB_2U_LIB.S9S_MB_2U(SCH_1):PAGE19_I1@PURE_QUANTA.SOCKET4677_AZIF0045P001C01CS(CHIPS)':
 'RSVD77': CDS_PINID='RSVD77';
NET_NAME
'NC_CPU0_DMI_APROBE<1>'
 '@S9S_MB_2U_LIB.S9S_MB_2U(SCH_1):NC_CPU0_DMI_APROBE'<1>:
 C_SIGNAL='@s9s_mb_2u_lib.s9s_mb_2u(sch_1):nc_cpu0_dmi_aprobe(1)';
NODE_NAME     U2 BW21
 '@S9S_MB_2U_LIB.S9S_MB_2U(SCH_1):PAGE19_I1@PURE_QUANTA.SOCKET4677_AZIF0045P001C01CS(CHIPS)':
 'RSVD74': CDS_PINID='RSVD74';
NET_NAME
'NC_CPU0_HBM0_VIEWDIG0'
 '@S9S_MB_2U_LIB.S9S_MB_2U(SCH_1):NC_CPU0_HBM0_VIEWDIG0':
 C_SIGNAL='@s9s_mb_2u_lib.s9s_mb_2u(sch_1):nc_cpu0_hbm0_viewdig0';
NODE_NAME     U2 U17
 '@S9S_MB_2U_LIB.S9S_MB_2U(SCH_1):PAGE17_I1@PURE_QUANTA.SOCKET4677_AZIF0045P001C01CS(CHIPS)':
 'RSVD164': CDS_PINID='RSVD164';
NET_NAME
'NC_CPU0_HBM0_VIEWDIG1'
 '@S9S_MB_2U_LIB.S9S_MB_2U(SCH_1):NC_CPU0_HBM0_VIEWDIG1':
 C_SIGNAL='@s9s_mb_2u_lib.s9s_mb_2u(sch_1):nc_cpu0_hbm0_viewdig1';
NODE_NAME     U2 EG17
 '@S9S_MB_2U_LIB.S9S_MB_2U(SCH_1):PAGE17_I1@PURE_QUANTA.SOCKET4677_AZIF0045P001C01CS(CHIPS)':
 'RSVD160': CDS_PINID='RSVD160';
NET_NAME
'NC_CPU0_HBM1_VIEWDIG0'
 '@S9S_MB_2U_LIB.S9S_MB_2U(SCH_1):NC_CPU0_HBM1_VIEWDIG0':
 C_SIGNAL='@s9s_mb_2u_lib.s9s_mb_2u(sch_1):nc_cpu0_hbm1_viewdig0';
NODE_NAME     U2 W17
 '@S9S_MB_2U_LIB.S9S_MB_2U(SCH_1):PAGE17_I1@PURE_QUANTA.SOCKET4677_AZIF0045P001C01CS(CHIPS)':
 'RSVD165': CDS_PINID='RSVD165';
NET_NAME
'NC_CPU0_HBM1_VIEWDIG1'
 '@S9S_MB_2U_LIB.S9S_MB_2U(SCH_1):NC_CPU0_HBM1_VIEWDIG1':
 C_SIGNAL='@s9s_mb_2u_lib.s9s_mb_2u(sch_1):nc_cpu0_hbm1_viewdig1';
NODE_NAME     U2 CW41
 '@S9S_MB_2U_LIB.S9S_MB_2U(SCH_1):PAGE17_I1@PURE_QUANTA.SOCKET4677_AZIF0045P001C01CS(CHIPS)':
 'RSVD147': CDS_PINID='RSVD147';
NET_NAME
'NC_CPU0_HBM2_VIEWDIG0'
 '@S9S_MB_2U_LIB.S9S_MB_2U(SCH_1):NC_CPU0_HBM2_VIEWDIG0':
 C_SIGNAL='@s9s_mb_2u_lib.s9s_mb_2u(sch_1):nc_cpu0_hbm2_viewdig0';
NODE_NAME     U2 AC78
 '@S9S_MB_2U_LIB.S9S_MB_2U(SCH_1):PAGE17_I1@PURE_QUANTA.SOCKET4677_AZIF0045P001C01CS(CHIPS)':
 'RSVD0': CDS_PINID='RSVD0';
NET_NAME
'NC_CPU0_HBM2_VIEWDIG1'
 '@S9S_MB_2U_LIB.S9S_MB_2U(SCH_1):NC_CPU0_HBM2_VIEWDIG1':
 C_SIGNAL='@s9s_mb_2u_lib.s9s_mb_2u(sch_1):nc_cpu0_hbm2_viewdig1';
NODE_NAME     U2 AD77
 '@S9S_MB_2U_LIB.S9S_MB_2U(SCH_1):PAGE17_I1@PURE_QUANTA.SOCKET4677_AZIF0045P001C01CS(CHIPS)':
 'RSVD1': CDS_PINID='RSVD1';
NET_NAME
'NC_CPU0_HBM3_VIEWDIG0'
 '@S9S_MB_2U_LIB.S9S_MB_2U(SCH_1):NC_CPU0_HBM3_VIEWDIG0':
 C_SIGNAL='@s9s_mb_2u_lib.s9s_mb_2u(sch_1):nc_cpu0_hbm3_viewdig0';
NODE_NAME     U2 BG78
 '@S9S_MB_2U_LIB.S9S_MB_2U(SCH_1):PAGE17_I1@PURE_QUANTA.SOCKET4677_AZIF0045P001C01CS(CHIPS)':
 'RSVD54': CDS_PINID='RSVD54';
NET_NAME
'NC_CPU0_HBM3_VIEWDIG1'
 '@S9S_MB_2U_LIB.S9S_MB_2U(SCH_1):NC_CPU0_HBM3_VIEWDIG1':
 C_SIGNAL='@s9s_mb_2u_lib.s9s_mb_2u(sch_1):nc_cpu0_hbm3_viewdig1';
NODE_NAME     U2 BL60
 '@S9S_MB_2U_LIB.S9S_MB_2U(SCH_1):PAGE17_I1@PURE_QUANTA.SOCKET4677_AZIF0045P001C01CS(CHIPS)':
 'RSVD63': CDS_PINID='RSVD63';
NET_NAME
'NC_CPU0_LGSSPARE0'
 '@S9S_MB_2U_LIB.S9S_MB_2U(SCH_1):NC_CPU0_LGSSPARE0':
 C_SIGNAL='@s9s_mb_2u_lib.s9s_mb_2u(sch_1):nc_cpu0_lgsspare0';
NODE_NAME     U2 CR60
 '@S9S_MB_2U_LIB.S9S_MB_2U(SCH_1):PAGE16_I1@PURE_QUANTA.SOCKET4677_AZIF0045P001C01CS(CHIPS)':
 'RSVD134': CDS_PINID='RSVD134';
NET_NAME
'NC_CPU0_LGSSPARE1'
 '@S9S_MB_2U_LIB.S9S_MB_2U(SCH_1):NC_CPU0_LGSSPARE1':
 C_SIGNAL='@s9s_mb_2u_lib.s9s_mb_2u(sch_1):nc_cpu0_lgsspare1';
NODE_NAME     U2 CN60
 '@S9S_MB_2U_LIB.S9S_MB_2U(SCH_1):PAGE16_I1@PURE_QUANTA.SOCKET4677_AZIF0045P001C01CS(CHIPS)':
 'RSVD125': CDS_PINID='RSVD125';
NET_NAME
'NC_CPU0_LGSSPARE2'
 '@S9S_MB_2U_LIB.S9S_MB_2U(SCH_1):NC_CPU0_LGSSPARE2':
 C_SIGNAL='@s9s_mb_2u_lib.s9s_mb_2u(sch_1):nc_cpu0_lgsspare2';
NODE_NAME     U2 CU62
 '@S9S_MB_2U_LIB.S9S_MB_2U(SCH_1):PAGE16_I1@PURE_QUANTA.SOCKET4677_AZIF0045P001C01CS(CHIPS)':
 'RSVD139': CDS_PINID='RSVD139';
NET_NAME
'NC_CPU0_LGSSPARE3'
 '@S9S_MB_2U_LIB.S9S_MB_2U(SCH_1):NC_CPU0_LGSSPARE3':
 C_SIGNAL='@s9s_mb_2u_lib.s9s_mb_2u(sch_1):nc_cpu0_lgsspare3';
NODE_NAME     U2 CE62
 '@S9S_MB_2U_LIB.S9S_MB_2U(SCH_1):PAGE16_I1@PURE_QUANTA.SOCKET4677_AZIF0045P001C01CS(CHIPS)':
 'RSVD90': CDS_PINID='RSVD90';
NET_NAME
'NC_CPU0_LGSSPARE4'
 '@S9S_MB_2U_LIB.S9S_MB_2U(SCH_1):NC_CPU0_LGSSPARE4':
 C_SIGNAL='@s9s_mb_2u_lib.s9s_mb_2u(sch_1):nc_cpu0_lgsspare4';
NODE_NAME     U2 CC64
 '@S9S_MB_2U_LIB.S9S_MB_2U(SCH_1):PAGE16_I1@PURE_QUANTA.SOCKET4677_AZIF0045P001C01CS(CHIPS)':
 'RSVD81': CDS_PINID='RSVD81';
NET_NAME
'NC_CPU0_LGSSPARE5'
 '@S9S_MB_2U_LIB.S9S_MB_2U(SCH_1):NC_CPU0_LGSSPARE5':
 C_SIGNAL='@s9s_mb_2u_lib.s9s_mb_2u(sch_1):nc_cpu0_lgsspare5';
NODE_NAME     U2 CP61
 '@S9S_MB_2U_LIB.S9S_MB_2U(SCH_1):PAGE16_I1@PURE_QUANTA.SOCKET4677_AZIF0045P001C01CS(CHIPS)':
 'RSVD129': CDS_PINID='RSVD129';
NET_NAME
'NC_CPU0_MDFI_DIE00_EW0'
 '@S9S_MB_2U_LIB.S9S_MB_2U(SCH_1):NC_CPU0_MDFI_DIE00_EW0':
 C_SIGNAL='@s9s_mb_2u_lib.s9s_mb_2u(sch_1):nc_cpu0_mdfi_die00_ew0';
NODE_NAME     U2 BP22
 '@S9S_MB_2U_LIB.S9S_MB_2U(SCH_1):PAGE17_I1@PURE_QUANTA.SOCKET4677_AZIF0045P001C01CS(CHIPS)':
 'RSVD67': CDS_PINID='RSVD67';
NET_NAME
'NC_CPU0_MDFI_DIE00_EW1'
 '@S9S_MB_2U_LIB.S9S_MB_2U(SCH_1):NC_CPU0_MDFI_DIE00_EW1':
 C_SIGNAL='@s9s_mb_2u_lib.s9s_mb_2u(sch_1):nc_cpu0_mdfi_die00_ew1';
NODE_NAME     U2 BR21
 '@S9S_MB_2U_LIB.S9S_MB_2U(SCH_1):PAGE17_I1@PURE_QUANTA.SOCKET4677_AZIF0045P001C01CS(CHIPS)':
 'RSVD71': CDS_PINID='RSVD71';
NET_NAME
'NC_CPU0_MDFI_DIE00_NS0'
 '@S9S_MB_2U_LIB.S9S_MB_2U(SCH_1):NC_CPU0_MDFI_DIE00_NS0':
 C_SIGNAL='@s9s_mb_2u_lib.s9s_mb_2u(sch_1):nc_cpu0_mdfi_die00_ns0';
NODE_NAME     U2 BK22
 '@S9S_MB_2U_LIB.S9S_MB_2U(SCH_1):PAGE17_I1@PURE_QUANTA.SOCKET4677_AZIF0045P001C01CS(CHIPS)':
 'RSVD60': CDS_PINID='RSVD60';
NET_NAME
'NC_CPU0_MDFI_DIE00_NS1'
 '@S9S_MB_2U_LIB.S9S_MB_2U(SCH_1):NC_CPU0_MDFI_DIE00_NS1':
 C_SIGNAL='@s9s_mb_2u_lib.s9s_mb_2u(sch_1):nc_cpu0_mdfi_die00_ns1';
NODE_NAME     U2 BJ21
 '@S9S_MB_2U_LIB.S9S_MB_2U(SCH_1):PAGE17_I1@PURE_QUANTA.SOCKET4677_AZIF0045P001C01CS(CHIPS)':
 'RSVD57': CDS_PINID='RSVD57';
NET_NAME
'NC_CPU0_MDFI_DIE01_EW0'
 '@S9S_MB_2U_LIB.S9S_MB_2U(SCH_1):NC_CPU0_MDFI_DIE01_EW0':
 C_SIGNAL='@s9s_mb_2u_lib.s9s_mb_2u(sch_1):nc_cpu0_mdfi_die01_ew0';
NODE_NAME     U2 AV65
 '@S9S_MB_2U_LIB.S9S_MB_2U(SCH_1):PAGE17_I1@PURE_QUANTA.SOCKET4677_AZIF0045P001C01CS(CHIPS)':
 'RSVD21': CDS_PINID='RSVD21';
NET_NAME
'NC_CPU0_MDFI_DIE01_EW1'
 '@S9S_MB_2U_LIB.S9S_MB_2U(SCH_1):NC_CPU0_MDFI_DIE01_EW1':
 C_SIGNAL='@s9s_mb_2u_lib.s9s_mb_2u(sch_1):nc_cpu0_mdfi_die01_ew1';
NODE_NAME     U2 CC66
 '@S9S_MB_2U_LIB.S9S_MB_2U(SCH_1):PAGE17_I1@PURE_QUANTA.SOCKET4677_AZIF0045P001C01CS(CHIPS)':
 'RSVD82': CDS_PINID='RSVD82';
NET_NAME
'NC_CPU0_MDFI_DIE01_NS0'
 '@S9S_MB_2U_LIB.S9S_MB_2U(SCH_1):NC_CPU0_MDFI_DIE01_NS0':
 C_SIGNAL='@s9s_mb_2u_lib.s9s_mb_2u(sch_1):nc_cpu0_mdfi_die01_ns0';
NODE_NAME     U2 BF71
 '@S9S_MB_2U_LIB.S9S_MB_2U(SCH_1):PAGE17_I1@PURE_QUANTA.SOCKET4677_AZIF0045P001C01CS(CHIPS)':
 'RSVD51': CDS_PINID='RSVD51';
NET_NAME
'NC_CPU0_MDFI_DIE01_NS1'
 '@S9S_MB_2U_LIB.S9S_MB_2U(SCH_1):NC_CPU0_MDFI_DIE01_NS1':
 C_SIGNAL='@s9s_mb_2u_lib.s9s_mb_2u(sch_1):nc_cpu0_mdfi_die01_ns1';
NODE_NAME     U2 BD71
 '@S9S_MB_2U_LIB.S9S_MB_2U(SCH_1):PAGE17_I1@PURE_QUANTA.SOCKET4677_AZIF0045P001C01CS(CHIPS)':
 'RSVD43': CDS_PINID='RSVD43';
NET_NAME
'NC_CPU0_MDFI_DIE10_EW0'
 '@S9S_MB_2U_LIB.S9S_MB_2U(SCH_1):NC_CPU0_MDFI_DIE10_EW0':
 C_SIGNAL='@s9s_mb_2u_lib.s9s_mb_2u(sch_1):nc_cpu0_mdfi_die10_ew0';
NODE_NAME     U2 CD26
 '@S9S_MB_2U_LIB.S9S_MB_2U(SCH_1):PAGE17_I1@PURE_QUANTA.SOCKET4677_AZIF0045P001C01CS(CHIPS)':
 'RSVD84': CDS_PINID='RSVD84';
NET_NAME
'NC_CPU0_MDFI_DIE10_EW1'
 '@S9S_MB_2U_LIB.S9S_MB_2U(SCH_1):NC_CPU0_MDFI_DIE10_EW1':
 C_SIGNAL='@s9s_mb_2u_lib.s9s_mb_2u(sch_1):nc_cpu0_mdfi_die10_ew1';
NODE_NAME     U2 CD30
 '@S9S_MB_2U_LIB.S9S_MB_2U(SCH_1):PAGE17_I1@PURE_QUANTA.SOCKET4677_AZIF0045P001C01CS(CHIPS)':
 'RSVD85': CDS_PINID='RSVD85';
NET_NAME
'NC_CPU0_MDFI_DIE10_NS0'
 '@S9S_MB_2U_LIB.S9S_MB_2U(SCH_1):NC_CPU0_MDFI_DIE10_NS0':
 C_SIGNAL='@s9s_mb_2u_lib.s9s_mb_2u(sch_1):nc_cpu0_mdfi_die10_ns0';
NODE_NAME     U2 CF22
 '@S9S_MB_2U_LIB.S9S_MB_2U(SCH_1):PAGE17_I1@PURE_QUANTA.SOCKET4677_AZIF0045P001C01CS(CHIPS)':
 'RSVD92': CDS_PINID='RSVD92';
NET_NAME
'NC_CPU0_MDFI_DIE10_NS1'
 '@S9S_MB_2U_LIB.S9S_MB_2U(SCH_1):NC_CPU0_MDFI_DIE10_NS1':
 C_SIGNAL='@s9s_mb_2u_lib.s9s_mb_2u(sch_1):nc_cpu0_mdfi_die10_ns1';
NODE_NAME     U2 CD22
 '@S9S_MB_2U_LIB.S9S_MB_2U(SCH_1):PAGE17_I1@PURE_QUANTA.SOCKET4677_AZIF0045P001C01CS(CHIPS)':
 'RSVD83': CDS_PINID='RSVD83';
NET_NAME
'NC_CPU0_MDFI_DIE11_EW0'
 '@S9S_MB_2U_LIB.S9S_MB_2U(SCH_1):NC_CPU0_MDFI_DIE11_EW0':
 C_SIGNAL='@s9s_mb_2u_lib.s9s_mb_2u(sch_1):nc_cpu0_mdfi_die11_ew0';
NODE_NAME     U2 CJ70
 '@S9S_MB_2U_LIB.S9S_MB_2U(SCH_1):PAGE17_I1@PURE_QUANTA.SOCKET4677_AZIF0045P001C01CS(CHIPS)':
 'RSVD107': CDS_PINID='RSVD107';
NET_NAME
'NC_CPU0_MDFI_DIE11_EW1'
 '@S9S_MB_2U_LIB.S9S_MB_2U(SCH_1):NC_CPU0_MDFI_DIE11_EW1':
 C_SIGNAL='@s9s_mb_2u_lib.s9s_mb_2u(sch_1):nc_cpu0_mdfi_die11_ew1';
NODE_NAME     U2 CH69
 '@S9S_MB_2U_LIB.S9S_MB_2U(SCH_1):PAGE17_I1@PURE_QUANTA.SOCKET4677_AZIF0045P001C01CS(CHIPS)':
 'RSVD99': CDS_PINID='RSVD99';
NET_NAME
'NC_CPU0_MDFI_DIE11_NS0'
 '@S9S_MB_2U_LIB.S9S_MB_2U(SCH_1):NC_CPU0_MDFI_DIE11_NS0':
 C_SIGNAL='@s9s_mb_2u_lib.s9s_mb_2u(sch_1):nc_cpu0_mdfi_die11_ns0';
NODE_NAME     U2 CJ68
 '@S9S_MB_2U_LIB.S9S_MB_2U(SCH_1):PAGE17_I1@PURE_QUANTA.SOCKET4677_AZIF0045P001C01CS(CHIPS)':
 'RSVD106': CDS_PINID='RSVD106';
NET_NAME
'NC_CPU0_MDFI_DIE11_NS1'
 '@S9S_MB_2U_LIB.S9S_MB_2U(SCH_1):NC_CPU0_MDFI_DIE11_NS1':
 C_SIGNAL='@s9s_mb_2u_lib.s9s_mb_2u(sch_1):nc_cpu0_mdfi_die11_ns1';
NODE_NAME     U2 CK67
 '@S9S_MB_2U_LIB.S9S_MB_2U(SCH_1):PAGE17_I1@PURE_QUANTA.SOCKET4677_AZIF0045P001C01CS(CHIPS)':
 'RSVD112': CDS_PINID='RSVD112';
NET_NAME
'NC_CPU0_PE0_APROBE<0>'
 '@S9S_MB_2U_LIB.S9S_MB_2U(SCH_1):NC_CPU0_PE0_APROBE'<0>:
 C_SIGNAL='@s9s_mb_2u_lib.s9s_mb_2u(sch_1):nc_cpu0_pe0_aprobe(0)';
NODE_NAME     U2 BN21
 '@S9S_MB_2U_LIB.S9S_MB_2U(SCH_1):PAGE19_I1@PURE_QUANTA.SOCKET4677_AZIF0045P001C01CS(CHIPS)':
 'RSVD66': CDS_PINID='RSVD66';
NET_NAME
'NC_CPU0_PE0_APROBE<1>'
 '@S9S_MB_2U_LIB.S9S_MB_2U(SCH_1):NC_CPU0_PE0_APROBE'<1>:
 C_SIGNAL='@s9s_mb_2u_lib.s9s_mb_2u(sch_1):nc_cpu0_pe0_aprobe(1)';
NODE_NAME     U2 BL21
 '@S9S_MB_2U_LIB.S9S_MB_2U(SCH_1):PAGE19_I1@PURE_QUANTA.SOCKET4677_AZIF0045P001C01CS(CHIPS)':
 'RSVD62': CDS_PINID='RSVD62';
NET_NAME
'NC_CPU0_PE1_APROBE<0>'
 '@S9S_MB_2U_LIB.S9S_MB_2U(SCH_1):NC_CPU0_PE1_APROBE'<0>:
 C_SIGNAL='@s9s_mb_2u_lib.s9s_mb_2u(sch_1):nc_cpu0_pe1_aprobe(0)';
NODE_NAME     U2 CE21
 '@S9S_MB_2U_LIB.S9S_MB_2U(SCH_1):PAGE19_I1@PURE_QUANTA.SOCKET4677_AZIF0045P001C01CS(CHIPS)':
 'RSVD89': CDS_PINID='RSVD89';
NET_NAME
'NC_CPU0_PE1_APROBE<1>'
 '@S9S_MB_2U_LIB.S9S_MB_2U(SCH_1):NC_CPU0_PE1_APROBE'<1>:
 C_SIGNAL='@s9s_mb_2u_lib.s9s_mb_2u(sch_1):nc_cpu0_pe1_aprobe(1)';
NODE_NAME     U2 CC21
 '@S9S_MB_2U_LIB.S9S_MB_2U(SCH_1):PAGE19_I1@PURE_QUANTA.SOCKET4677_AZIF0045P001C01CS(CHIPS)':
 'RSVD79': CDS_PINID='RSVD79';
NET_NAME
'NC_CPU0_PE2_APROBE<0>'
 '@S9S_MB_2U_LIB.S9S_MB_2U(SCH_1):NC_CPU0_PE2_APROBE'<0>:
 C_SIGNAL='@s9s_mb_2u_lib.s9s_mb_2u(sch_1):nc_cpu0_pe2_aprobe(0)';
NODE_NAME     U2 CC23
 '@S9S_MB_2U_LIB.S9S_MB_2U(SCH_1):PAGE19_I1@PURE_QUANTA.SOCKET4677_AZIF0045P001C01CS(CHIPS)':
 'RSVD80': CDS_PINID='RSVD80';
NET_NAME
'NC_CPU0_PE2_APROBE<1>'
 '@S9S_MB_2U_LIB.S9S_MB_2U(SCH_1):NC_CPU0_PE2_APROBE'<1>:
 C_SIGNAL='@s9s_mb_2u_lib.s9s_mb_2u(sch_1):nc_cpu0_pe2_aprobe(1)';
NODE_NAME     U2 BW23
 '@S9S_MB_2U_LIB.S9S_MB_2U(SCH_1):PAGE19_I1@PURE_QUANTA.SOCKET4677_AZIF0045P001C01CS(CHIPS)':
 'RSVD75': CDS_PINID='RSVD75';
NET_NAME
'NC_CPU0_PE3_APROBE<0>'
 '@S9S_MB_2U_LIB.S9S_MB_2U(SCH_1):NC_CPU0_PE3_APROBE'<0>:
 C_SIGNAL='@s9s_mb_2u_lib.s9s_mb_2u(sch_1):nc_cpu0_pe3_aprobe(0)';
NODE_NAME     U2 CL68
 '@S9S_MB_2U_LIB.S9S_MB_2U(SCH_1):PAGE19_I1@PURE_QUANTA.SOCKET4677_AZIF0045P001C01CS(CHIPS)':
 'RSVD118': CDS_PINID='RSVD118';
NET_NAME
'NC_CPU0_PE3_APROBE<1>'
 '@S9S_MB_2U_LIB.S9S_MB_2U(SCH_1):NC_CPU0_PE3_APROBE'<1>:
 C_SIGNAL='@s9s_mb_2u_lib.s9s_mb_2u(sch_1):nc_cpu0_pe3_aprobe(1)';
NODE_NAME     U2 CM69
 '@S9S_MB_2U_LIB.S9S_MB_2U(SCH_1):PAGE19_I1@PURE_QUANTA.SOCKET4677_AZIF0045P001C01CS(CHIPS)':
 'RSVD122': CDS_PINID='RSVD122';
NET_NAME
'NC_CPU0_PE4_APROBE<0>'
 '@S9S_MB_2U_LIB.S9S_MB_2U(SCH_1):NC_CPU0_PE4_APROBE'<0>:
 C_SIGNAL='@s9s_mb_2u_lib.s9s_mb_2u(sch_1):nc_cpu0_pe4_aprobe(0)';
NODE_NAME     U2 AV67
 '@S9S_MB_2U_LIB.S9S_MB_2U(SCH_1):PAGE19_I1@PURE_QUANTA.SOCKET4677_AZIF0045P001C01CS(CHIPS)':
 'RSVD22': CDS_PINID='RSVD22';
NET_NAME
'NC_CPU0_PE4_APROBE<1>'
 '@S9S_MB_2U_LIB.S9S_MB_2U(SCH_1):NC_CPU0_PE4_APROBE'<1>:
 C_SIGNAL='@s9s_mb_2u_lib.s9s_mb_2u(sch_1):nc_cpu0_pe4_aprobe(1)';
NODE_NAME     U2 AU66
 '@S9S_MB_2U_LIB.S9S_MB_2U(SCH_1):PAGE19_I1@PURE_QUANTA.SOCKET4677_AZIF0045P001C01CS(CHIPS)':
 'RSVD13': CDS_PINID='RSVD13';
NET_NAME
'NC_CPU0_RSVD<144>'
 '@S9S_MB_2U_LIB.S9S_MB_2U(SCH_1):NC_CPU0_RSVD'<144>:
 C_SIGNAL='@s9s_mb_2u_lib.s9s_mb_2u(sch_1):nc_cpu0_rsvd(144)';
NODE_NAME     U2 CW68
 '@S9S_MB_2U_LIB.S9S_MB_2U(SCH_1):PAGE14_I1@PURE_QUANTA.SOCKET4677_AZIF0045P001C01CS(CHIPS)':
 'RSVD150': CDS_PINID='RSVD150';
NET_NAME
'NC_CPU0_SOC_SPARE0'
 '@S9S_MB_2U_LIB.S9S_MB_2U(SCH_1):NC_CPU0_SOC_SPARE0':
 C_SIGNAL='@s9s_mb_2u_lib.s9s_mb_2u(sch_1):nc_cpu0_soc_spare0';
NODE_NAME     U2 AY24
 '@S9S_MB_2U_LIB.S9S_MB_2U(SCH_1):PAGE17_I1@PURE_QUANTA.SOCKET4677_AZIF0045P001C01CS(CHIPS)':
 'RSVD26': CDS_PINID='RSVD26';
NET_NAME
'NC_CPU0_SOC_SPARE1'
 '@S9S_MB_2U_LIB.S9S_MB_2U(SCH_1):NC_CPU0_SOC_SPARE1':
 C_SIGNAL='@s9s_mb_2u_lib.s9s_mb_2u(sch_1):nc_cpu0_soc_spare1';
NODE_NAME     U2 BM65
 '@S9S_MB_2U_LIB.S9S_MB_2U(SCH_1):PAGE17_I1@PURE_QUANTA.SOCKET4677_AZIF0045P001C01CS(CHIPS)':
 'RSVD65': CDS_PINID='RSVD65';
NET_NAME
'NC_CPU0_SOC_SPARE4'
 '@S9S_MB_2U_LIB.S9S_MB_2U(SCH_1):NC_CPU0_SOC_SPARE4':
 C_SIGNAL='@s9s_mb_2u_lib.s9s_mb_2u(sch_1):nc_cpu0_soc_spare4';
NODE_NAME     U2 BA25
 '@S9S_MB_2U_LIB.S9S_MB_2U(SCH_1):PAGE17_I1@PURE_QUANTA.SOCKET4677_AZIF0045P001C01CS(CHIPS)':
 'RSVD31': CDS_PINID='RSVD31';
NET_NAME
'NC_CPU0_SOC_SPARE5'
 '@S9S_MB_2U_LIB.S9S_MB_2U(SCH_1):NC_CPU0_SOC_SPARE5':
 C_SIGNAL='@s9s_mb_2u_lib.s9s_mb_2u(sch_1):nc_cpu0_soc_spare5';
NODE_NAME     U2 BP65
 '@S9S_MB_2U_LIB.S9S_MB_2U(SCH_1):PAGE17_I1@PURE_QUANTA.SOCKET4677_AZIF0045P001C01CS(CHIPS)':
 'RSVD68': CDS_PINID='RSVD68';
NET_NAME
'NC_CPU0_THERMADA'
 '@S9S_MB_2U_LIB.S9S_MB_2U(SCH_1):NC_CPU0_THERMADA':
 C_SIGNAL='@s9s_mb_2u_lib.s9s_mb_2u(sch_1):nc_cpu0_thermada';
NODE_NAME     U2 AV40
 '@S9S_MB_2U_LIB.S9S_MB_2U(SCH_1):PAGE16_I1@PURE_QUANTA.SOCKET4677_AZIF0045P001C01CS(CHIPS)':
 'RSVD18': CDS_PINID='RSVD18';
NET_NAME
'NC_CPU0_THERMADC'
 '@S9S_MB_2U_LIB.S9S_MB_2U(SCH_1):NC_CPU0_THERMADC':
 C_SIGNAL='@s9s_mb_2u_lib.s9s_mb_2u(sch_1):nc_cpu0_thermadc';
NODE_NAME     U2 AV38
 '@S9S_MB_2U_LIB.S9S_MB_2U(SCH_1):PAGE16_I1@PURE_QUANTA.SOCKET4677_AZIF0045P001C01CS(CHIPS)':
 'RSVD17': CDS_PINID='RSVD17';
NET_NAME
'NC_CPU0_UPI0_APROBE<0>'
 '@S9S_MB_2U_LIB.S9S_MB_2U(SCH_1):NC_CPU0_UPI0_APROBE'<0>:
 C_SIGNAL='@s9s_mb_2u_lib.s9s_mb_2u(sch_1):nc_cpu0_upi0_aprobe(0)';
NODE_NAME     U2 AN17
 '@S9S_MB_2U_LIB.S9S_MB_2U(SCH_1):PAGE19_I1@PURE_QUANTA.SOCKET4677_AZIF0045P001C01CS(CHIPS)':
 'RSVD2': CDS_PINID='RSVD2';
NET_NAME
'NC_CPU0_UPI0_APROBE<1>'
 '@S9S_MB_2U_LIB.S9S_MB_2U(SCH_1):NC_CPU0_UPI0_APROBE'<1>:
 C_SIGNAL='@s9s_mb_2u_lib.s9s_mb_2u(sch_1):nc_cpu0_upi0_aprobe(1)';
NODE_NAME     U2 AR17
 '@S9S_MB_2U_LIB.S9S_MB_2U(SCH_1):PAGE19_I1@PURE_QUANTA.SOCKET4677_AZIF0045P001C01CS(CHIPS)':
 'RSVD3': CDS_PINID='RSVD3';
NET_NAME
'NC_CPU0_UPI1_APROBE<0>'
 '@S9S_MB_2U_LIB.S9S_MB_2U(SCH_1):NC_CPU0_UPI1_APROBE'<0>:
 C_SIGNAL='@s9s_mb_2u_lib.s9s_mb_2u(sch_1):nc_cpu0_upi1_aprobe(0)';
NODE_NAME     U2 BV22
 '@S9S_MB_2U_LIB.S9S_MB_2U(SCH_1):PAGE19_I1@PURE_QUANTA.SOCKET4677_AZIF0045P001C01CS(CHIPS)':
 'RSVD73': CDS_PINID='RSVD73';
NET_NAME
'NC_CPU0_UPI1_APROBE<1>'
 '@S9S_MB_2U_LIB.S9S_MB_2U(SCH_1):NC_CPU0_UPI1_APROBE'<1>:
 C_SIGNAL='@s9s_mb_2u_lib.s9s_mb_2u(sch_1):nc_cpu0_upi1_aprobe(1)';
NODE_NAME     U2 CA23
 '@S9S_MB_2U_LIB.S9S_MB_2U(SCH_1):PAGE19_I1@PURE_QUANTA.SOCKET4677_AZIF0045P001C01CS(CHIPS)':
 'RSVD78': CDS_PINID='RSVD78';
NET_NAME
'NC_CPU0_UPI2_APROBE<0>'
 '@S9S_MB_2U_LIB.S9S_MB_2U(SCH_1):NC_CPU0_UPI2_APROBE'<0>:
 C_SIGNAL='@s9s_mb_2u_lib.s9s_mb_2u(sch_1):nc_cpu0_upi2_aprobe(0)';
NODE_NAME     U2 AU68
 '@S9S_MB_2U_LIB.S9S_MB_2U(SCH_1):PAGE19_I1@PURE_QUANTA.SOCKET4677_AZIF0045P001C01CS(CHIPS)':
 'RSVD14': CDS_PINID='RSVD14';
NET_NAME
'NC_CPU0_UPI2_APROBE<1>'
 '@S9S_MB_2U_LIB.S9S_MB_2U(SCH_1):NC_CPU0_UPI2_APROBE'<1>:
 C_SIGNAL='@s9s_mb_2u_lib.s9s_mb_2u(sch_1):nc_cpu0_upi2_aprobe(1)';
NODE_NAME     U2 AT67
 '@S9S_MB_2U_LIB.S9S_MB_2U(SCH_1):PAGE19_I1@PURE_QUANTA.SOCKET4677_AZIF0045P001C01CS(CHIPS)':
 'RSVD5': CDS_PINID='RSVD5';
NET_NAME
'NC_CPU0_UPI3_APROBE<0>'
 '@S9S_MB_2U_LIB.S9S_MB_2U(SCH_1):NC_CPU0_UPI3_APROBE'<0>:
 C_SIGNAL='@s9s_mb_2u_lib.s9s_mb_2u(sch_1):nc_cpu0_upi3_aprobe(0)';
NODE_NAME     U2 CP69
 '@S9S_MB_2U_LIB.S9S_MB_2U(SCH_1):PAGE19_I1@PURE_QUANTA.SOCKET4677_AZIF0045P001C01CS(CHIPS)':
 'RSVD130': CDS_PINID='RSVD130';
NET_NAME
'NC_CPU0_UPI3_APROBE<1>'
 '@S9S_MB_2U_LIB.S9S_MB_2U(SCH_1):NC_CPU0_UPI3_APROBE'<1>:
 C_SIGNAL='@s9s_mb_2u_lib.s9s_mb_2u(sch_1):nc_cpu0_upi3_aprobe(1)';
NODE_NAME     U2 CR68
 '@S9S_MB_2U_LIB.S9S_MB_2U(SCH_1):PAGE19_I1@PURE_QUANTA.SOCKET4677_AZIF0045P001C01CS(CHIPS)':
 'RSVD135': CDS_PINID='RSVD135';
NET_NAME
'NC_CPU0_VIEWPIN_DIE00<0>'
 '@S9S_MB_2U_LIB.S9S_MB_2U(SCH_1):NC_CPU0_VIEWPIN_DIE00'<0>:
 C_SIGNAL='@s9s_mb_2u_lib.s9s_mb_2u(sch_1):nc_cpu0_viewpin_die00(0)';
NODE_NAME     U2 AY26
 '@S9S_MB_2U_LIB.S9S_MB_2U(SCH_1):PAGE14_I1@PURE_QUANTA.SOCKET4677_AZIF0045P001C01CS(CHIPS)':
 'RSVD27': CDS_PINID='RSVD27';
NET_NAME
'NC_CPU0_VIEWPIN_DIE00<1>'
 '@S9S_MB_2U_LIB.S9S_MB_2U(SCH_1):NC_CPU0_VIEWPIN_DIE00'<1>:
 C_SIGNAL='@s9s_mb_2u_lib.s9s_mb_2u(sch_1):nc_cpu0_viewpin_die00(1)';
NODE_NAME     U2 AT24
 '@S9S_MB_2U_LIB.S9S_MB_2U(SCH_1):PAGE14_I1@PURE_QUANTA.SOCKET4677_AZIF0045P001C01CS(CHIPS)':
 'RSVD4': CDS_PINID='RSVD4';
NET_NAME
'NC_CPU0_VIEWPIN_DIE00<2>'
 '@S9S_MB_2U_LIB.S9S_MB_2U(SCH_1):NC_CPU0_VIEWPIN_DIE00'<2>:
 C_SIGNAL='@s9s_mb_2u_lib.s9s_mb_2u(sch_1):nc_cpu0_viewpin_die00(2)';
NODE_NAME     U2 AU25
 '@S9S_MB_2U_LIB.S9S_MB_2U(SCH_1):PAGE14_I1@PURE_QUANTA.SOCKET4677_AZIF0045P001C01CS(CHIPS)':
 'RSVD6': CDS_PINID='RSVD6';
NET_NAME
'NC_CPU0_VIEWPIN_DIE00<3>'
 '@S9S_MB_2U_LIB.S9S_MB_2U(SCH_1):NC_CPU0_VIEWPIN_DIE00'<3>:
 C_SIGNAL='@s9s_mb_2u_lib.s9s_mb_2u(sch_1):nc_cpu0_viewpin_die00(3)';
NODE_NAME     U2 AV26
 '@S9S_MB_2U_LIB.S9S_MB_2U(SCH_1):PAGE14_I1@PURE_QUANTA.SOCKET4677_AZIF0045P001C01CS(CHIPS)':
 'RSVD15': CDS_PINID='RSVD15';
NET_NAME
'NC_CPU0_VIEWPIN_DIE01<0>'
 '@S9S_MB_2U_LIB.S9S_MB_2U(SCH_1):NC_CPU0_VIEWPIN_DIE01'<0>:
 C_SIGNAL='@s9s_mb_2u_lib.s9s_mb_2u(sch_1):nc_cpu0_viewpin_die01(0)';
NODE_NAME     U2 BP69
 '@S9S_MB_2U_LIB.S9S_MB_2U(SCH_1):PAGE14_I1@PURE_QUANTA.SOCKET4677_AZIF0045P001C01CS(CHIPS)':
 'RSVD70': CDS_PINID='RSVD70';
NET_NAME
'NC_CPU0_VIEWPIN_DIE01<1>'
 '@S9S_MB_2U_LIB.S9S_MB_2U(SCH_1):NC_CPU0_VIEWPIN_DIE01'<1>:
 C_SIGNAL='@s9s_mb_2u_lib.s9s_mb_2u(sch_1):nc_cpu0_viewpin_die01(1)';
NODE_NAME     U2 BP67
 '@S9S_MB_2U_LIB.S9S_MB_2U(SCH_1):PAGE14_I1@PURE_QUANTA.SOCKET4677_AZIF0045P001C01CS(CHIPS)':
 'RSVD69': CDS_PINID='RSVD69';
NET_NAME
'NC_CPU0_VIEWPIN_DIE01<2>'
 '@S9S_MB_2U_LIB.S9S_MB_2U(SCH_1):NC_CPU0_VIEWPIN_DIE01'<2>:
 C_SIGNAL='@s9s_mb_2u_lib.s9s_mb_2u(sch_1):nc_cpu0_viewpin_die01(2)';
NODE_NAME     U2 AY65
 '@S9S_MB_2U_LIB.S9S_MB_2U(SCH_1):PAGE14_I1@PURE_QUANTA.SOCKET4677_AZIF0045P001C01CS(CHIPS)':
 'RSVD29': CDS_PINID='RSVD29';
NET_NAME
'NC_CPU0_VIEWPIN_DIE01<3>'
 '@S9S_MB_2U_LIB.S9S_MB_2U(SCH_1):NC_CPU0_VIEWPIN_DIE01'<3>:
 C_SIGNAL='@s9s_mb_2u_lib.s9s_mb_2u(sch_1):nc_cpu0_viewpin_die01(3)';
NODE_NAME     U2 BJ70
 '@S9S_MB_2U_LIB.S9S_MB_2U(SCH_1):PAGE14_I1@PURE_QUANTA.SOCKET4677_AZIF0045P001C01CS(CHIPS)':
 'RSVD59': CDS_PINID='RSVD59';
NET_NAME
'NC_CPU0_VIEWPIN_DIE10<0>'
 '@S9S_MB_2U_LIB.S9S_MB_2U(SCH_1):NC_CPU0_VIEWPIN_DIE10'<0>:
 C_SIGNAL='@s9s_mb_2u_lib.s9s_mb_2u(sch_1):nc_cpu0_viewpin_die10(0)';
NODE_NAME     U2 CR23
 '@S9S_MB_2U_LIB.S9S_MB_2U(SCH_1):PAGE14_I1@PURE_QUANTA.SOCKET4677_AZIF0045P001C01CS(CHIPS)':
 'RSVD132': CDS_PINID='RSVD132';
NET_NAME
'NC_CPU0_VIEWPIN_DIE10<1>'
 '@S9S_MB_2U_LIB.S9S_MB_2U(SCH_1):NC_CPU0_VIEWPIN_DIE10'<1>:
 C_SIGNAL='@s9s_mb_2u_lib.s9s_mb_2u(sch_1):nc_cpu0_viewpin_die10(1)';
NODE_NAME     U2 CW25
 '@S9S_MB_2U_LIB.S9S_MB_2U(SCH_1):PAGE14_I1@PURE_QUANTA.SOCKET4677_AZIF0045P001C01CS(CHIPS)':
 'RSVD146': CDS_PINID='RSVD146';
NET_NAME
'NC_CPU0_VIEWPIN_DIE10<2>'
 '@S9S_MB_2U_LIB.S9S_MB_2U(SCH_1):NC_CPU0_VIEWPIN_DIE10'<2>:
 C_SIGNAL='@s9s_mb_2u_lib.s9s_mb_2u(sch_1):nc_cpu0_viewpin_die10(2)';
NODE_NAME     U2 CV24
 '@S9S_MB_2U_LIB.S9S_MB_2U(SCH_1):PAGE14_I1@PURE_QUANTA.SOCKET4677_AZIF0045P001C01CS(CHIPS)':
 'RSVD141': CDS_PINID='RSVD141';
NET_NAME
'NC_CPU0_VIEWPIN_DIE10<3>'
 '@S9S_MB_2U_LIB.S9S_MB_2U(SCH_1):NC_CPU0_VIEWPIN_DIE10'<3>:
 C_SIGNAL='@s9s_mb_2u_lib.s9s_mb_2u(sch_1):nc_cpu0_viewpin_die10(3)';
NODE_NAME     U2 CW23
 '@S9S_MB_2U_LIB.S9S_MB_2U(SCH_1):PAGE14_I1@PURE_QUANTA.SOCKET4677_AZIF0045P001C01CS(CHIPS)':
 'RSVD145': CDS_PINID='RSVD145';
NET_NAME
'NC_CPU0_VIEWPIN_DIE11<0>'
 '@S9S_MB_2U_LIB.S9S_MB_2U(SCH_1):NC_CPU0_VIEWPIN_DIE11'<0>:
 C_SIGNAL='@s9s_mb_2u_lib.s9s_mb_2u(sch_1):nc_cpu0_viewpin_die11(0)';
NODE_NAME     U2 CJ62
 '@S9S_MB_2U_LIB.S9S_MB_2U(SCH_1):PAGE14_I1@PURE_QUANTA.SOCKET4677_AZIF0045P001C01CS(CHIPS)':
 'RSVD104': CDS_PINID='RSVD104';
NET_NAME
'NC_CPU0_VIEWPIN_DIE11<1>'
 '@S9S_MB_2U_LIB.S9S_MB_2U(SCH_1):NC_CPU0_VIEWPIN_DIE11'<1>:
 C_SIGNAL='@s9s_mb_2u_lib.s9s_mb_2u(sch_1):nc_cpu0_viewpin_die11(1)';
NODE_NAME     U2 CN62
 '@S9S_MB_2U_LIB.S9S_MB_2U(SCH_1):PAGE14_I1@PURE_QUANTA.SOCKET4677_AZIF0045P001C01CS(CHIPS)':
 'RSVD126': CDS_PINID='RSVD126';
NET_NAME
'NC_CPU0_VIEWPIN_DIE11<2>'
 '@S9S_MB_2U_LIB.S9S_MB_2U(SCH_1):NC_CPU0_VIEWPIN_DIE11'<2>:
 C_SIGNAL='@s9s_mb_2u_lib.s9s_mb_2u(sch_1):nc_cpu0_viewpin_die11(2)';
NODE_NAME     U2 CM63
 '@S9S_MB_2U_LIB.S9S_MB_2U(SCH_1):PAGE14_I1@PURE_QUANTA.SOCKET4677_AZIF0045P001C01CS(CHIPS)':
 'RSVD121': CDS_PINID='RSVD121';
NET_NAME
'NC_CPU0_VIEWPIN_DIE11<3>'
 '@S9S_MB_2U_LIB.S9S_MB_2U(SCH_1):NC_CPU0_VIEWPIN_DIE11'<3>:
 C_SIGNAL='@s9s_mb_2u_lib.s9s_mb_2u(sch_1):nc_cpu0_viewpin_die11(3)';
NODE_NAME     U2 CL64
 '@S9S_MB_2U_LIB.S9S_MB_2U(SCH_1):PAGE14_I1@PURE_QUANTA.SOCKET4677_AZIF0045P001C01CS(CHIPS)':
 'RSVD116': CDS_PINID='RSVD116';
NET_NAME
'NC_CPU0_VIEWPIN_GNR0'
 '@S9S_MB_2U_LIB.S9S_MB_2U(SCH_1):NC_CPU0_VIEWPIN_GNR0':
 C_SIGNAL='@s9s_mb_2u_lib.s9s_mb_2u(sch_1):nc_cpu0_viewpin_gnr0';
NODE_NAME     U2 CT26
 '@S9S_MB_2U_LIB.S9S_MB_2U(SCH_1):PAGE17_I1@PURE_QUANTA.SOCKET4677_AZIF0045P001C01CS(CHIPS)':
 'RSVD138': CDS_PINID='RSVD138';
NET_NAME
'NC_CPU0_VIEWPIN_GNR1'
 '@S9S_MB_2U_LIB.S9S_MB_2U(SCH_1):NC_CPU0_VIEWPIN_GNR1':
 C_SIGNAL='@s9s_mb_2u_lib.s9s_mb_2u(sch_1):nc_cpu0_viewpin_gnr1';
NODE_NAME     U2 CW58
 '@S9S_MB_2U_LIB.S9S_MB_2U(SCH_1):PAGE17_I1@PURE_QUANTA.SOCKET4677_AZIF0045P001C01CS(CHIPS)':
 'RSVD149': CDS_PINID='RSVD149';
NET_NAME
'NC_CPU0_VIEWPIN_GNR2'
 '@S9S_MB_2U_LIB.S9S_MB_2U(SCH_1):NC_CPU0_VIEWPIN_GNR2':
 C_SIGNAL='@s9s_mb_2u_lib.s9s_mb_2u(sch_1):nc_cpu0_viewpin_gnr2';
NODE_NAME     U2 CR25
 '@S9S_MB_2U_LIB.S9S_MB_2U(SCH_1):PAGE17_I1@PURE_QUANTA.SOCKET4677_AZIF0045P001C01CS(CHIPS)':
 'RSVD133': CDS_PINID='RSVD133';
NET_NAME
'NC_CPU0_VIEWPIN_GNR3'
 '@S9S_MB_2U_LIB.S9S_MB_2U(SCH_1):NC_CPU0_VIEWPIN_GNR3':
 C_SIGNAL='@s9s_mb_2u_lib.s9s_mb_2u(sch_1):nc_cpu0_viewpin_gnr3';
NODE_NAME     U2 CY57
 '@S9S_MB_2U_LIB.S9S_MB_2U(SCH_1):PAGE17_I1@PURE_QUANTA.SOCKET4677_AZIF0045P001C01CS(CHIPS)':
 'RSVD154': CDS_PINID='RSVD154';
NET_NAME
'NC_CPU1_DDR01_VIEWDIG0'
 '@S9S_MB_2U_LIB.S9S_MB_2U(SCH_1):NC_CPU1_DDR01_VIEWDIG0':
 C_SIGNAL='@s9s_mb_2u_lib.s9s_mb_2u(sch_1):nc_cpu1_ddr01_viewdig0';
NODE_NAME     U1 AU58
 '@S9S_MB_2U_LIB.S9S_MB_2U(SCH_1):PAGE47_I16@PURE_QUANTA.SOCKET4677_AZIF0045P001C01CS(CHIPS)':
 'RSVD10': CDS_PINID='RSVD10';
NET_NAME
'NC_CPU1_DDR01_VIEWDIG1'
 '@S9S_MB_2U_LIB.S9S_MB_2U(SCH_1):NC_CPU1_DDR01_VIEWDIG1':
 C_SIGNAL='@s9s_mb_2u_lib.s9s_mb_2u(sch_1):nc_cpu1_ddr01_viewdig1';
NODE_NAME     U1 AU56
 '@S9S_MB_2U_LIB.S9S_MB_2U(SCH_1):PAGE47_I16@PURE_QUANTA.SOCKET4677_AZIF0045P001C01CS(CHIPS)':
 'RSVD9': CDS_PINID='RSVD9';
NET_NAME
'NC_CPU1_DDR23_VIEWDIG0'
 '@S9S_MB_2U_LIB.S9S_MB_2U(SCH_1):NC_CPU1_DDR23_VIEWDIG0':
 C_SIGNAL='@s9s_mb_2u_lib.s9s_mb_2u(sch_1):nc_cpu1_ddr23_viewdig0';
NODE_NAME     U1 AV32
 '@S9S_MB_2U_LIB.S9S_MB_2U(SCH_1):PAGE47_I16@PURE_QUANTA.SOCKET4677_AZIF0045P001C01CS(CHIPS)':
 'RSVD16': CDS_PINID='RSVD16';
NET_NAME
'NC_CPU1_DDR23_VIEWDIG1'
 '@S9S_MB_2U_LIB.S9S_MB_2U(SCH_1):NC_CPU1_DDR23_VIEWDIG1':
 C_SIGNAL='@s9s_mb_2u_lib.s9s_mb_2u(sch_1):nc_cpu1_ddr23_viewdig1';
NODE_NAME     U1 AU33
 '@S9S_MB_2U_LIB.S9S_MB_2U(SCH_1):PAGE47_I16@PURE_QUANTA.SOCKET4677_AZIF0045P001C01CS(CHIPS)':
 'RSVD7': CDS_PINID='RSVD7';
NET_NAME
'NC_CPU1_DDR45_VIEWDIG0'
 '@S9S_MB_2U_LIB.S9S_MB_2U(SCH_1):NC_CPU1_DDR45_VIEWDIG0':
 C_SIGNAL='@s9s_mb_2u_lib.s9s_mb_2u(sch_1):nc_cpu1_ddr45_viewdig0';
NODE_NAME     U1 CY24
 '@S9S_MB_2U_LIB.S9S_MB_2U(SCH_1):PAGE47_I16@PURE_QUANTA.SOCKET4677_AZIF0045P001C01CS(CHIPS)':
 'RSVD151': CDS_PINID='RSVD151';
NET_NAME
'NC_CPU1_DDR45_VIEWDIG1'
 '@S9S_MB_2U_LIB.S9S_MB_2U(SCH_1):NC_CPU1_DDR45_VIEWDIG1':
 C_SIGNAL='@s9s_mb_2u_lib.s9s_mb_2u(sch_1):nc_cpu1_ddr45_viewdig1';
NODE_NAME     U1 CY38
 '@S9S_MB_2U_LIB.S9S_MB_2U(SCH_1):PAGE47_I16@PURE_QUANTA.SOCKET4677_AZIF0045P001C01CS(CHIPS)':
 'RSVD152': CDS_PINID='RSVD152';
NET_NAME
'NC_CPU1_DDR67_VIEWDIG0'
 '@S9S_MB_2U_LIB.S9S_MB_2U(SCH_1):NC_CPU1_DDR67_VIEWDIG0':
 C_SIGNAL='@s9s_mb_2u_lib.s9s_mb_2u(sch_1):nc_cpu1_ddr67_viewdig0';
NODE_NAME     U1 DA45
 '@S9S_MB_2U_LIB.S9S_MB_2U(SCH_1):PAGE47_I16@PURE_QUANTA.SOCKET4677_AZIF0045P001C01CS(CHIPS)':
 'RSVD158': CDS_PINID='RSVD158';
NET_NAME
'NC_CPU1_DDR67_VIEWDIG1'
 '@S9S_MB_2U_LIB.S9S_MB_2U(SCH_1):NC_CPU1_DDR67_VIEWDIG1':
 C_SIGNAL='@s9s_mb_2u_lib.s9s_mb_2u(sch_1):nc_cpu1_ddr67_viewdig1';
NODE_NAME     U1 CY49
 '@S9S_MB_2U_LIB.S9S_MB_2U(SCH_1):PAGE47_I16@PURE_QUANTA.SOCKET4677_AZIF0045P001C01CS(CHIPS)':
 'RSVD153': CDS_PINID='RSVD153';
NET_NAME
'NC_CPU1_DMI_APROBE<0>'
 '@S9S_MB_2U_LIB.S9S_MB_2U(SCH_1):NC_CPU1_DMI_APROBE'<0>:
 C_SIGNAL='@s9s_mb_2u_lib.s9s_mb_2u(sch_1):nc_cpu1_dmi_aprobe(0)';
NODE_NAME     U1 CA21
 '@S9S_MB_2U_LIB.S9S_MB_2U(SCH_1):PAGE50_I23@PURE_QUANTA.SOCKET4677_AZIF0045P001C01CS(CHIPS)':
 'RSVD77': CDS_PINID='RSVD77';
NET_NAME
'NC_CPU1_DMI_APROBE<1>'
 '@S9S_MB_2U_LIB.S9S_MB_2U(SCH_1):NC_CPU1_DMI_APROBE'<1>:
 C_SIGNAL='@s9s_mb_2u_lib.s9s_mb_2u(sch_1):nc_cpu1_dmi_aprobe(1)';
NODE_NAME     U1 BW21
 '@S9S_MB_2U_LIB.S9S_MB_2U(SCH_1):PAGE50_I23@PURE_QUANTA.SOCKET4677_AZIF0045P001C01CS(CHIPS)':
 'RSVD74': CDS_PINID='RSVD74';
NET_NAME
'NC_CPU1_HBM0_VIEWDIG0'
 '@S9S_MB_2U_LIB.S9S_MB_2U(SCH_1):NC_CPU1_HBM0_VIEWDIG0':
 C_SIGNAL='@s9s_mb_2u_lib.s9s_mb_2u(sch_1):nc_cpu1_hbm0_viewdig0';
NODE_NAME     U1 U17
 '@S9S_MB_2U_LIB.S9S_MB_2U(SCH_1):PAGE48_I1@PURE_QUANTA.SOCKET4677_AZIF0045P001C01CS(CHIPS)':
 'RSVD164': CDS_PINID='RSVD164';
NET_NAME
'NC_CPU1_HBM0_VIEWDIG1'
 '@S9S_MB_2U_LIB.S9S_MB_2U(SCH_1):NC_CPU1_HBM0_VIEWDIG1':
 C_SIGNAL='@s9s_mb_2u_lib.s9s_mb_2u(sch_1):nc_cpu1_hbm0_viewdig1';
NODE_NAME     U1 EG17
 '@S9S_MB_2U_LIB.S9S_MB_2U(SCH_1):PAGE48_I1@PURE_QUANTA.SOCKET4677_AZIF0045P001C01CS(CHIPS)':
 'RSVD160': CDS_PINID='RSVD160';
NET_NAME
'NC_CPU1_HBM1_VIEWDIG0'
 '@S9S_MB_2U_LIB.S9S_MB_2U(SCH_1):NC_CPU1_HBM1_VIEWDIG0':
 C_SIGNAL='@s9s_mb_2u_lib.s9s_mb_2u(sch_1):nc_cpu1_hbm1_viewdig0';
NODE_NAME     U1 W17
 '@S9S_MB_2U_LIB.S9S_MB_2U(SCH_1):PAGE48_I1@PURE_QUANTA.SOCKET4677_AZIF0045P001C01CS(CHIPS)':
 'RSVD165': CDS_PINID='RSVD165';
NET_NAME
'NC_CPU1_HBM1_VIEWDIG1'
 '@S9S_MB_2U_LIB.S9S_MB_2U(SCH_1):NC_CPU1_HBM1_VIEWDIG1':
 C_SIGNAL='@s9s_mb_2u_lib.s9s_mb_2u(sch_1):nc_cpu1_hbm1_viewdig1';
NODE_NAME     U1 CW41
 '@S9S_MB_2U_LIB.S9S_MB_2U(SCH_1):PAGE48_I1@PURE_QUANTA.SOCKET4677_AZIF0045P001C01CS(CHIPS)':
 'RSVD147': CDS_PINID='RSVD147';
NET_NAME
'NC_CPU1_HBM2_VIEWDIG0'
 '@S9S_MB_2U_LIB.S9S_MB_2U(SCH_1):NC_CPU1_HBM2_VIEWDIG0':
 C_SIGNAL='@s9s_mb_2u_lib.s9s_mb_2u(sch_1):nc_cpu1_hbm2_viewdig0';
NODE_NAME     U1 AC78
 '@S9S_MB_2U_LIB.S9S_MB_2U(SCH_1):PAGE48_I1@PURE_QUANTA.SOCKET4677_AZIF0045P001C01CS(CHIPS)':
 'RSVD0': CDS_PINID='RSVD0';
NET_NAME
'NC_CPU1_HBM2_VIEWDIG1'
 '@S9S_MB_2U_LIB.S9S_MB_2U(SCH_1):NC_CPU1_HBM2_VIEWDIG1':
 C_SIGNAL='@s9s_mb_2u_lib.s9s_mb_2u(sch_1):nc_cpu1_hbm2_viewdig1';
NODE_NAME     U1 AD77
 '@S9S_MB_2U_LIB.S9S_MB_2U(SCH_1):PAGE48_I1@PURE_QUANTA.SOCKET4677_AZIF0045P001C01CS(CHIPS)':
 'RSVD1': CDS_PINID='RSVD1';
NET_NAME
'NC_CPU1_HBM3_VIEWDIG0'
 '@S9S_MB_2U_LIB.S9S_MB_2U(SCH_1):NC_CPU1_HBM3_VIEWDIG0':
 C_SIGNAL='@s9s_mb_2u_lib.s9s_mb_2u(sch_1):nc_cpu1_hbm3_viewdig0';
NODE_NAME     U1 BG78
 '@S9S_MB_2U_LIB.S9S_MB_2U(SCH_1):PAGE48_I1@PURE_QUANTA.SOCKET4677_AZIF0045P001C01CS(CHIPS)':
 'RSVD54': CDS_PINID='RSVD54';
NET_NAME
'NC_CPU1_HBM3_VIEWDIG1'
 '@S9S_MB_2U_LIB.S9S_MB_2U(SCH_1):NC_CPU1_HBM3_VIEWDIG1':
 C_SIGNAL='@s9s_mb_2u_lib.s9s_mb_2u(sch_1):nc_cpu1_hbm3_viewdig1';
NODE_NAME     U1 BL60
 '@S9S_MB_2U_LIB.S9S_MB_2U(SCH_1):PAGE48_I1@PURE_QUANTA.SOCKET4677_AZIF0045P001C01CS(CHIPS)':
 'RSVD63': CDS_PINID='RSVD63';
NET_NAME
'NC_CPU1_LGSSPARE0'
 '@S9S_MB_2U_LIB.S9S_MB_2U(SCH_1):NC_CPU1_LGSSPARE0':
 C_SIGNAL='@s9s_mb_2u_lib.s9s_mb_2u(sch_1):nc_cpu1_lgsspare0';
NODE_NAME     U1 CR60
 '@S9S_MB_2U_LIB.S9S_MB_2U(SCH_1):PAGE47_I16@PURE_QUANTA.SOCKET4677_AZIF0045P001C01CS(CHIPS)':
 'RSVD134': CDS_PINID='RSVD134';
NET_NAME
'NC_CPU1_LGSSPARE1'
 '@S9S_MB_2U_LIB.S9S_MB_2U(SCH_1):NC_CPU1_LGSSPARE1':
 C_SIGNAL='@s9s_mb_2u_lib.s9s_mb_2u(sch_1):nc_cpu1_lgsspare1';
NODE_NAME     U1 CN60
 '@S9S_MB_2U_LIB.S9S_MB_2U(SCH_1):PAGE47_I16@PURE_QUANTA.SOCKET4677_AZIF0045P001C01CS(CHIPS)':
 'RSVD125': CDS_PINID='RSVD125';
NET_NAME
'NC_CPU1_LGSSPARE2'
 '@S9S_MB_2U_LIB.S9S_MB_2U(SCH_1):NC_CPU1_LGSSPARE2':
 C_SIGNAL='@s9s_mb_2u_lib.s9s_mb_2u(sch_1):nc_cpu1_lgsspare2';
NODE_NAME     U1 CU62
 '@S9S_MB_2U_LIB.S9S_MB_2U(SCH_1):PAGE47_I16@PURE_QUANTA.SOCKET4677_AZIF0045P001C01CS(CHIPS)':
 'RSVD139': CDS_PINID='RSVD139';
NET_NAME
'NC_CPU1_LGSSPARE3'
 '@S9S_MB_2U_LIB.S9S_MB_2U(SCH_1):NC_CPU1_LGSSPARE3':
 C_SIGNAL='@s9s_mb_2u_lib.s9s_mb_2u(sch_1):nc_cpu1_lgsspare3';
NODE_NAME     U1 CE62
 '@S9S_MB_2U_LIB.S9S_MB_2U(SCH_1):PAGE47_I16@PURE_QUANTA.SOCKET4677_AZIF0045P001C01CS(CHIPS)':
 'RSVD90': CDS_PINID='RSVD90';
NET_NAME
'NC_CPU1_LGSSPARE4'
 '@S9S_MB_2U_LIB.S9S_MB_2U(SCH_1):NC_CPU1_LGSSPARE4':
 C_SIGNAL='@s9s_mb_2u_lib.s9s_mb_2u(sch_1):nc_cpu1_lgsspare4';
NODE_NAME     U1 CC64
 '@S9S_MB_2U_LIB.S9S_MB_2U(SCH_1):PAGE47_I16@PURE_QUANTA.SOCKET4677_AZIF0045P001C01CS(CHIPS)':
 'RSVD81': CDS_PINID='RSVD81';
NET_NAME
'NC_CPU1_LGSSPARE5'
 '@S9S_MB_2U_LIB.S9S_MB_2U(SCH_1):NC_CPU1_LGSSPARE5':
 C_SIGNAL='@s9s_mb_2u_lib.s9s_mb_2u(sch_1):nc_cpu1_lgsspare5';
NODE_NAME     U1 CP61
 '@S9S_MB_2U_LIB.S9S_MB_2U(SCH_1):PAGE47_I16@PURE_QUANTA.SOCKET4677_AZIF0045P001C01CS(CHIPS)':
 'RSVD129': CDS_PINID='RSVD129';
NET_NAME
'NC_CPU1_MDFI_DIE00_EW0'
 '@S9S_MB_2U_LIB.S9S_MB_2U(SCH_1):NC_CPU1_MDFI_DIE00_EW0':
 C_SIGNAL='@s9s_mb_2u_lib.s9s_mb_2u(sch_1):nc_cpu1_mdfi_die00_ew0';
NODE_NAME     U1 BP22
 '@S9S_MB_2U_LIB.S9S_MB_2U(SCH_1):PAGE48_I1@PURE_QUANTA.SOCKET4677_AZIF0045P001C01CS(CHIPS)':
 'RSVD67': CDS_PINID='RSVD67';
NET_NAME
'NC_CPU1_MDFI_DIE00_EW1'
 '@S9S_MB_2U_LIB.S9S_MB_2U(SCH_1):NC_CPU1_MDFI_DIE00_EW1':
 C_SIGNAL='@s9s_mb_2u_lib.s9s_mb_2u(sch_1):nc_cpu1_mdfi_die00_ew1';
NODE_NAME     U1 BR21
 '@S9S_MB_2U_LIB.S9S_MB_2U(SCH_1):PAGE48_I1@PURE_QUANTA.SOCKET4677_AZIF0045P001C01CS(CHIPS)':
 'RSVD71': CDS_PINID='RSVD71';
NET_NAME
'NC_CPU1_MDFI_DIE00_NS0'
 '@S9S_MB_2U_LIB.S9S_MB_2U(SCH_1):NC_CPU1_MDFI_DIE00_NS0':
 C_SIGNAL='@s9s_mb_2u_lib.s9s_mb_2u(sch_1):nc_cpu1_mdfi_die00_ns0';
NODE_NAME     U1 BK22
 '@S9S_MB_2U_LIB.S9S_MB_2U(SCH_1):PAGE48_I1@PURE_QUANTA.SOCKET4677_AZIF0045P001C01CS(CHIPS)':
 'RSVD60': CDS_PINID='RSVD60';
NET_NAME
'NC_CPU1_MDFI_DIE00_NS1'
 '@S9S_MB_2U_LIB.S9S_MB_2U(SCH_1):NC_CPU1_MDFI_DIE00_NS1':
 C_SIGNAL='@s9s_mb_2u_lib.s9s_mb_2u(sch_1):nc_cpu1_mdfi_die00_ns1';
NODE_NAME     U1 BJ21
 '@S9S_MB_2U_LIB.S9S_MB_2U(SCH_1):PAGE48_I1@PURE_QUANTA.SOCKET4677_AZIF0045P001C01CS(CHIPS)':
 'RSVD57': CDS_PINID='RSVD57';
NET_NAME
'NC_CPU1_MDFI_DIE01_EW0'
 '@S9S_MB_2U_LIB.S9S_MB_2U(SCH_1):NC_CPU1_MDFI_DIE01_EW0':
 C_SIGNAL='@s9s_mb_2u_lib.s9s_mb_2u(sch_1):nc_cpu1_mdfi_die01_ew0';
NODE_NAME     U1 AV65
 '@S9S_MB_2U_LIB.S9S_MB_2U(SCH_1):PAGE48_I1@PURE_QUANTA.SOCKET4677_AZIF0045P001C01CS(CHIPS)':
 'RSVD21': CDS_PINID='RSVD21';
NET_NAME
'NC_CPU1_MDFI_DIE01_EW1'
 '@S9S_MB_2U_LIB.S9S_MB_2U(SCH_1):NC_CPU1_MDFI_DIE01_EW1':
 C_SIGNAL='@s9s_mb_2u_lib.s9s_mb_2u(sch_1):nc_cpu1_mdfi_die01_ew1';
NODE_NAME     U1 CC66
 '@S9S_MB_2U_LIB.S9S_MB_2U(SCH_1):PAGE48_I1@PURE_QUANTA.SOCKET4677_AZIF0045P001C01CS(CHIPS)':
 'RSVD82': CDS_PINID='RSVD82';
NET_NAME
'NC_CPU1_MDFI_DIE01_NS0'
 '@S9S_MB_2U_LIB.S9S_MB_2U(SCH_1):NC_CPU1_MDFI_DIE01_NS0':
 C_SIGNAL='@s9s_mb_2u_lib.s9s_mb_2u(sch_1):nc_cpu1_mdfi_die01_ns0';
NODE_NAME     U1 BF71
 '@S9S_MB_2U_LIB.S9S_MB_2U(SCH_1):PAGE48_I1@PURE_QUANTA.SOCKET4677_AZIF0045P001C01CS(CHIPS)':
 'RSVD51': CDS_PINID='RSVD51';
NET_NAME
'NC_CPU1_MDFI_DIE01_NS1'
 '@S9S_MB_2U_LIB.S9S_MB_2U(SCH_1):NC_CPU1_MDFI_DIE01_NS1':
 C_SIGNAL='@s9s_mb_2u_lib.s9s_mb_2u(sch_1):nc_cpu1_mdfi_die01_ns1';
NODE_NAME     U1 BD71
 '@S9S_MB_2U_LIB.S9S_MB_2U(SCH_1):PAGE48_I1@PURE_QUANTA.SOCKET4677_AZIF0045P001C01CS(CHIPS)':
 'RSVD43': CDS_PINID='RSVD43';
NET_NAME
'NC_CPU1_MDFI_DIE10_EW0'
 '@S9S_MB_2U_LIB.S9S_MB_2U(SCH_1):NC_CPU1_MDFI_DIE10_EW0':
 C_SIGNAL='@s9s_mb_2u_lib.s9s_mb_2u(sch_1):nc_cpu1_mdfi_die10_ew0';
NODE_NAME     U1 CD26
 '@S9S_MB_2U_LIB.S9S_MB_2U(SCH_1):PAGE48_I1@PURE_QUANTA.SOCKET4677_AZIF0045P001C01CS(CHIPS)':
 'RSVD84': CDS_PINID='RSVD84';
NET_NAME
'NC_CPU1_MDFI_DIE10_EW1'
 '@S9S_MB_2U_LIB.S9S_MB_2U(SCH_1):NC_CPU1_MDFI_DIE10_EW1':
 C_SIGNAL='@s9s_mb_2u_lib.s9s_mb_2u(sch_1):nc_cpu1_mdfi_die10_ew1';
NODE_NAME     U1 CD30
 '@S9S_MB_2U_LIB.S9S_MB_2U(SCH_1):PAGE48_I1@PURE_QUANTA.SOCKET4677_AZIF0045P001C01CS(CHIPS)':
 'RSVD85': CDS_PINID='RSVD85';
NET_NAME
'NC_CPU1_MDFI_DIE10_NS0'
 '@S9S_MB_2U_LIB.S9S_MB_2U(SCH_1):NC_CPU1_MDFI_DIE10_NS0':
 C_SIGNAL='@s9s_mb_2u_lib.s9s_mb_2u(sch_1):nc_cpu1_mdfi_die10_ns0';
NODE_NAME     U1 CF22
 '@S9S_MB_2U_LIB.S9S_MB_2U(SCH_1):PAGE48_I1@PURE_QUANTA.SOCKET4677_AZIF0045P001C01CS(CHIPS)':
 'RSVD92': CDS_PINID='RSVD92';
NET_NAME
'NC_CPU1_MDFI_DIE10_NS1'
 '@S9S_MB_2U_LIB.S9S_MB_2U(SCH_1):NC_CPU1_MDFI_DIE10_NS1':
 C_SIGNAL='@s9s_mb_2u_lib.s9s_mb_2u(sch_1):nc_cpu1_mdfi_die10_ns1';
NODE_NAME     U1 CD22
 '@S9S_MB_2U_LIB.S9S_MB_2U(SCH_1):PAGE48_I1@PURE_QUANTA.SOCKET4677_AZIF0045P001C01CS(CHIPS)':
 'RSVD83': CDS_PINID='RSVD83';
NET_NAME
'NC_CPU1_MDFI_DIE11_EW0'
 '@S9S_MB_2U_LIB.S9S_MB_2U(SCH_1):NC_CPU1_MDFI_DIE11_EW0':
 C_SIGNAL='@s9s_mb_2u_lib.s9s_mb_2u(sch_1):nc_cpu1_mdfi_die11_ew0';
NODE_NAME     U1 CJ70
 '@S9S_MB_2U_LIB.S9S_MB_2U(SCH_1):PAGE48_I1@PURE_QUANTA.SOCKET4677_AZIF0045P001C01CS(CHIPS)':
 'RSVD107': CDS_PINID='RSVD107';
NET_NAME
'NC_CPU1_MDFI_DIE11_EW1'
 '@S9S_MB_2U_LIB.S9S_MB_2U(SCH_1):NC_CPU1_MDFI_DIE11_EW1':
 C_SIGNAL='@s9s_mb_2u_lib.s9s_mb_2u(sch_1):nc_cpu1_mdfi_die11_ew1';
NODE_NAME     U1 CH69
 '@S9S_MB_2U_LIB.S9S_MB_2U(SCH_1):PAGE48_I1@PURE_QUANTA.SOCKET4677_AZIF0045P001C01CS(CHIPS)':
 'RSVD99': CDS_PINID='RSVD99';
NET_NAME
'NC_CPU1_MDFI_DIE11_NS0'
 '@S9S_MB_2U_LIB.S9S_MB_2U(SCH_1):NC_CPU1_MDFI_DIE11_NS0':
 C_SIGNAL='@s9s_mb_2u_lib.s9s_mb_2u(sch_1):nc_cpu1_mdfi_die11_ns0';
NODE_NAME     U1 CJ68
 '@S9S_MB_2U_LIB.S9S_MB_2U(SCH_1):PAGE48_I1@PURE_QUANTA.SOCKET4677_AZIF0045P001C01CS(CHIPS)':
 'RSVD106': CDS_PINID='RSVD106';
NET_NAME
'NC_CPU1_MDFI_DIE11_NS1'
 '@S9S_MB_2U_LIB.S9S_MB_2U(SCH_1):NC_CPU1_MDFI_DIE11_NS1':
 C_SIGNAL='@s9s_mb_2u_lib.s9s_mb_2u(sch_1):nc_cpu1_mdfi_die11_ns1';
NODE_NAME     U1 CK67
 '@S9S_MB_2U_LIB.S9S_MB_2U(SCH_1):PAGE48_I1@PURE_QUANTA.SOCKET4677_AZIF0045P001C01CS(CHIPS)':
 'RSVD112': CDS_PINID='RSVD112';
NET_NAME
'NC_CPU1_PE0_APROBE<0>'
 '@S9S_MB_2U_LIB.S9S_MB_2U(SCH_1):NC_CPU1_PE0_APROBE'<0>:
 C_SIGNAL='@s9s_mb_2u_lib.s9s_mb_2u(sch_1):nc_cpu1_pe0_aprobe(0)';
NODE_NAME     U1 BN21
 '@S9S_MB_2U_LIB.S9S_MB_2U(SCH_1):PAGE50_I23@PURE_QUANTA.SOCKET4677_AZIF0045P001C01CS(CHIPS)':
 'RSVD66': CDS_PINID='RSVD66';
NET_NAME
'NC_CPU1_PE0_APROBE<1>'
 '@S9S_MB_2U_LIB.S9S_MB_2U(SCH_1):NC_CPU1_PE0_APROBE'<1>:
 C_SIGNAL='@s9s_mb_2u_lib.s9s_mb_2u(sch_1):nc_cpu1_pe0_aprobe(1)';
NODE_NAME     U1 BL21
 '@S9S_MB_2U_LIB.S9S_MB_2U(SCH_1):PAGE50_I23@PURE_QUANTA.SOCKET4677_AZIF0045P001C01CS(CHIPS)':
 'RSVD62': CDS_PINID='RSVD62';
NET_NAME
'NC_CPU1_PE1_APROBE<0>'
 '@S9S_MB_2U_LIB.S9S_MB_2U(SCH_1):NC_CPU1_PE1_APROBE'<0>:
 C_SIGNAL='@s9s_mb_2u_lib.s9s_mb_2u(sch_1):nc_cpu1_pe1_aprobe(0)';
NODE_NAME     U1 CE21
 '@S9S_MB_2U_LIB.S9S_MB_2U(SCH_1):PAGE50_I23@PURE_QUANTA.SOCKET4677_AZIF0045P001C01CS(CHIPS)':
 'RSVD89': CDS_PINID='RSVD89';
NET_NAME
'NC_CPU1_PE1_APROBE<1>'
 '@S9S_MB_2U_LIB.S9S_MB_2U(SCH_1):NC_CPU1_PE1_APROBE'<1>:
 C_SIGNAL='@s9s_mb_2u_lib.s9s_mb_2u(sch_1):nc_cpu1_pe1_aprobe(1)';
NODE_NAME     U1 CC21
 '@S9S_MB_2U_LIB.S9S_MB_2U(SCH_1):PAGE50_I23@PURE_QUANTA.SOCKET4677_AZIF0045P001C01CS(CHIPS)':
 'RSVD79': CDS_PINID='RSVD79';
NET_NAME
'NC_CPU1_PE2_APROBE<0>'
 '@S9S_MB_2U_LIB.S9S_MB_2U(SCH_1):NC_CPU1_PE2_APROBE'<0>:
 C_SIGNAL='@s9s_mb_2u_lib.s9s_mb_2u(sch_1):nc_cpu1_pe2_aprobe(0)';
NODE_NAME     U1 CC23
 '@S9S_MB_2U_LIB.S9S_MB_2U(SCH_1):PAGE50_I23@PURE_QUANTA.SOCKET4677_AZIF0045P001C01CS(CHIPS)':
 'RSVD80': CDS_PINID='RSVD80';
NET_NAME
'NC_CPU1_PE2_APROBE<1>'
 '@S9S_MB_2U_LIB.S9S_MB_2U(SCH_1):NC_CPU1_PE2_APROBE'<1>:
 C_SIGNAL='@s9s_mb_2u_lib.s9s_mb_2u(sch_1):nc_cpu1_pe2_aprobe(1)';
NODE_NAME     U1 BW23
 '@S9S_MB_2U_LIB.S9S_MB_2U(SCH_1):PAGE50_I23@PURE_QUANTA.SOCKET4677_AZIF0045P001C01CS(CHIPS)':
 'RSVD75': CDS_PINID='RSVD75';
NET_NAME
'NC_CPU1_PE3_APROBE<0>'
 '@S9S_MB_2U_LIB.S9S_MB_2U(SCH_1):NC_CPU1_PE3_APROBE'<0>:
 C_SIGNAL='@s9s_mb_2u_lib.s9s_mb_2u(sch_1):nc_cpu1_pe3_aprobe(0)';
NODE_NAME     U1 CL68
 '@S9S_MB_2U_LIB.S9S_MB_2U(SCH_1):PAGE50_I23@PURE_QUANTA.SOCKET4677_AZIF0045P001C01CS(CHIPS)':
 'RSVD118': CDS_PINID='RSVD118';
NET_NAME
'NC_CPU1_PE3_APROBE<1>'
 '@S9S_MB_2U_LIB.S9S_MB_2U(SCH_1):NC_CPU1_PE3_APROBE'<1>:
 C_SIGNAL='@s9s_mb_2u_lib.s9s_mb_2u(sch_1):nc_cpu1_pe3_aprobe(1)';
NODE_NAME     U1 CM69
 '@S9S_MB_2U_LIB.S9S_MB_2U(SCH_1):PAGE50_I23@PURE_QUANTA.SOCKET4677_AZIF0045P001C01CS(CHIPS)':
 'RSVD122': CDS_PINID='RSVD122';
NET_NAME
'NC_CPU1_PE4_APROBE<0>'
 '@S9S_MB_2U_LIB.S9S_MB_2U(SCH_1):NC_CPU1_PE4_APROBE'<0>:
 C_SIGNAL='@s9s_mb_2u_lib.s9s_mb_2u(sch_1):nc_cpu1_pe4_aprobe(0)';
NODE_NAME     U1 AV67
 '@S9S_MB_2U_LIB.S9S_MB_2U(SCH_1):PAGE50_I23@PURE_QUANTA.SOCKET4677_AZIF0045P001C01CS(CHIPS)':
 'RSVD22': CDS_PINID='RSVD22';
NET_NAME
'NC_CPU1_PE4_APROBE<1>'
 '@S9S_MB_2U_LIB.S9S_MB_2U(SCH_1):NC_CPU1_PE4_APROBE'<1>:
 C_SIGNAL='@s9s_mb_2u_lib.s9s_mb_2u(sch_1):nc_cpu1_pe4_aprobe(1)';
NODE_NAME     U1 AU66
 '@S9S_MB_2U_LIB.S9S_MB_2U(SCH_1):PAGE50_I23@PURE_QUANTA.SOCKET4677_AZIF0045P001C01CS(CHIPS)':
 'RSVD13': CDS_PINID='RSVD13';
NET_NAME
'NC_CPU1_SOC_SPARE0'
 '@S9S_MB_2U_LIB.S9S_MB_2U(SCH_1):NC_CPU1_SOC_SPARE0':
 C_SIGNAL='@s9s_mb_2u_lib.s9s_mb_2u(sch_1):nc_cpu1_soc_spare0';
NODE_NAME     U1 AY24
 '@S9S_MB_2U_LIB.S9S_MB_2U(SCH_1):PAGE48_I1@PURE_QUANTA.SOCKET4677_AZIF0045P001C01CS(CHIPS)':
 'RSVD26': CDS_PINID='RSVD26';
NET_NAME
'NC_CPU1_SOC_SPARE1'
 '@S9S_MB_2U_LIB.S9S_MB_2U(SCH_1):NC_CPU1_SOC_SPARE1':
 C_SIGNAL='@s9s_mb_2u_lib.s9s_mb_2u(sch_1):nc_cpu1_soc_spare1';
NODE_NAME     U1 BM65
 '@S9S_MB_2U_LIB.S9S_MB_2U(SCH_1):PAGE48_I1@PURE_QUANTA.SOCKET4677_AZIF0045P001C01CS(CHIPS)':
 'RSVD65': CDS_PINID='RSVD65';
NET_NAME
'NC_CPU1_SOC_SPARE4'
 '@S9S_MB_2U_LIB.S9S_MB_2U(SCH_1):NC_CPU1_SOC_SPARE4':
 C_SIGNAL='@s9s_mb_2u_lib.s9s_mb_2u(sch_1):nc_cpu1_soc_spare4';
NODE_NAME     U1 BA25
 '@S9S_MB_2U_LIB.S9S_MB_2U(SCH_1):PAGE48_I1@PURE_QUANTA.SOCKET4677_AZIF0045P001C01CS(CHIPS)':
 'RSVD31': CDS_PINID='RSVD31';
NET_NAME
'NC_CPU1_SOC_SPARE5'
 '@S9S_MB_2U_LIB.S9S_MB_2U(SCH_1):NC_CPU1_SOC_SPARE5':
 C_SIGNAL='@s9s_mb_2u_lib.s9s_mb_2u(sch_1):nc_cpu1_soc_spare5';
NODE_NAME     U1 BP65
 '@S9S_MB_2U_LIB.S9S_MB_2U(SCH_1):PAGE48_I1@PURE_QUANTA.SOCKET4677_AZIF0045P001C01CS(CHIPS)':
 'RSVD68': CDS_PINID='RSVD68';
NET_NAME
'NC_CPU1_THERMADA'
 '@S9S_MB_2U_LIB.S9S_MB_2U(SCH_1):NC_CPU1_THERMADA':
 C_SIGNAL='@s9s_mb_2u_lib.s9s_mb_2u(sch_1):nc_cpu1_thermada';
NODE_NAME     U1 AV40
 '@S9S_MB_2U_LIB.S9S_MB_2U(SCH_1):PAGE47_I16@PURE_QUANTA.SOCKET4677_AZIF0045P001C01CS(CHIPS)':
 'RSVD18': CDS_PINID='RSVD18';
NET_NAME
'NC_CPU1_THERMADC'
 '@S9S_MB_2U_LIB.S9S_MB_2U(SCH_1):NC_CPU1_THERMADC':
 C_SIGNAL='@s9s_mb_2u_lib.s9s_mb_2u(sch_1):nc_cpu1_thermadc';
NODE_NAME     U1 AV38
 '@S9S_MB_2U_LIB.S9S_MB_2U(SCH_1):PAGE47_I16@PURE_QUANTA.SOCKET4677_AZIF0045P001C01CS(CHIPS)':
 'RSVD17': CDS_PINID='RSVD17';
NET_NAME
'NC_CPU1_UPI0_APROBE<0>'
 '@S9S_MB_2U_LIB.S9S_MB_2U(SCH_1):NC_CPU1_UPI0_APROBE'<0>:
 C_SIGNAL='@s9s_mb_2u_lib.s9s_mb_2u(sch_1):nc_cpu1_upi0_aprobe(0)';
NODE_NAME     U1 AN17
 '@S9S_MB_2U_LIB.S9S_MB_2U(SCH_1):PAGE50_I23@PURE_QUANTA.SOCKET4677_AZIF0045P001C01CS(CHIPS)':
 'RSVD2': CDS_PINID='RSVD2';
NET_NAME
'NC_CPU1_UPI0_APROBE<1>'
 '@S9S_MB_2U_LIB.S9S_MB_2U(SCH_1):NC_CPU1_UPI0_APROBE'<1>:
 C_SIGNAL='@s9s_mb_2u_lib.s9s_mb_2u(sch_1):nc_cpu1_upi0_aprobe(1)';
NODE_NAME     U1 AR17
 '@S9S_MB_2U_LIB.S9S_MB_2U(SCH_1):PAGE50_I23@PURE_QUANTA.SOCKET4677_AZIF0045P001C01CS(CHIPS)':
 'RSVD3': CDS_PINID='RSVD3';
NET_NAME
'NC_CPU1_UPI1_APROBE<0>'
 '@S9S_MB_2U_LIB.S9S_MB_2U(SCH_1):NC_CPU1_UPI1_APROBE'<0>:
 C_SIGNAL='@s9s_mb_2u_lib.s9s_mb_2u(sch_1):nc_cpu1_upi1_aprobe(0)';
NODE_NAME     U1 BV22
 '@S9S_MB_2U_LIB.S9S_MB_2U(SCH_1):PAGE50_I23@PURE_QUANTA.SOCKET4677_AZIF0045P001C01CS(CHIPS)':
 'RSVD73': CDS_PINID='RSVD73';
NET_NAME
'NC_CPU1_UPI1_APROBE<1>'
 '@S9S_MB_2U_LIB.S9S_MB_2U(SCH_1):NC_CPU1_UPI1_APROBE'<1>:
 C_SIGNAL='@s9s_mb_2u_lib.s9s_mb_2u(sch_1):nc_cpu1_upi1_aprobe(1)';
NODE_NAME     U1 CA23
 '@S9S_MB_2U_LIB.S9S_MB_2U(SCH_1):PAGE50_I23@PURE_QUANTA.SOCKET4677_AZIF0045P001C01CS(CHIPS)':
 'RSVD78': CDS_PINID='RSVD78';
NET_NAME
'NC_CPU1_UPI2_APROBE<0>'
 '@S9S_MB_2U_LIB.S9S_MB_2U(SCH_1):NC_CPU1_UPI2_APROBE'<0>:
 C_SIGNAL='@s9s_mb_2u_lib.s9s_mb_2u(sch_1):nc_cpu1_upi2_aprobe(0)';
NODE_NAME     U1 AU68
 '@S9S_MB_2U_LIB.S9S_MB_2U(SCH_1):PAGE50_I23@PURE_QUANTA.SOCKET4677_AZIF0045P001C01CS(CHIPS)':
 'RSVD14': CDS_PINID='RSVD14';
NET_NAME
'NC_CPU1_UPI2_APROBE<1>'
 '@S9S_MB_2U_LIB.S9S_MB_2U(SCH_1):NC_CPU1_UPI2_APROBE'<1>:
 C_SIGNAL='@s9s_mb_2u_lib.s9s_mb_2u(sch_1):nc_cpu1_upi2_aprobe(1)';
NODE_NAME     U1 AT67
 '@S9S_MB_2U_LIB.S9S_MB_2U(SCH_1):PAGE50_I23@PURE_QUANTA.SOCKET4677_AZIF0045P001C01CS(CHIPS)':
 'RSVD5': CDS_PINID='RSVD5';
NET_NAME
'NC_CPU1_UPI3_APROBE<0>'
 '@S9S_MB_2U_LIB.S9S_MB_2U(SCH_1):NC_CPU1_UPI3_APROBE'<0>:
 C_SIGNAL='@s9s_mb_2u_lib.s9s_mb_2u(sch_1):nc_cpu1_upi3_aprobe(0)';
NODE_NAME     U1 CP69
 '@S9S_MB_2U_LIB.S9S_MB_2U(SCH_1):PAGE50_I23@PURE_QUANTA.SOCKET4677_AZIF0045P001C01CS(CHIPS)':
 'RSVD130': CDS_PINID='RSVD130';
NET_NAME
'NC_CPU1_UPI3_APROBE<1>'
 '@S9S_MB_2U_LIB.S9S_MB_2U(SCH_1):NC_CPU1_UPI3_APROBE'<1>:
 C_SIGNAL='@s9s_mb_2u_lib.s9s_mb_2u(sch_1):nc_cpu1_upi3_aprobe(1)';
NODE_NAME     U1 CR68
 '@S9S_MB_2U_LIB.S9S_MB_2U(SCH_1):PAGE50_I23@PURE_QUANTA.SOCKET4677_AZIF0045P001C01CS(CHIPS)':
 'RSVD135': CDS_PINID='RSVD135';
NET_NAME
'NC_CPU1_VIEWPIN_GNR0'
 '@S9S_MB_2U_LIB.S9S_MB_2U(SCH_1):NC_CPU1_VIEWPIN_GNR0':
 C_SIGNAL='@s9s_mb_2u_lib.s9s_mb_2u(sch_1):nc_cpu1_viewpin_gnr0';
NODE_NAME     U1 CT26
 '@S9S_MB_2U_LIB.S9S_MB_2U(SCH_1):PAGE48_I1@PURE_QUANTA.SOCKET4677_AZIF0045P001C01CS(CHIPS)':
 'RSVD138': CDS_PINID='RSVD138';
NET_NAME
'NC_CPU1_VIEWPIN_GNR1'
 '@S9S_MB_2U_LIB.S9S_MB_2U(SCH_1):NC_CPU1_VIEWPIN_GNR1':
 C_SIGNAL='@s9s_mb_2u_lib.s9s_mb_2u(sch_1):nc_cpu1_viewpin_gnr1';
NODE_NAME     U1 CW58
 '@S9S_MB_2U_LIB.S9S_MB_2U(SCH_1):PAGE48_I1@PURE_QUANTA.SOCKET4677_AZIF0045P001C01CS(CHIPS)':
 'RSVD149': CDS_PINID='RSVD149';
NET_NAME
'NC_CPU1_VIEWPIN_GNR2'
 '@S9S_MB_2U_LIB.S9S_MB_2U(SCH_1):NC_CPU1_VIEWPIN_GNR2':
 C_SIGNAL='@s9s_mb_2u_lib.s9s_mb_2u(sch_1):nc_cpu1_viewpin_gnr2';
NODE_NAME     U1 CR25
 '@S9S_MB_2U_LIB.S9S_MB_2U(SCH_1):PAGE48_I1@PURE_QUANTA.SOCKET4677_AZIF0045P001C01CS(CHIPS)':
 'RSVD133': CDS_PINID='RSVD133';
NET_NAME
'NC_CPU1_VIEWPIN_GNR3'
 '@S9S_MB_2U_LIB.S9S_MB_2U(SCH_1):NC_CPU1_VIEWPIN_GNR3':
 C_SIGNAL='@s9s_mb_2u_lib.s9s_mb_2u(sch_1):nc_cpu1_viewpin_gnr3';
NODE_NAME     U1 CY57
 '@S9S_MB_2U_LIB.S9S_MB_2U(SCH_1):PAGE48_I1@PURE_QUANTA.SOCKET4677_AZIF0045P001C01CS(CHIPS)':
 'RSVD154': CDS_PINID='RSVD154';
NET_NAME
'NC_DBP_P18'
 '@S9S_MB_2U_LIB.S9S_MB_2U(SCH_1):NC_DBP_P18':
 C_SIGNAL='@s9s_mb_2u_lib.s9s_mb_2u(sch_1):nc_dbp_p18';
NODE_NAME     J42 18
 '@S9S_MB_2U_LIB.S9S_MB_2U(SCH_1):PAGE133_I44@PURE_QUANTA.SCONN60_ASP21410801(CHIPS)':
 '18': CDS_PINID='\18\';
NET_NAME
'NC_DBP_P20'
 '@S9S_MB_2U_LIB.S9S_MB_2U(SCH_1):NC_DBP_P20':
 C_SIGNAL='@s9s_mb_2u_lib.s9s_mb_2u(sch_1):nc_dbp_p20';
NODE_NAME     J42 20
 '@S9S_MB_2U_LIB.S9S_MB_2U(SCH_1):PAGE133_I44@PURE_QUANTA.SCONN60_ASP21410801(CHIPS)':
 '20': CDS_PINID='\20\';
NET_NAME
'NC_DBP_P22'
 '@S9S_MB_2U_LIB.S9S_MB_2U(SCH_1):NC_DBP_P22':
 C_SIGNAL='@s9s_mb_2u_lib.s9s_mb_2u(sch_1):nc_dbp_p22';
NODE_NAME     J42 22
 '@S9S_MB_2U_LIB.S9S_MB_2U(SCH_1):PAGE133_I44@PURE_QUANTA.SCONN60_ASP21410801(CHIPS)':
 '22': CDS_PINID='\22\';
NET_NAME
'NC_DBP_P24'
 '@S9S_MB_2U_LIB.S9S_MB_2U(SCH_1):NC_DBP_P24':
 C_SIGNAL='@s9s_mb_2u_lib.s9s_mb_2u(sch_1):nc_dbp_p24';
NODE_NAME     J42 24
 '@S9S_MB_2U_LIB.S9S_MB_2U(SCH_1):PAGE133_I44@PURE_QUANTA.SCONN60_ASP21410801(CHIPS)':
 '24': CDS_PINID='\24\';
NET_NAME
'NC_DBP_P26'
 '@S9S_MB_2U_LIB.S9S_MB_2U(SCH_1):NC_DBP_P26':
 C_SIGNAL='@s9s_mb_2u_lib.s9s_mb_2u(sch_1):nc_dbp_p26';
NODE_NAME     J42 26
 '@S9S_MB_2U_LIB.S9S_MB_2U(SCH_1):PAGE133_I44@PURE_QUANTA.SCONN60_ASP21410801(CHIPS)':
 '26': CDS_PINID='\26\';
NET_NAME
'NC_DBP_P28'
 '@S9S_MB_2U_LIB.S9S_MB_2U(SCH_1):NC_DBP_P28':
 C_SIGNAL='@s9s_mb_2u_lib.s9s_mb_2u(sch_1):nc_dbp_p28';
NODE_NAME     J42 28
 '@S9S_MB_2U_LIB.S9S_MB_2U(SCH_1):PAGE133_I44@PURE_QUANTA.SCONN60_ASP21410801(CHIPS)':
 '28': CDS_PINID='\28\';
NET_NAME
'NC_DBP_P30'
 '@S9S_MB_2U_LIB.S9S_MB_2U(SCH_1):NC_DBP_P30':
 C_SIGNAL='@s9s_mb_2u_lib.s9s_mb_2u(sch_1):nc_dbp_p30';
NODE_NAME     J42 30
 '@S9S_MB_2U_LIB.S9S_MB_2U(SCH_1):PAGE133_I44@PURE_QUANTA.SCONN60_ASP21410801(CHIPS)':
 '30': CDS_PINID='\30\';
NET_NAME
'NC_DBP_P32'
 '@S9S_MB_2U_LIB.S9S_MB_2U(SCH_1):NC_DBP_P32':
 C_SIGNAL='@s9s_mb_2u_lib.s9s_mb_2u(sch_1):nc_dbp_p32';
NODE_NAME     J42 32
 '@S9S_MB_2U_LIB.S9S_MB_2U(SCH_1):PAGE133_I44@PURE_QUANTA.SCONN60_ASP21410801(CHIPS)':
 '32': CDS_PINID='\32\';
NET_NAME
'NC_DBP_P34'
 '@S9S_MB_2U_LIB.S9S_MB_2U(SCH_1):NC_DBP_P34':
 C_SIGNAL='@s9s_mb_2u_lib.s9s_mb_2u(sch_1):nc_dbp_p34';
NODE_NAME     J42 34
 '@S9S_MB_2U_LIB.S9S_MB_2U(SCH_1):PAGE133_I44@PURE_QUANTA.SCONN60_ASP21410801(CHIPS)':
 '34': CDS_PINID='\34\';
NET_NAME
'NC_DBP_P44'
 '@S9S_MB_2U_LIB.S9S_MB_2U(SCH_1):NC_DBP_P44':
 C_SIGNAL='@s9s_mb_2u_lib.s9s_mb_2u(sch_1):nc_dbp_p44';
NODE_NAME     J42 44
 '@S9S_MB_2U_LIB.S9S_MB_2U(SCH_1):PAGE133_I44@PURE_QUANTA.SCONN60_ASP21410801(CHIPS)':
 '44': CDS_PINID='\44\';
NET_NAME
'NC_DBP_P46'
 '@S9S_MB_2U_LIB.S9S_MB_2U(SCH_1):NC_DBP_P46':
 C_SIGNAL='@s9s_mb_2u_lib.s9s_mb_2u(sch_1):nc_dbp_p46';
NODE_NAME     J42 46
 '@S9S_MB_2U_LIB.S9S_MB_2U(SCH_1):PAGE133_I44@PURE_QUANTA.SCONN60_ASP21410801(CHIPS)':
 '46': CDS_PINID='\46\';
NET_NAME
'NC_DBP_P54'
 '@S9S_MB_2U_LIB.S9S_MB_2U(SCH_1):NC_DBP_P54':
 C_SIGNAL='@s9s_mb_2u_lib.s9s_mb_2u(sch_1):nc_dbp_p54';
NODE_NAME     J42 54
 '@S9S_MB_2U_LIB.S9S_MB_2U(SCH_1):PAGE133_I44@PURE_QUANTA.SCONN60_ASP21410801(CHIPS)':
 '54': CDS_PINID='\54\';
NET_NAME
'NC_DBP_P56'
 '@S9S_MB_2U_LIB.S9S_MB_2U(SCH_1):NC_DBP_P56':
 C_SIGNAL='@s9s_mb_2u_lib.s9s_mb_2u(sch_1):nc_dbp_p56';
NODE_NAME     J42 56
 '@S9S_MB_2U_LIB.S9S_MB_2U(SCH_1):PAGE133_I44@PURE_QUANTA.SCONN60_ASP21410801(CHIPS)':
 '56': CDS_PINID='\56\';
NET_NAME
'NC_ESPI_IBL_CPU1_ALERT0_N'
 '@S9S_MB_2U_LIB.S9S_MB_2U(SCH_1):NC_ESPI_IBL_CPU1_ALERT0_N':
 C_SIGNAL='@s9s_mb_2u_lib.s9s_mb_2u(sch_1):nc_espi_ibl_cpu1_alert0_n';
NODE_NAME     U1 BE62
 '@S9S_MB_2U_LIB.S9S_MB_2U(SCH_1):PAGE46_I5@PURE_QUANTA.SOCKET4677_AZIF0045P001C01CS(CHIPS)':
 'RSVD48': CDS_PINID='RSVD48';
NET_NAME
'NC_ESPI_IBL_CPU1_ALERT1_N'
 '@S9S_MB_2U_LIB.S9S_MB_2U(SCH_1):NC_ESPI_IBL_CPU1_ALERT1_N':
 C_SIGNAL='@s9s_mb_2u_lib.s9s_mb_2u(sch_1):nc_espi_ibl_cpu1_alert1_n';
NODE_NAME     U1 BD63
 '@S9S_MB_2U_LIB.S9S_MB_2U(SCH_1):PAGE46_I5@PURE_QUANTA.SOCKET4677_AZIF0045P001C01CS(CHIPS)':
 'RSVD41': CDS_PINID='RSVD41';
NET_NAME
'NC_ESPI_IBL_CPU1_CLK'
 '@S9S_MB_2U_LIB.S9S_MB_2U(SCH_1):NC_ESPI_IBL_CPU1_CLK':
 C_SIGNAL='@s9s_mb_2u_lib.s9s_mb_2u(sch_1):nc_espi_ibl_cpu1_clk';
NODE_NAME     U1 BG62
 '@S9S_MB_2U_LIB.S9S_MB_2U(SCH_1):PAGE46_I5@PURE_QUANTA.SOCKET4677_AZIF0045P001C01CS(CHIPS)':
 'RSVD52': CDS_PINID='RSVD52';
NET_NAME
'NC_ESPI_IBL_CPU1_CS0_N'
 '@S9S_MB_2U_LIB.S9S_MB_2U(SCH_1):NC_ESPI_IBL_CPU1_CS0_N':
 C_SIGNAL='@s9s_mb_2u_lib.s9s_mb_2u(sch_1):nc_espi_ibl_cpu1_cs0_n';
NODE_NAME     U1 BF65
 '@S9S_MB_2U_LIB.S9S_MB_2U(SCH_1):PAGE46_I5@PURE_QUANTA.SOCKET4677_AZIF0045P001C01CS(CHIPS)':
 'RSVD50': CDS_PINID='RSVD50';
NET_NAME
'NC_ESPI_IBL_CPU1_CS1_N'
 '@S9S_MB_2U_LIB.S9S_MB_2U(SCH_1):NC_ESPI_IBL_CPU1_CS1_N':
 C_SIGNAL='@s9s_mb_2u_lib.s9s_mb_2u(sch_1):nc_espi_ibl_cpu1_cs1_n';
NODE_NAME     U1 BH65
 '@S9S_MB_2U_LIB.S9S_MB_2U(SCH_1):PAGE46_I5@PURE_QUANTA.SOCKET4677_AZIF0045P001C01CS(CHIPS)':
 'RSVD56': CDS_PINID='RSVD56';
NET_NAME
'NC_ESPI_IBL_CPU1_IO0'
 '@S9S_MB_2U_LIB.S9S_MB_2U(SCH_1):NC_ESPI_IBL_CPU1_IO0':
 C_SIGNAL='@s9s_mb_2u_lib.s9s_mb_2u(sch_1):nc_espi_ibl_cpu1_io0';
NODE_NAME     U1 BK63
 '@S9S_MB_2U_LIB.S9S_MB_2U(SCH_1):PAGE46_I5@PURE_QUANTA.SOCKET4677_AZIF0045P001C01CS(CHIPS)':
 'RSVD61': CDS_PINID='RSVD61';
NET_NAME
'NC_ESPI_IBL_CPU1_IO1'
 '@S9S_MB_2U_LIB.S9S_MB_2U(SCH_1):NC_ESPI_IBL_CPU1_IO1':
 C_SIGNAL='@s9s_mb_2u_lib.s9s_mb_2u(sch_1):nc_espi_ibl_cpu1_io1';
NODE_NAME     U1 BJ64
 '@S9S_MB_2U_LIB.S9S_MB_2U(SCH_1):PAGE46_I5@PURE_QUANTA.SOCKET4677_AZIF0045P001C01CS(CHIPS)':
 'RSVD58': CDS_PINID='RSVD58';
NET_NAME
'NC_ESPI_IBL_CPU1_IO2'
 '@S9S_MB_2U_LIB.S9S_MB_2U(SCH_1):NC_ESPI_IBL_CPU1_IO2':
 C_SIGNAL='@s9s_mb_2u_lib.s9s_mb_2u(sch_1):nc_espi_ibl_cpu1_io2';
NODE_NAME     U1 AU64
 '@S9S_MB_2U_LIB.S9S_MB_2U(SCH_1):PAGE46_I5@PURE_QUANTA.SOCKET4677_AZIF0045P001C01CS(CHIPS)':
 'RSVD12': CDS_PINID='RSVD12';
NET_NAME
'NC_ESPI_IBL_CPU1_IO3'
 '@S9S_MB_2U_LIB.S9S_MB_2U(SCH_1):NC_ESPI_IBL_CPU1_IO3':
 C_SIGNAL='@s9s_mb_2u_lib.s9s_mb_2u(sch_1):nc_espi_ibl_cpu1_io3';
NODE_NAME     U1 BM63
 '@S9S_MB_2U_LIB.S9S_MB_2U(SCH_1):PAGE46_I5@PURE_QUANTA.SOCKET4677_AZIF0045P001C01CS(CHIPS)':
 'RSVD64': CDS_PINID='RSVD64';
NET_NAME
'NC_ESPI_IBL_CPU1_OE_N'
 '@S9S_MB_2U_LIB.S9S_MB_2U(SCH_1):NC_ESPI_IBL_CPU1_OE_N':
 C_SIGNAL='@s9s_mb_2u_lib.s9s_mb_2u(sch_1):nc_espi_ibl_cpu1_oe_n';
NODE_NAME     U1 BH63
 '@S9S_MB_2U_LIB.S9S_MB_2U(SCH_1):PAGE46_I5@PURE_QUANTA.SOCKET4677_AZIF0045P001C01CS(CHIPS)':
 'RSVD55': CDS_PINID='RSVD55';
NET_NAME
'NC_ESPI_IBL_CPU1_RESET_N'
 '@S9S_MB_2U_LIB.S9S_MB_2U(SCH_1):NC_ESPI_IBL_CPU1_RESET_N':
 C_SIGNAL='@s9s_mb_2u_lib.s9s_mb_2u(sch_1):nc_espi_ibl_cpu1_reset_n';
NODE_NAME     U1 BG64
 '@S9S_MB_2U_LIB.S9S_MB_2U(SCH_1):PAGE46_I5@PURE_QUANTA.SOCKET4677_AZIF0045P001C01CS(CHIPS)':
 'RSVD53': CDS_PINID='RSVD53';
NET_NAME
'NC_ESPI_PLD_R_EN_BUF'
 '@S9S_MB_2U_LIB.S9S_MB_2U(SCH_1):NC_ESPI_PLD_R_EN_BUF':
 C_SIGNAL='@s9s_mb_2u_lib.s9s_mb_2u(sch_1):nc_espi_pld_r_en_buf';
NODE_NAME     U154 1
 '@S9S_MB_2U_LIB.S9S_MB_2U(SCH_1):PAGE190_I95@PURE_QUANTA.74LVC1G07SE7(CHIPS)':
 'NC1': CDS_PINID='NC1';
NET_NAME
'NC_FM_IBL_ADR_ACK_CPU1'
 '@S9S_MB_2U_LIB.S9S_MB_2U(SCH_1):NC_FM_IBL_ADR_ACK_CPU1':
 C_SIGNAL='@s9s_mb_2u_lib.s9s_mb_2u(sch_1):nc_fm_ibl_adr_ack_cpu1';
NODE_NAME     U1 CN23
 '@S9S_MB_2U_LIB.S9S_MB_2U(SCH_1):PAGE46_I5@PURE_QUANTA.SOCKET4677_AZIF0045P001C01CS(CHIPS)':
 'RSVD124': CDS_PINID='RSVD124';
NET_NAME
'NC_FM_IBL_ADR_COMPLETE_CPU1_R'
 '@S9S_MB_2U_LIB.S9S_MB_2U(SCH_1):NC_FM_IBL_ADR_COMPLETE_CPU1_R':
 C_SIGNAL='@s9s_mb_2u_lib.s9s_mb_2u(sch_1):nc_fm_ibl_adr_complete_cpu1_r';
NODE_NAME     U1 CP24
 '@S9S_MB_2U_LIB.S9S_MB_2U(SCH_1):PAGE46_I5@PURE_QUANTA.SOCKET4677_AZIF0045P001C01CS(CHIPS)':
 'RSVD128': CDS_PINID='RSVD128';
NET_NAME
'NC_FM_IBL_ADR_TRIGGER_CPU1_R'
 '@S9S_MB_2U_LIB.S9S_MB_2U(SCH_1):NC_FM_IBL_ADR_TRIGGER_CPU1_R':
 C_SIGNAL='@s9s_mb_2u_lib.s9s_mb_2u(sch_1):nc_fm_ibl_adr_trigger_cpu1_r';
NODE_NAME     U1 CT24
 '@S9S_MB_2U_LIB.S9S_MB_2U(SCH_1):PAGE46_I5@PURE_QUANTA.SOCKET4677_AZIF0045P001C01CS(CHIPS)':
 'RSVD137': CDS_PINID='RSVD137';
NET_NAME
'NC_FPGA_PB22B'
 '@S9S_MB_2U_LIB.S9S_MB_2U(SCH_1):NC_FPGA_PB22B':
 C_SIGNAL='@s9s_mb_2u_lib.s9s_mb_2u(sch_1):nc_fpga_pb22b';
NODE_NAME     U249 AB10
 '@S9S_MB_2U_LIB.S9S_MB_2U(SCH_1):PAGE312_I1@PURE_QUANTA.LCMXO3LF9400C5BG484C(CHIPS)':
 'PB22B||PCLKC2_0': CDS_PINID='\pb22b||pclkc2_0\';
NET_NAME
'NC_FPGA_PB32D'
 '@S9S_MB_2U_LIB.S9S_MB_2U(SCH_1):NC_FPGA_PB32D':
 C_SIGNAL='@s9s_mb_2u_lib.s9s_mb_2u(sch_1):nc_fpga_pb32d';
NODE_NAME     U249 V14
 '@S9S_MB_2U_LIB.S9S_MB_2U(SCH_1):PAGE312_I1@PURE_QUANTA.LCMXO3LF9400C5BG484C(CHIPS)':
 'PB32D': CDS_PINID='PB32D';
NET_NAME
'NC_FPGA_PB35B'
 '@S9S_MB_2U_LIB.S9S_MB_2U(SCH_1):NC_FPGA_PB35B':
 C_SIGNAL='@s9s_mb_2u_lib.s9s_mb_2u(sch_1):nc_fpga_pb35b';
NODE_NAME     U249 AA15
 '@S9S_MB_2U_LIB.S9S_MB_2U(SCH_1):PAGE312_I1@PURE_QUANTA.LCMXO3LF9400C5BG484C(CHIPS)':
 'PB35B': CDS_PINID='PB35B';
NET_NAME
'NC_FPGA_PB43D'
 '@S9S_MB_2U_LIB.S9S_MB_2U(SCH_1):NC_FPGA_PB43D':
 C_SIGNAL='@s9s_mb_2u_lib.s9s_mb_2u(sch_1):nc_fpga_pb43d';
NODE_NAME     U249 U16
 '@S9S_MB_2U_LIB.S9S_MB_2U(SCH_1):PAGE312_I1@PURE_QUANTA.LCMXO3LF9400C5BG484C(CHIPS)':
 'PB43D': CDS_PINID='PB43D';
NET_NAME
'NC_FPGA_PB46B'
 '@S9S_MB_2U_LIB.S9S_MB_2U(SCH_1):NC_FPGA_PB46B':
 C_SIGNAL='@s9s_mb_2u_lib.s9s_mb_2u(sch_1):nc_fpga_pb46b';
NODE_NAME     U249 AA21
 '@S9S_MB_2U_LIB.S9S_MB_2U(SCH_1):PAGE312_I1@PURE_QUANTA.LCMXO3LF9400C5BG484C(CHIPS)':
 'PB46B||SI||SISPI': CDS_PINID='\pb46b||si||sispi\';
NET_NAME
'NC_FPGA_PB7D'
 '@S9S_MB_2U_LIB.S9S_MB_2U(SCH_1):NC_FPGA_PB7D':
 C_SIGNAL='@s9s_mb_2u_lib.s9s_mb_2u(sch_1):nc_fpga_pb7d';
NODE_NAME     U249 W5
 '@S9S_MB_2U_LIB.S9S_MB_2U(SCH_1):PAGE312_I1@PURE_QUANTA.LCMXO3LF9400C5BG484C(CHIPS)':
 'PB7D': CDS_PINID='PB7D';
NET_NAME
'NC_FPGA_PR13A'
 '@S9S_MB_2U_LIB.S9S_MB_2U(SCH_1):NC_FPGA_PR13A':
 C_SIGNAL='@s9s_mb_2u_lib.s9s_mb_2u(sch_1):nc_fpga_pr13a';
NODE_NAME     U249 K19
 '@S9S_MB_2U_LIB.S9S_MB_2U(SCH_1):PAGE313_I1@PURE_QUANTA.LCMXO3LF9400C5BG484C(CHIPS)':
 'PR13A': CDS_PINID='PR13A';
NET_NAME
'NC_FPGA_PR14A'
 '@S9S_MB_2U_LIB.S9S_MB_2U(SCH_1):NC_FPGA_PR14A':
 C_SIGNAL='@s9s_mb_2u_lib.s9s_mb_2u(sch_1):nc_fpga_pr14a';
NODE_NAME     U249 L17
 '@S9S_MB_2U_LIB.S9S_MB_2U(SCH_1):PAGE313_I1@PURE_QUANTA.LCMXO3LF9400C5BG484C(CHIPS)':
 'PR14A': CDS_PINID='PR14A';
NET_NAME
'NC_FPGA_PR14B'
 '@S9S_MB_2U_LIB.S9S_MB_2U(SCH_1):NC_FPGA_PR14B':
 C_SIGNAL='@s9s_mb_2u_lib.s9s_mb_2u(sch_1):nc_fpga_pr14b';
NODE_NAME     U249 L16
 '@S9S_MB_2U_LIB.S9S_MB_2U(SCH_1):PAGE313_I1@PURE_QUANTA.LCMXO3LF9400C5BG484C(CHIPS)':
 'PR14B': CDS_PINID='PR14B';
NET_NAME
'NC_FPGA_PR16C'
 '@S9S_MB_2U_LIB.S9S_MB_2U(SCH_1):NC_FPGA_PR16C':
 C_SIGNAL='@s9s_mb_2u_lib.s9s_mb_2u(sch_1):nc_fpga_pr16c';
NODE_NAME     U249 L22
 '@S9S_MB_2U_LIB.S9S_MB_2U(SCH_1):PAGE313_I1@PURE_QUANTA.LCMXO3LF9400C5BG484C(CHIPS)':
 'PR16C': CDS_PINID='PR16C';
NET_NAME
'NC_FPGA_PR16D'
 '@S9S_MB_2U_LIB.S9S_MB_2U(SCH_1):NC_FPGA_PR16D':
 C_SIGNAL='@s9s_mb_2u_lib.s9s_mb_2u(sch_1):nc_fpga_pr16d';
NODE_NAME     U249 M17
 '@S9S_MB_2U_LIB.S9S_MB_2U(SCH_1):PAGE313_I1@PURE_QUANTA.LCMXO3LF9400C5BG484C(CHIPS)':
 'PR16D': CDS_PINID='PR16D';
NET_NAME
'NC_FPGA_PR30D'
 '@S9S_MB_2U_LIB.S9S_MB_2U(SCH_1):NC_FPGA_PR30D':
 C_SIGNAL='@s9s_mb_2u_lib.s9s_mb_2u(sch_1):nc_fpga_pr30d';
NODE_NAME     U249 Y20
 '@S9S_MB_2U_LIB.S9S_MB_2U(SCH_1):PAGE313_I1@PURE_QUANTA.LCMXO3LF9400C5BG484C(CHIPS)':
 'PR30D': CDS_PINID='PR30D';
NET_NAME
'NC_FPGA_PT41D'
 '@S9S_MB_2U_LIB.S9S_MB_2U(SCH_1):NC_FPGA_PT41D':
 C_SIGNAL='@s9s_mb_2u_lib.s9s_mb_2u(sch_1):nc_fpga_pt41d';
NODE_NAME     U249 D18
 '@S9S_MB_2U_LIB.S9S_MB_2U(SCH_1):PAGE314_I188@PURE_QUANTA.LCMXO3LF9400C5BG484C(CHIPS)':
 'PT41D': CDS_PINID='PT41D';
NET_NAME
'NC_FPGA_PT42D'
 '@S9S_MB_2U_LIB.S9S_MB_2U(SCH_1):NC_FPGA_PT42D':
 C_SIGNAL='@s9s_mb_2u_lib.s9s_mb_2u(sch_1):nc_fpga_pt42d';
NODE_NAME     U249 G15
 '@S9S_MB_2U_LIB.S9S_MB_2U(SCH_1):PAGE314_I188@PURE_QUANTA.LCMXO3LF9400C5BG484C(CHIPS)':
 'PT42D': CDS_PINID='PT42D';
NET_NAME
'NC_FPGA_PT43A'
 '@S9S_MB_2U_LIB.S9S_MB_2U(SCH_1):NC_FPGA_PT43A':
 C_SIGNAL='@s9s_mb_2u_lib.s9s_mb_2u(sch_1):nc_fpga_pt43a';
NODE_NAME     U249 A20
 '@S9S_MB_2U_LIB.S9S_MB_2U(SCH_1):PAGE314_I188@PURE_QUANTA.LCMXO3LF9400C5BG484C(CHIPS)':
 'PT43A||R_GPLLT': CDS_PINID='\pt43a||r_gpllt\';
NET_NAME
'NC_FPGA_PT43B'
 '@S9S_MB_2U_LIB.S9S_MB_2U(SCH_1):NC_FPGA_PT43B':
 C_SIGNAL='@s9s_mb_2u_lib.s9s_mb_2u(sch_1):nc_fpga_pt43b';
NODE_NAME     U249 B21
 '@S9S_MB_2U_LIB.S9S_MB_2U(SCH_1):PAGE314_I188@PURE_QUANTA.LCMXO3LF9400C5BG484C(CHIPS)':
 'PT43B||R_GPLLC': CDS_PINID='\pt43b||r_gpllc\';
NET_NAME
'NC_FPGA_PT43C'
 '@S9S_MB_2U_LIB.S9S_MB_2U(SCH_1):NC_FPGA_PT43C':
 C_SIGNAL='@s9s_mb_2u_lib.s9s_mb_2u(sch_1):nc_fpga_pt43c';
NODE_NAME     U249 C19
 '@S9S_MB_2U_LIB.S9S_MB_2U(SCH_1):PAGE314_I188@PURE_QUANTA.LCMXO3LF9400C5BG484C(CHIPS)':
 'PT43C': CDS_PINID='PT43C';
NET_NAME
'NC_FPGA_PT43D'
 '@S9S_MB_2U_LIB.S9S_MB_2U(SCH_1):NC_FPGA_PT43D':
 C_SIGNAL='@s9s_mb_2u_lib.s9s_mb_2u(sch_1):nc_fpga_pt43d';
NODE_NAME     U249 C20
 '@S9S_MB_2U_LIB.S9S_MB_2U(SCH_1):PAGE314_I188@PURE_QUANTA.LCMXO3LF9400C5BG484C(CHIPS)':
 'PT43D': CDS_PINID='PT43D';
NET_NAME
'NC_FPGA_PT44A'
 '@S9S_MB_2U_LIB.S9S_MB_2U(SCH_1):NC_FPGA_PT44A':
 C_SIGNAL='@s9s_mb_2u_lib.s9s_mb_2u(sch_1):nc_fpga_pt44a';
NODE_NAME     U249 A21
 '@S9S_MB_2U_LIB.S9S_MB_2U(SCH_1):PAGE314_I188@PURE_QUANTA.LCMXO3LF9400C5BG484C(CHIPS)':
 'PT44A||R_GPLLT': CDS_PINID='\pt44a||r_gpllt\';
NET_NAME
'NC_FPGA_PT44B'
 '@S9S_MB_2U_LIB.S9S_MB_2U(SCH_1):NC_FPGA_PT44B':
 C_SIGNAL='@s9s_mb_2u_lib.s9s_mb_2u(sch_1):nc_fpga_pt44b';
NODE_NAME     U249 B22
 '@S9S_MB_2U_LIB.S9S_MB_2U(SCH_1):PAGE314_I188@PURE_QUANTA.LCMXO3LF9400C5BG484C(CHIPS)':
 'PT44B||R_GPLLC': CDS_PINID='\pt44b||r_gpllc\';
NET_NAME
'NC_FPGA_PT44C'
 '@S9S_MB_2U_LIB.S9S_MB_2U(SCH_1):NC_FPGA_PT44C':
 C_SIGNAL='@s9s_mb_2u_lib.s9s_mb_2u(sch_1):nc_fpga_pt44c';
NODE_NAME     U249 F16
 '@S9S_MB_2U_LIB.S9S_MB_2U(SCH_1):PAGE311_I70@PURE_QUANTA.LCMXO3LF9400C5BG484C(CHIPS)':
 'PT44C||INITN': CDS_PINID='\pt44c||initn\';
NET_NAME
'NC_FPGA_PT44D'
 '@S9S_MB_2U_LIB.S9S_MB_2U(SCH_1):NC_FPGA_PT44D':
 C_SIGNAL='@s9s_mb_2u_lib.s9s_mb_2u(sch_1):nc_fpga_pt44d';
NODE_NAME     U249 E17
 '@S9S_MB_2U_LIB.S9S_MB_2U(SCH_1):PAGE311_I70@PURE_QUANTA.LCMXO3LF9400C5BG484C(CHIPS)':
 'PT44D||DONE': CDS_PINID='\pt44d||done\';
NET_NAME
'NC_HICCUP'
 '@S9S_MB_2U_LIB.S9S_MB_2U(SCH_1):NC_HICCUP':
 C_SIGNAL='@s9s_mb_2u_lib.s9s_mb_2u(sch_1):nc_hiccup';
NODE_NAME     PU9 35
 '@S9S_MB_2U_LIB.S9S_MB_2U(SCH_1):PAGE245_I95@PURE_QUANTA.IR3889MTRPBF(CHIPS)':
 'NC4': CDS_PINID='NC4';
NET_NAME
'NC_HSC_TYPE_NC0'
 '@S9S_MB_2U_LIB.S9S_MB_2U(SCH_1):NC_HSC_TYPE_NC0':
 C_SIGNAL='@s9s_mb_2u_lib.s9s_mb_2u(sch_1):nc_hsc_type_nc0';
NODE_NAME     U331 6
 '@S9S_MB_2U_LIB.S9S_MB_2U(SCH_1):PAGE240_I39@PURE_QUANTA.INA230AIRGTR(CHIPS)':
 'NC0': CDS_PINID='NC0';
NET_NAME
'NC_HSC_TYPE_NC1'
 '@S9S_MB_2U_LIB.S9S_MB_2U(SCH_1):NC_HSC_TYPE_NC1':
 C_SIGNAL='@s9s_mb_2u_lib.s9s_mb_2u(sch_1):nc_hsc_type_nc1';
NODE_NAME     U331 7
 '@S9S_MB_2U_LIB.S9S_MB_2U(SCH_1):PAGE240_I39@PURE_QUANTA.INA230AIRGTR(CHIPS)':
 'NC1': CDS_PINID='NC1';
NET_NAME
'NC_HSC_TYPE_NC2'
 '@S9S_MB_2U_LIB.S9S_MB_2U(SCH_1):NC_HSC_TYPE_NC2':
 C_SIGNAL='@s9s_mb_2u_lib.s9s_mb_2u(sch_1):nc_hsc_type_nc2';
NODE_NAME     U331 8
 '@S9S_MB_2U_LIB.S9S_MB_2U(SCH_1):PAGE240_I39@PURE_QUANTA.INA230AIRGTR(CHIPS)':
 'NC2': CDS_PINID='NC2';
NET_NAME
'NC_HSC_TYPE_NC3'
 '@S9S_MB_2U_LIB.S9S_MB_2U(SCH_1):NC_HSC_TYPE_NC3':
 C_SIGNAL='@s9s_mb_2u_lib.s9s_mb_2u(sch_1):nc_hsc_type_nc3';
NODE_NAME     U331 14
 '@S9S_MB_2U_LIB.S9S_MB_2U(SCH_1):PAGE240_I39@PURE_QUANTA.INA230AIRGTR(CHIPS)':
 'NC3': CDS_PINID='NC3';
NET_NAME
'NC_HSC_TYPE_NC4'
 '@S9S_MB_2U_LIB.S9S_MB_2U(SCH_1):NC_HSC_TYPE_NC4':
 C_SIGNAL='@s9s_mb_2u_lib.s9s_mb_2u(sch_1):nc_hsc_type_nc4';
NODE_NAME     U331 15
 '@S9S_MB_2U_LIB.S9S_MB_2U(SCH_1):PAGE240_I39@PURE_QUANTA.INA230AIRGTR(CHIPS)':
 'NC4': CDS_PINID='NC4';
NET_NAME
'NC_HSC_TYPE_NC5'
 '@S9S_MB_2U_LIB.S9S_MB_2U(SCH_1):NC_HSC_TYPE_NC5':
 C_SIGNAL='@s9s_mb_2u_lib.s9s_mb_2u(sch_1):nc_hsc_type_nc5';
NODE_NAME     U331 16
 '@S9S_MB_2U_LIB.S9S_MB_2U(SCH_1):PAGE240_I39@PURE_QUANTA.INA230AIRGTR(CHIPS)':
 'NC5': CDS_PINID='NC5';
NET_NAME
'NC_HSC_TYPE_VINM'
 '@S9S_MB_2U_LIB.S9S_MB_2U(SCH_1):NC_HSC_TYPE_VINM':
 C_SIGNAL='@s9s_mb_2u_lib.s9s_mb_2u(sch_1):nc_hsc_type_vinm';
NODE_NAME     U331 12
 '@S9S_MB_2U_LIB.S9S_MB_2U(SCH_1):PAGE240_I39@PURE_QUANTA.INA230AIRGTR(CHIPS)':
 'IN-': CDS_PINID='\in-\';
NET_NAME
'NC_HSC_TYPE_VINP'
 '@S9S_MB_2U_LIB.S9S_MB_2U(SCH_1):NC_HSC_TYPE_VINP':
 C_SIGNAL='@s9s_mb_2u_lib.s9s_mb_2u(sch_1):nc_hsc_type_vinp';
NODE_NAME     U331 13
 '@S9S_MB_2U_LIB.S9S_MB_2U(SCH_1):PAGE240_I39@PURE_QUANTA.INA230AIRGTR(CHIPS)':
 'IN+': CDS_PINID='\in+\';
NET_NAME
'NC_INA230_1_NC0'
 '@S9S_MB_2U_LIB.S9S_MB_2U(SCH_1):NC_INA230_1_NC0':
 C_SIGNAL='@s9s_mb_2u_lib.s9s_mb_2u(sch_1):nc_ina230_1_nc0';
NODE_NAME     U266 6
 '@S9S_MB_2U_LIB.S9S_MB_2U(SCH_1):PAGE295_I30@PURE_QUANTA.INA230AIRGTR(CHIPS)':
 'NC0': CDS_PINID='NC0';
NET_NAME
'NC_INA230_1_NC1'
 '@S9S_MB_2U_LIB.S9S_MB_2U(SCH_1):NC_INA230_1_NC1':
 C_SIGNAL='@s9s_mb_2u_lib.s9s_mb_2u(sch_1):nc_ina230_1_nc1';
NODE_NAME     U266 7
 '@S9S_MB_2U_LIB.S9S_MB_2U(SCH_1):PAGE295_I30@PURE_QUANTA.INA230AIRGTR(CHIPS)':
 'NC1': CDS_PINID='NC1';
NET_NAME
'NC_INA230_1_NC2'
 '@S9S_MB_2U_LIB.S9S_MB_2U(SCH_1):NC_INA230_1_NC2':
 C_SIGNAL='@s9s_mb_2u_lib.s9s_mb_2u(sch_1):nc_ina230_1_nc2';
NODE_NAME     U266 8
 '@S9S_MB_2U_LIB.S9S_MB_2U(SCH_1):PAGE295_I30@PURE_QUANTA.INA230AIRGTR(CHIPS)':
 'NC2': CDS_PINID='NC2';
NET_NAME
'NC_INA230_1_NC3'
 '@S9S_MB_2U_LIB.S9S_MB_2U(SCH_1):NC_INA230_1_NC3':
 C_SIGNAL='@s9s_mb_2u_lib.s9s_mb_2u(sch_1):nc_ina230_1_nc3';
NODE_NAME     U266 14
 '@S9S_MB_2U_LIB.S9S_MB_2U(SCH_1):PAGE295_I30@PURE_QUANTA.INA230AIRGTR(CHIPS)':
 'NC3': CDS_PINID='NC3';
NET_NAME
'NC_INA230_1_NC4'
 '@S9S_MB_2U_LIB.S9S_MB_2U(SCH_1):NC_INA230_1_NC4':
 C_SIGNAL='@s9s_mb_2u_lib.s9s_mb_2u(sch_1):nc_ina230_1_nc4';
NODE_NAME     U266 15
 '@S9S_MB_2U_LIB.S9S_MB_2U(SCH_1):PAGE295_I30@PURE_QUANTA.INA230AIRGTR(CHIPS)':
 'NC4': CDS_PINID='NC4';
NET_NAME
'NC_INA230_1_NC5'
 '@S9S_MB_2U_LIB.S9S_MB_2U(SCH_1):NC_INA230_1_NC5':
 C_SIGNAL='@s9s_mb_2u_lib.s9s_mb_2u(sch_1):nc_ina230_1_nc5';
NODE_NAME     U266 16
 '@S9S_MB_2U_LIB.S9S_MB_2U(SCH_1):PAGE295_I30@PURE_QUANTA.INA230AIRGTR(CHIPS)':
 'NC5': CDS_PINID='NC5';
NET_NAME
'NC_INA230_2_NC0'
 '@S9S_MB_2U_LIB.S9S_MB_2U(SCH_1):NC_INA230_2_NC0':
 C_SIGNAL='@s9s_mb_2u_lib.s9s_mb_2u(sch_1):nc_ina230_2_nc0';
NODE_NAME     U276 6
 '@S9S_MB_2U_LIB.S9S_MB_2U(SCH_1):PAGE295_I129@PURE_QUANTA.INA230AIRGTR(CHIPS)':
 'NC0': CDS_PINID='NC0';
NET_NAME
'NC_INA230_2_NC1'
 '@S9S_MB_2U_LIB.S9S_MB_2U(SCH_1):NC_INA230_2_NC1':
 C_SIGNAL='@s9s_mb_2u_lib.s9s_mb_2u(sch_1):nc_ina230_2_nc1';
NODE_NAME     U276 7
 '@S9S_MB_2U_LIB.S9S_MB_2U(SCH_1):PAGE295_I129@PURE_QUANTA.INA230AIRGTR(CHIPS)':
 'NC1': CDS_PINID='NC1';
NET_NAME
'NC_INA230_2_NC2'
 '@S9S_MB_2U_LIB.S9S_MB_2U(SCH_1):NC_INA230_2_NC2':
 C_SIGNAL='@s9s_mb_2u_lib.s9s_mb_2u(sch_1):nc_ina230_2_nc2';
NODE_NAME     U276 8
 '@S9S_MB_2U_LIB.S9S_MB_2U(SCH_1):PAGE295_I129@PURE_QUANTA.INA230AIRGTR(CHIPS)':
 'NC2': CDS_PINID='NC2';
NET_NAME
'NC_INA230_2_NC3'
 '@S9S_MB_2U_LIB.S9S_MB_2U(SCH_1):NC_INA230_2_NC3':
 C_SIGNAL='@s9s_mb_2u_lib.s9s_mb_2u(sch_1):nc_ina230_2_nc3';
NODE_NAME     U276 14
 '@S9S_MB_2U_LIB.S9S_MB_2U(SCH_1):PAGE295_I129@PURE_QUANTA.INA230AIRGTR(CHIPS)':
 'NC3': CDS_PINID='NC3';
NET_NAME
'NC_INA230_2_NC4'
 '@S9S_MB_2U_LIB.S9S_MB_2U(SCH_1):NC_INA230_2_NC4':
 C_SIGNAL='@s9s_mb_2u_lib.s9s_mb_2u(sch_1):nc_ina230_2_nc4';
NODE_NAME     U276 15
 '@S9S_MB_2U_LIB.S9S_MB_2U(SCH_1):PAGE295_I129@PURE_QUANTA.INA230AIRGTR(CHIPS)':
 'NC4': CDS_PINID='NC4';
NET_NAME
'NC_INA230_2_NC5'
 '@S9S_MB_2U_LIB.S9S_MB_2U(SCH_1):NC_INA230_2_NC5':
 C_SIGNAL='@s9s_mb_2u_lib.s9s_mb_2u(sch_1):nc_ina230_2_nc5';
NODE_NAME     U276 16
 '@S9S_MB_2U_LIB.S9S_MB_2U(SCH_1):PAGE295_I129@PURE_QUANTA.INA230AIRGTR(CHIPS)':
 'NC5': CDS_PINID='NC5';
NET_NAME
'NC_INA230_3_NC0'
 '@S9S_MB_2U_LIB.S9S_MB_2U(SCH_1):NC_INA230_3_NC0':
 C_SIGNAL='@s9s_mb_2u_lib.s9s_mb_2u(sch_1):nc_ina230_3_nc0';
NODE_NAME     U263 6
 '@S9S_MB_2U_LIB.S9S_MB_2U(SCH_1):PAGE163_I94@PURE_QUANTA.INA230AIRGTR(CHIPS)':
 'NC0': CDS_PINID='NC0';
NET_NAME
'NC_INA230_3_NC1'
 '@S9S_MB_2U_LIB.S9S_MB_2U(SCH_1):NC_INA230_3_NC1':
 C_SIGNAL='@s9s_mb_2u_lib.s9s_mb_2u(sch_1):nc_ina230_3_nc1';
NODE_NAME     U263 7
 '@S9S_MB_2U_LIB.S9S_MB_2U(SCH_1):PAGE163_I94@PURE_QUANTA.INA230AIRGTR(CHIPS)':
 'NC1': CDS_PINID='NC1';
NET_NAME
'NC_INA230_3_NC2'
 '@S9S_MB_2U_LIB.S9S_MB_2U(SCH_1):NC_INA230_3_NC2':
 C_SIGNAL='@s9s_mb_2u_lib.s9s_mb_2u(sch_1):nc_ina230_3_nc2';
NODE_NAME     U263 8
 '@S9S_MB_2U_LIB.S9S_MB_2U(SCH_1):PAGE163_I94@PURE_QUANTA.INA230AIRGTR(CHIPS)':
 'NC2': CDS_PINID='NC2';
NET_NAME
'NC_INA230_3_NC3'
 '@S9S_MB_2U_LIB.S9S_MB_2U(SCH_1):NC_INA230_3_NC3':
 C_SIGNAL='@s9s_mb_2u_lib.s9s_mb_2u(sch_1):nc_ina230_3_nc3';
NODE_NAME     U263 14
 '@S9S_MB_2U_LIB.S9S_MB_2U(SCH_1):PAGE163_I94@PURE_QUANTA.INA230AIRGTR(CHIPS)':
 'NC3': CDS_PINID='NC3';
NET_NAME
'NC_INA230_3_NC4'
 '@S9S_MB_2U_LIB.S9S_MB_2U(SCH_1):NC_INA230_3_NC4':
 C_SIGNAL='@s9s_mb_2u_lib.s9s_mb_2u(sch_1):nc_ina230_3_nc4';
NODE_NAME     U263 15
 '@S9S_MB_2U_LIB.S9S_MB_2U(SCH_1):PAGE163_I94@PURE_QUANTA.INA230AIRGTR(CHIPS)':
 'NC4': CDS_PINID='NC4';
NET_NAME
'NC_INA230_3_NC5'
 '@S9S_MB_2U_LIB.S9S_MB_2U(SCH_1):NC_INA230_3_NC5':
 C_SIGNAL='@s9s_mb_2u_lib.s9s_mb_2u(sch_1):nc_ina230_3_nc5';
NODE_NAME     U263 16
 '@S9S_MB_2U_LIB.S9S_MB_2U(SCH_1):PAGE163_I94@PURE_QUANTA.INA230AIRGTR(CHIPS)':
 'NC5': CDS_PINID='NC5';
NET_NAME
'NC_INA230_4_NC0'
 '@S9S_MB_2U_LIB.S9S_MB_2U(SCH_1):NC_INA230_4_NC0':
 C_SIGNAL='@s9s_mb_2u_lib.s9s_mb_2u(sch_1):nc_ina230_4_nc0';
NODE_NAME     U264 6
 '@S9S_MB_2U_LIB.S9S_MB_2U(SCH_1):PAGE163_I46@PURE_QUANTA.INA230AIRGTR(CHIPS)':
 'NC0': CDS_PINID='NC0';
NET_NAME
'NC_INA230_4_NC1'
 '@S9S_MB_2U_LIB.S9S_MB_2U(SCH_1):NC_INA230_4_NC1':
 C_SIGNAL='@s9s_mb_2u_lib.s9s_mb_2u(sch_1):nc_ina230_4_nc1';
NODE_NAME     U264 7
 '@S9S_MB_2U_LIB.S9S_MB_2U(SCH_1):PAGE163_I46@PURE_QUANTA.INA230AIRGTR(CHIPS)':
 'NC1': CDS_PINID='NC1';
NET_NAME
'NC_INA230_4_NC2'
 '@S9S_MB_2U_LIB.S9S_MB_2U(SCH_1):NC_INA230_4_NC2':
 C_SIGNAL='@s9s_mb_2u_lib.s9s_mb_2u(sch_1):nc_ina230_4_nc2';
NODE_NAME     U264 8
 '@S9S_MB_2U_LIB.S9S_MB_2U(SCH_1):PAGE163_I46@PURE_QUANTA.INA230AIRGTR(CHIPS)':
 'NC2': CDS_PINID='NC2';
NET_NAME
'NC_INA230_4_NC3'
 '@S9S_MB_2U_LIB.S9S_MB_2U(SCH_1):NC_INA230_4_NC3':
 C_SIGNAL='@s9s_mb_2u_lib.s9s_mb_2u(sch_1):nc_ina230_4_nc3';
NODE_NAME     U264 14
 '@S9S_MB_2U_LIB.S9S_MB_2U(SCH_1):PAGE163_I46@PURE_QUANTA.INA230AIRGTR(CHIPS)':
 'NC3': CDS_PINID='NC3';
NET_NAME
'NC_INA230_4_NC4'
 '@S9S_MB_2U_LIB.S9S_MB_2U(SCH_1):NC_INA230_4_NC4':
 C_SIGNAL='@s9s_mb_2u_lib.s9s_mb_2u(sch_1):nc_ina230_4_nc4';
NODE_NAME     U264 15
 '@S9S_MB_2U_LIB.S9S_MB_2U(SCH_1):PAGE163_I46@PURE_QUANTA.INA230AIRGTR(CHIPS)':
 'NC4': CDS_PINID='NC4';
NET_NAME
'NC_INA230_4_NC5'
 '@S9S_MB_2U_LIB.S9S_MB_2U(SCH_1):NC_INA230_4_NC5':
 C_SIGNAL='@s9s_mb_2u_lib.s9s_mb_2u(sch_1):nc_ina230_4_nc5';
NODE_NAME     U264 16
 '@S9S_MB_2U_LIB.S9S_MB_2U(SCH_1):PAGE163_I46@PURE_QUANTA.INA230AIRGTR(CHIPS)':
 'NC5': CDS_PINID='NC5';
NET_NAME
'NC_INA230_5_NC0'
 '@S9S_MB_2U_LIB.S9S_MB_2U(SCH_1):NC_INA230_5_NC0':
 C_SIGNAL='@s9s_mb_2u_lib.s9s_mb_2u(sch_1):nc_ina230_5_nc0';
NODE_NAME     U265 6
 '@S9S_MB_2U_LIB.S9S_MB_2U(SCH_1):PAGE163_I69@PURE_QUANTA.INA230AIRGTR(CHIPS)':
 'NC0': CDS_PINID='NC0';
NET_NAME
'NC_INA230_5_NC1'
 '@S9S_MB_2U_LIB.S9S_MB_2U(SCH_1):NC_INA230_5_NC1':
 C_SIGNAL='@s9s_mb_2u_lib.s9s_mb_2u(sch_1):nc_ina230_5_nc1';
NODE_NAME     U265 7
 '@S9S_MB_2U_LIB.S9S_MB_2U(SCH_1):PAGE163_I69@PURE_QUANTA.INA230AIRGTR(CHIPS)':
 'NC1': CDS_PINID='NC1';
NET_NAME
'NC_INA230_5_NC2'
 '@S9S_MB_2U_LIB.S9S_MB_2U(SCH_1):NC_INA230_5_NC2':
 C_SIGNAL='@s9s_mb_2u_lib.s9s_mb_2u(sch_1):nc_ina230_5_nc2';
NODE_NAME     U265 8
 '@S9S_MB_2U_LIB.S9S_MB_2U(SCH_1):PAGE163_I69@PURE_QUANTA.INA230AIRGTR(CHIPS)':
 'NC2': CDS_PINID='NC2';
NET_NAME
'NC_INA230_5_NC3'
 '@S9S_MB_2U_LIB.S9S_MB_2U(SCH_1):NC_INA230_5_NC3':
 C_SIGNAL='@s9s_mb_2u_lib.s9s_mb_2u(sch_1):nc_ina230_5_nc3';
NODE_NAME     U265 14
 '@S9S_MB_2U_LIB.S9S_MB_2U(SCH_1):PAGE163_I69@PURE_QUANTA.INA230AIRGTR(CHIPS)':
 'NC3': CDS_PINID='NC3';
NET_NAME
'NC_INA230_5_NC4'
 '@S9S_MB_2U_LIB.S9S_MB_2U(SCH_1):NC_INA230_5_NC4':
 C_SIGNAL='@s9s_mb_2u_lib.s9s_mb_2u(sch_1):nc_ina230_5_nc4';
NODE_NAME     U265 15
 '@S9S_MB_2U_LIB.S9S_MB_2U(SCH_1):PAGE163_I69@PURE_QUANTA.INA230AIRGTR(CHIPS)':
 'NC4': CDS_PINID='NC4';
NET_NAME
'NC_INA230_5_NC5'
 '@S9S_MB_2U_LIB.S9S_MB_2U(SCH_1):NC_INA230_5_NC5':
 C_SIGNAL='@s9s_mb_2u_lib.s9s_mb_2u(sch_1):nc_ina230_5_nc5';
NODE_NAME     U265 16
 '@S9S_MB_2U_LIB.S9S_MB_2U(SCH_1):PAGE163_I69@PURE_QUANTA.INA230AIRGTR(CHIPS)':
 'NC5': CDS_PINID='NC5';
NET_NAME
'NC_J106_A5'
 '@S9S_MB_2U_LIB.S9S_MB_2U(SCH_1):NC_J106_A5':
 C_SIGNAL='@s9s_mb_2u_lib.s9s_mb_2u(sch_1):nc_j106_a5';
NODE_NAME     J106 A5
 '@S9S_MB_2U_LIB.S9S_MB_2U(SCH_1):PAGE144_I68@PURE_QUANTA.CONN112_10137002101LF(CHIPS)':
 'A5': CDS_PINID='A5';
NET_NAME
'NC_J107_A1'
 '@S9S_MB_2U_LIB.S9S_MB_2U(SCH_1):NC_J107_A1':
 C_SIGNAL='@s9s_mb_2u_lib.s9s_mb_2u(sch_1):nc_j107_a1';
NODE_NAME     J107 A1
 '@S9S_MB_2U_LIB.S9S_MB_2U(SCH_1):PAGE317_I58@PURE_QUANTA.CONN112_10137002101LF(CHIPS)':
 'A1': CDS_PINID='A1';
NET_NAME
'NC_J107_A3'
 '@S9S_MB_2U_LIB.S9S_MB_2U(SCH_1):NC_J107_A3':
 C_SIGNAL='@s9s_mb_2u_lib.s9s_mb_2u(sch_1):nc_j107_a3';
NODE_NAME     J107 A3
 '@S9S_MB_2U_LIB.S9S_MB_2U(SCH_1):PAGE317_I58@PURE_QUANTA.CONN112_10137002101LF(CHIPS)':
 'A3': CDS_PINID='A3';
NET_NAME
'NC_J107_A5'
 '@S9S_MB_2U_LIB.S9S_MB_2U(SCH_1):NC_J107_A5':
 C_SIGNAL='@s9s_mb_2u_lib.s9s_mb_2u(sch_1):nc_j107_a5';
NODE_NAME     J107 A5
 '@S9S_MB_2U_LIB.S9S_MB_2U(SCH_1):PAGE317_I38@PURE_QUANTA.CONN112_10137002101LF(CHIPS)':
 'A5': CDS_PINID='A5';
NET_NAME
'NC_J107_N4'
 '@S9S_MB_2U_LIB.S9S_MB_2U(SCH_1):NC_J107_N4':
 C_SIGNAL='@s9s_mb_2u_lib.s9s_mb_2u(sch_1):nc_j107_n4';
NODE_NAME     J107 N4
 '@S9S_MB_2U_LIB.S9S_MB_2U(SCH_1):PAGE317_I58@PURE_QUANTA.CONN112_10137002101LF(CHIPS)':
 'N4': CDS_PINID='N4';
NET_NAME
'NC_J107_N6'
 '@S9S_MB_2U_LIB.S9S_MB_2U(SCH_1):NC_J107_N6':
 C_SIGNAL='@s9s_mb_2u_lib.s9s_mb_2u(sch_1):nc_j107_n6';
NODE_NAME     J107 N6
 '@S9S_MB_2U_LIB.S9S_MB_2U(SCH_1):PAGE317_I38@PURE_QUANTA.CONN112_10137002101LF(CHIPS)':
 'N6': CDS_PINID='N6';
NET_NAME
'NC_J108_N2'
 '@S9S_MB_2U_LIB.S9S_MB_2U(SCH_1):NC_J108_N2':
 C_SIGNAL='@s9s_mb_2u_lib.s9s_mb_2u(sch_1):nc_j108_n2';
NODE_NAME     J108 N2
 '@S9S_MB_2U_LIB.S9S_MB_2U(SCH_1):PAGE320_I57@PURE_QUANTA.CONN112_10137002101LF(CHIPS)':
 'N2': CDS_PINID='N2';
NET_NAME
'NC_J108_N4'
 '@S9S_MB_2U_LIB.S9S_MB_2U(SCH_1):NC_J108_N4':
 C_SIGNAL='@s9s_mb_2u_lib.s9s_mb_2u(sch_1):nc_j108_n4';
NODE_NAME     J108 N4
 '@S9S_MB_2U_LIB.S9S_MB_2U(SCH_1):PAGE320_I57@PURE_QUANTA.CONN112_10137002101LF(CHIPS)':
 'N4': CDS_PINID='N4';
NET_NAME
'NC_J108_N6'
 '@S9S_MB_2U_LIB.S9S_MB_2U(SCH_1):NC_J108_N6':
 C_SIGNAL='@s9s_mb_2u_lib.s9s_mb_2u(sch_1):nc_j108_n6';
NODE_NAME     J108 N6
 '@S9S_MB_2U_LIB.S9S_MB_2U(SCH_1):PAGE320_I76@PURE_QUANTA.CONN112_10137002101LF(CHIPS)':
 'N6': CDS_PINID='N6';
NET_NAME
'NC_J112_N2'
 '@S9S_MB_2U_LIB.S9S_MB_2U(SCH_1):NC_J112_N2':
 C_SIGNAL='@s9s_mb_2u_lib.s9s_mb_2u(sch_1):nc_j112_n2';
NODE_NAME     J112 N2
 '@S9S_MB_2U_LIB.S9S_MB_2U(SCH_1):PAGE149_I76@PURE_QUANTA.CONN160_10131762101LF(CHIPS)':
 'N2': CDS_PINID='N2';
NET_NAME
'NC_J112_O2'
 '@S9S_MB_2U_LIB.S9S_MB_2U(SCH_1):NC_J112_O2':
 C_SIGNAL='@s9s_mb_2u_lib.s9s_mb_2u(sch_1):nc_j112_o2';
NODE_NAME     J112 O2
 '@S9S_MB_2U_LIB.S9S_MB_2U(SCH_1):PAGE149_I76@PURE_QUANTA.CONN160_10131762101LF(CHIPS)':
 'O2': CDS_PINID='O2';
NET_NAME
'NC_J112_O5'
 '@S9S_MB_2U_LIB.S9S_MB_2U(SCH_1):NC_J112_O5':
 C_SIGNAL='@s9s_mb_2u_lib.s9s_mb_2u(sch_1):nc_j112_o5';
NODE_NAME     J112 O5
 '@S9S_MB_2U_LIB.S9S_MB_2U(SCH_1):PAGE149_I75@PURE_QUANTA.CONN160_10131762101LF(CHIPS)':
 'O5': CDS_PINID='O5';
NET_NAME
'NC_J112_P5'
 '@S9S_MB_2U_LIB.S9S_MB_2U(SCH_1):NC_J112_P5':
 C_SIGNAL='@s9s_mb_2u_lib.s9s_mb_2u(sch_1):nc_j112_p5';
NODE_NAME     J112 P5
 '@S9S_MB_2U_LIB.S9S_MB_2U(SCH_1):PAGE149_I75@PURE_QUANTA.CONN160_10131762101LF(CHIPS)':
 'P5': CDS_PINID='P5';
NET_NAME
'NC_J112_R5'
 '@S9S_MB_2U_LIB.S9S_MB_2U(SCH_1):NC_J112_R5':
 C_SIGNAL='@s9s_mb_2u_lib.s9s_mb_2u(sch_1):nc_j112_r5';
NODE_NAME     J112 R5
 '@S9S_MB_2U_LIB.S9S_MB_2U(SCH_1):PAGE149_I75@PURE_QUANTA.CONN160_10131762101LF(CHIPS)':
 'R5': CDS_PINID='R5';
NET_NAME
'NC_J112_S5'
 '@S9S_MB_2U_LIB.S9S_MB_2U(SCH_1):NC_J112_S5':
 C_SIGNAL='@s9s_mb_2u_lib.s9s_mb_2u(sch_1):nc_j112_s5';
NODE_NAME     J112 S5
 '@S9S_MB_2U_LIB.S9S_MB_2U(SCH_1):PAGE149_I75@PURE_QUANTA.CONN160_10131762101LF(CHIPS)':
 'S5': CDS_PINID='S5';
NET_NAME
'NC_M2_0_NC1'
 '@S9S_MB_2U_LIB.S9S_MB_2U(SCH_1):NC_M2_0_NC1':
 C_SIGNAL='@s9s_mb_2u_lib.s9s_mb_2u(sch_1):nc_m2_0_nc1';
NODE_NAME     J59 6
 '@S9S_MB_2U_LIB.S9S_MB_2U(SCH_1):PAGE182_I178@PURE_QUANTA.SCONN75K_APCI0155P004A(CHIPS)':
 'NC1': CDS_PINID='NC1';
NET_NAME
'NC_M2_0_NC10'
 '@S9S_MB_2U_LIB.S9S_MB_2U(SCH_1):NC_M2_0_NC10':
 C_SIGNAL='@s9s_mb_2u_lib.s9s_mb_2u(sch_1):nc_m2_0_nc10';
NODE_NAME     J59 34
 '@S9S_MB_2U_LIB.S9S_MB_2U(SCH_1):PAGE182_I178@PURE_QUANTA.SCONN75K_APCI0155P004A(CHIPS)':
 'NC10': CDS_PINID='NC10';
NET_NAME
'NC_M2_0_NC11'
 '@S9S_MB_2U_LIB.S9S_MB_2U(SCH_1):NC_M2_0_NC11':
 C_SIGNAL='@s9s_mb_2u_lib.s9s_mb_2u(sch_1):nc_m2_0_nc11';
NODE_NAME     J59 36
 '@S9S_MB_2U_LIB.S9S_MB_2U(SCH_1):PAGE182_I178@PURE_QUANTA.SCONN75K_APCI0155P004A(CHIPS)':
 'NC11': CDS_PINID='NC11';
NET_NAME
'NC_M2_0_NC14'
 '@S9S_MB_2U_LIB.S9S_MB_2U(SCH_1):NC_M2_0_NC14':
 C_SIGNAL='@s9s_mb_2u_lib.s9s_mb_2u(sch_1):nc_m2_0_nc14';
NODE_NAME     J59 44
 '@S9S_MB_2U_LIB.S9S_MB_2U(SCH_1):PAGE182_I178@PURE_QUANTA.SCONN75K_APCI0155P004A(CHIPS)':
 'NC14': CDS_PINID='NC14';
NET_NAME
'NC_M2_0_NC15'
 '@S9S_MB_2U_LIB.S9S_MB_2U(SCH_1):NC_M2_0_NC15':
 C_SIGNAL='@s9s_mb_2u_lib.s9s_mb_2u(sch_1):nc_m2_0_nc15';
NODE_NAME     J59 46
 '@S9S_MB_2U_LIB.S9S_MB_2U(SCH_1):PAGE182_I178@PURE_QUANTA.SCONN75K_APCI0155P004A(CHIPS)':
 'NC15': CDS_PINID='NC15';
NET_NAME
'NC_M2_0_NC16'
 '@S9S_MB_2U_LIB.S9S_MB_2U(SCH_1):NC_M2_0_NC16':
 C_SIGNAL='@s9s_mb_2u_lib.s9s_mb_2u(sch_1):nc_m2_0_nc16';
NODE_NAME     J59 48
 '@S9S_MB_2U_LIB.S9S_MB_2U(SCH_1):PAGE182_I178@PURE_QUANTA.SCONN75K_APCI0155P004A(CHIPS)':
 'NC16': CDS_PINID='NC16';
NET_NAME
'NC_M2_0_NC17'
 '@S9S_MB_2U_LIB.S9S_MB_2U(SCH_1):NC_M2_0_NC17':
 C_SIGNAL='@s9s_mb_2u_lib.s9s_mb_2u(sch_1):nc_m2_0_nc17';
NODE_NAME     J59 56
 '@S9S_MB_2U_LIB.S9S_MB_2U(SCH_1):PAGE182_I178@PURE_QUANTA.SCONN75K_APCI0155P004A(CHIPS)':
 'NC17': CDS_PINID='NC17';
NET_NAME
'NC_M2_0_NC18'
 '@S9S_MB_2U_LIB.S9S_MB_2U(SCH_1):NC_M2_0_NC18':
 C_SIGNAL='@s9s_mb_2u_lib.s9s_mb_2u(sch_1):nc_m2_0_nc18';
NODE_NAME     J59 58
 '@S9S_MB_2U_LIB.S9S_MB_2U(SCH_1):PAGE182_I178@PURE_QUANTA.SCONN75K_APCI0155P004A(CHIPS)':
 'NC18': CDS_PINID='NC18';
NET_NAME
'NC_M2_0_NC19'
 '@S9S_MB_2U_LIB.S9S_MB_2U(SCH_1):NC_M2_0_NC19':
 C_SIGNAL='@s9s_mb_2u_lib.s9s_mb_2u(sch_1):nc_m2_0_nc19';
NODE_NAME     J59 67
 '@S9S_MB_2U_LIB.S9S_MB_2U(SCH_1):PAGE182_I178@PURE_QUANTA.SCONN75K_APCI0155P004A(CHIPS)':
 'NC19': CDS_PINID='NC19';
NET_NAME
'NC_M2_0_NC2'
 '@S9S_MB_2U_LIB.S9S_MB_2U(SCH_1):NC_M2_0_NC2':
 C_SIGNAL='@s9s_mb_2u_lib.s9s_mb_2u(sch_1):nc_m2_0_nc2';
NODE_NAME     J59 8
 '@S9S_MB_2U_LIB.S9S_MB_2U(SCH_1):PAGE182_I178@PURE_QUANTA.SCONN75K_APCI0155P004A(CHIPS)':
 'NC2': CDS_PINID='NC2';
NET_NAME
'NC_M2_0_NC3'
 '@S9S_MB_2U_LIB.S9S_MB_2U(SCH_1):NC_M2_0_NC3':
 C_SIGNAL='@s9s_mb_2u_lib.s9s_mb_2u(sch_1):nc_m2_0_nc3';
NODE_NAME     J59 20
 '@S9S_MB_2U_LIB.S9S_MB_2U(SCH_1):PAGE182_I178@PURE_QUANTA.SCONN75K_APCI0155P004A(CHIPS)':
 'NC3': CDS_PINID='NC3';
NET_NAME
'NC_M2_0_NC4'
 '@S9S_MB_2U_LIB.S9S_MB_2U(SCH_1):NC_M2_0_NC4':
 C_SIGNAL='@s9s_mb_2u_lib.s9s_mb_2u(sch_1):nc_m2_0_nc4';
NODE_NAME     J59 22
 '@S9S_MB_2U_LIB.S9S_MB_2U(SCH_1):PAGE182_I178@PURE_QUANTA.SCONN75K_APCI0155P004A(CHIPS)':
 'NC4': CDS_PINID='NC4';
NET_NAME
'NC_M2_0_NC5'
 '@S9S_MB_2U_LIB.S9S_MB_2U(SCH_1):NC_M2_0_NC5':
 C_SIGNAL='@s9s_mb_2u_lib.s9s_mb_2u(sch_1):nc_m2_0_nc5';
NODE_NAME     J59 24
 '@S9S_MB_2U_LIB.S9S_MB_2U(SCH_1):PAGE182_I178@PURE_QUANTA.SCONN75K_APCI0155P004A(CHIPS)':
 'NC5': CDS_PINID='NC5';
NET_NAME
'NC_M2_0_NC6'
 '@S9S_MB_2U_LIB.S9S_MB_2U(SCH_1):NC_M2_0_NC6':
 C_SIGNAL='@s9s_mb_2u_lib.s9s_mb_2u(sch_1):nc_m2_0_nc6';
NODE_NAME     J59 26
 '@S9S_MB_2U_LIB.S9S_MB_2U(SCH_1):PAGE182_I178@PURE_QUANTA.SCONN75K_APCI0155P004A(CHIPS)':
 'NC6': CDS_PINID='NC6';
NET_NAME
'NC_M2_0_NC7'
 '@S9S_MB_2U_LIB.S9S_MB_2U(SCH_1):NC_M2_0_NC7':
 C_SIGNAL='@s9s_mb_2u_lib.s9s_mb_2u(sch_1):nc_m2_0_nc7';
NODE_NAME     J59 28
 '@S9S_MB_2U_LIB.S9S_MB_2U(SCH_1):PAGE182_I178@PURE_QUANTA.SCONN75K_APCI0155P004A(CHIPS)':
 'NC7': CDS_PINID='NC7';
NET_NAME
'NC_M2_0_NC8'
 '@S9S_MB_2U_LIB.S9S_MB_2U(SCH_1):NC_M2_0_NC8':
 C_SIGNAL='@s9s_mb_2u_lib.s9s_mb_2u(sch_1):nc_m2_0_nc8';
NODE_NAME     J59 30
 '@S9S_MB_2U_LIB.S9S_MB_2U(SCH_1):PAGE182_I178@PURE_QUANTA.SCONN75K_APCI0155P004A(CHIPS)':
 'NC8': CDS_PINID='NC8';
NET_NAME
'NC_M2_0_NC9'
 '@S9S_MB_2U_LIB.S9S_MB_2U(SCH_1):NC_M2_0_NC9':
 C_SIGNAL='@s9s_mb_2u_lib.s9s_mb_2u(sch_1):nc_m2_0_nc9';
NODE_NAME     J59 32
 '@S9S_MB_2U_LIB.S9S_MB_2U(SCH_1):PAGE182_I178@PURE_QUANTA.SCONN75K_APCI0155P004A(CHIPS)':
 'NC9': CDS_PINID='NC9';
NET_NAME
'NC_M2_0_SUSCLK'
 '@S9S_MB_2U_LIB.S9S_MB_2U(SCH_1):NC_M2_0_SUSCLK':
 C_SIGNAL='@s9s_mb_2u_lib.s9s_mb_2u(sch_1):nc_m2_0_susclk';
NODE_NAME     J59 68
 '@S9S_MB_2U_LIB.S9S_MB_2U(SCH_1):PAGE182_I178@PURE_QUANTA.SCONN75K_APCI0155P004A(CHIPS)':
 'SUSCLK': CDS_PINID='SUSCLK';
NET_NAME
'NC_MIPI60_P9'
 '@S9S_MB_2U_LIB.S9S_MB_2U(SCH_1):NC_MIPI60_P9':
 C_SIGNAL='@s9s_mb_2u_lib.s9s_mb_2u(sch_1):nc_mipi60_p9';
NODE_NAME     J42 9
 '@S9S_MB_2U_LIB.S9S_MB_2U(SCH_1):PAGE133_I44@PURE_QUANTA.SCONN60_ASP21410801(CHIPS)':
 '9': CDS_PINID='\9\';
NET_NAME
'NC_PCH_RSVD<10>'
 '@S9S_MB_2U_LIB.S9S_MB_2U(SCH_1):NC_PCH_RSVD'<10>:
 C_SIGNAL='@s9s_mb_2u_lib.s9s_mb_2u(sch_1):nc_pch_rsvd(10)';
NODE_NAME     U4 N40
 '@S9S_MB_2U_LIB.S9S_MB_2U(SCH_1):PAGE173_I110@PURE_QUANTA.EMMITSBURG_REV0P9(CHIPS)':
 'RSVD_N40': CDS_PINID='RSVD_N40';
NET_NAME
'NC_PCH_RSVD<11>'
 '@S9S_MB_2U_LIB.S9S_MB_2U(SCH_1):NC_PCH_RSVD'<11>:
 C_SIGNAL='@s9s_mb_2u_lib.s9s_mb_2u(sch_1):nc_pch_rsvd(11)';
NODE_NAME     U4 N42
 '@S9S_MB_2U_LIB.S9S_MB_2U(SCH_1):PAGE173_I110@PURE_QUANTA.EMMITSBURG_REV0P9(CHIPS)':
 'RSVD_N42': CDS_PINID='RSVD_N42';
NET_NAME
'NC_PCH_RSVD<14>'
 '@S9S_MB_2U_LIB.S9S_MB_2U(SCH_1):NC_PCH_RSVD'<14>:
 C_SIGNAL='@s9s_mb_2u_lib.s9s_mb_2u(sch_1):nc_pch_rsvd(14)';
NODE_NAME     U4 BC40
 '@S9S_MB_2U_LIB.S9S_MB_2U(SCH_1):PAGE172_I11@PURE_QUANTA.EMMITSBURG_REV0P9(CHIPS)':
 'RSVD_BC40': CDS_PINID='RSVD_BC40';
NET_NAME
'NC_PCH_RSVD<17>'
 '@S9S_MB_2U_LIB.S9S_MB_2U(SCH_1):NC_PCH_RSVD'<17>:
 C_SIGNAL='@s9s_mb_2u_lib.s9s_mb_2u(sch_1):nc_pch_rsvd(17)';
NODE_NAME     U4 BG36
 '@S9S_MB_2U_LIB.S9S_MB_2U(SCH_1):PAGE174_I36@PURE_QUANTA.EMMITSBURG_REV0P9(CHIPS)':
 'RSVD_BG36': CDS_PINID='RSVD_BG36';
NET_NAME
'NC_PCH_RSVD<3>'
 '@S9S_MB_2U_LIB.S9S_MB_2U(SCH_1):NC_PCH_RSVD'<3>:
 C_SIGNAL='@s9s_mb_2u_lib.s9s_mb_2u(sch_1):nc_pch_rsvd(3)';
NODE_NAME     U4 AW26
 '@S9S_MB_2U_LIB.S9S_MB_2U(SCH_1):PAGE174_I36@PURE_QUANTA.EMMITSBURG_REV0P9(CHIPS)':
 'RSVD_AW23': CDS_PINID='RSVD_AW23';
NET_NAME
'NC_PCH_RSVD<4>'
 '@S9S_MB_2U_LIB.S9S_MB_2U(SCH_1):NC_PCH_RSVD'<4>:
 C_SIGNAL='@s9s_mb_2u_lib.s9s_mb_2u(sch_1):nc_pch_rsvd(4)';
NODE_NAME     U4 AV21
 '@S9S_MB_2U_LIB.S9S_MB_2U(SCH_1):PAGE174_I36@PURE_QUANTA.EMMITSBURG_REV0P9(CHIPS)':
 'RSVD_AV21': CDS_PINID='RSVD_AV21';
NET_NAME
'NC_PCH_RSVD<5>'
 '@S9S_MB_2U_LIB.S9S_MB_2U(SCH_1):NC_PCH_RSVD'<5>:
 C_SIGNAL='@s9s_mb_2u_lib.s9s_mb_2u(sch_1):nc_pch_rsvd(5)';
NODE_NAME     U4 BF39
 '@S9S_MB_2U_LIB.S9S_MB_2U(SCH_1):PAGE174_I36@PURE_QUANTA.EMMITSBURG_REV0P9(CHIPS)':
 'RSVD_BF39': CDS_PINID='RSVD_BF39';
NET_NAME
'NC_PCH_RSVD<8>'
 '@S9S_MB_2U_LIB.S9S_MB_2U(SCH_1):NC_PCH_RSVD'<8>:
 C_SIGNAL='@s9s_mb_2u_lib.s9s_mb_2u(sch_1):nc_pch_rsvd(8)';
NODE_NAME     U4 C40
 '@S9S_MB_2U_LIB.S9S_MB_2U(SCH_1):PAGE173_I110@PURE_QUANTA.EMMITSBURG_REV0P9(CHIPS)':
 'RSVD_C40': CDS_PINID='RSVD_C40';
NET_NAME
'NC_PCH_RSVD<9>'
 '@S9S_MB_2U_LIB.S9S_MB_2U(SCH_1):NC_PCH_RSVD'<9>:
 C_SIGNAL='@s9s_mb_2u_lib.s9s_mb_2u(sch_1):nc_pch_rsvd(9)';
NODE_NAME     U4 D39
 '@S9S_MB_2U_LIB.S9S_MB_2U(SCH_1):PAGE173_I110@PURE_QUANTA.EMMITSBURG_REV0P9(CHIPS)':
 'RSVD_D39': CDS_PINID='RSVD_D39';
NET_NAME
'NC_PU9_1'
 '@S9S_MB_2U_LIB.S9S_MB_2U(SCH_1):NC_PU9_1':
 C_SIGNAL='@s9s_mb_2u_lib.s9s_mb_2u(sch_1):nc_pu9_1';
NODE_NAME     PU9 33
 '@S9S_MB_2U_LIB.S9S_MB_2U(SCH_1):PAGE245_I95@PURE_QUANTA.IR3889MTRPBF(CHIPS)':
 'NC2': CDS_PINID='NC2';
NET_NAME
'NC_PU9_2'
 '@S9S_MB_2U_LIB.S9S_MB_2U(SCH_1):NC_PU9_2':
 C_SIGNAL='@s9s_mb_2u_lib.s9s_mb_2u(sch_1):nc_pu9_2';
NODE_NAME     PU9 34
 '@S9S_MB_2U_LIB.S9S_MB_2U(SCH_1):PAGE245_I95@PURE_QUANTA.IR3889MTRPBF(CHIPS)':
 'NC3': CDS_PINID='NC3';
NET_NAME
'NC_PU9_3'
 '@S9S_MB_2U_LIB.S9S_MB_2U(SCH_1):NC_PU9_3':
 C_SIGNAL='@s9s_mb_2u_lib.s9s_mb_2u(sch_1):nc_pu9_3';
NODE_NAME     PU9 6
 '@S9S_MB_2U_LIB.S9S_MB_2U(SCH_1):PAGE245_I95@PURE_QUANTA.IR3889MTRPBF(CHIPS)':
 'GATEL1': CDS_PINID='GATEL1';
NET_NAME
'NC_PU9_4'
 '@S9S_MB_2U_LIB.S9S_MB_2U(SCH_1):NC_PU9_4':
 C_SIGNAL='@s9s_mb_2u_lib.s9s_mb_2u(sch_1):nc_pu9_4';
NODE_NAME     PU9 37
 '@S9S_MB_2U_LIB.S9S_MB_2U(SCH_1):PAGE245_I95@PURE_QUANTA.IR3889MTRPBF(CHIPS)':
 'GATEL2': CDS_PINID='GATEL2';
NET_NAME
'NC_PVCCD_HV_CPU0_ACSP2'
 '@S9S_MB_2U_LIB.S9S_MB_2U(SCH_1):NC_PVCCD_HV_CPU0_ACSP2':
 C_SIGNAL='@s9s_mb_2u_lib.s9s_mb_2u(sch_1):nc_pvccd_hv_cpu0_acsp2';
NODE_NAME     PU35 24
 '@S9S_MB_2U_LIB.S9S_MB_2U(SCH_1):PAGE264_I53@PURE_QUANTA.ISL69260IRAZT(CHIPS)':
 'CS6': CDS_PINID='CS6';
NODE_NAME     PR4230 1
 '@S9S_MB_2U_LIB.S9S_MB_2U(SCH_1):PAGE264_I74@PURE_QUANTA.Q_RES(CHIPS)':
 'A': CDS_PINID='A';
NET_NAME
'NC_PVCCD_HV_CPU0_ACSP3'
 '@S9S_MB_2U_LIB.S9S_MB_2U(SCH_1):NC_PVCCD_HV_CPU0_ACSP3':
 C_SIGNAL='@s9s_mb_2u_lib.s9s_mb_2u(sch_1):nc_pvccd_hv_cpu0_acsp3';
NODE_NAME     PU35 25
 '@S9S_MB_2U_LIB.S9S_MB_2U(SCH_1):PAGE264_I53@PURE_QUANTA.ISL69260IRAZT(CHIPS)':
 'CS5': CDS_PINID='CS5';
NODE_NAME     PR4231 1
 '@S9S_MB_2U_LIB.S9S_MB_2U(SCH_1):PAGE264_I69@PURE_QUANTA.Q_RES(CHIPS)':
 'A': CDS_PINID='A';
NET_NAME
'NC_PVCCD_HV_CPU0_ACSP4'
 '@S9S_MB_2U_LIB.S9S_MB_2U(SCH_1):NC_PVCCD_HV_CPU0_ACSP4':
 C_SIGNAL='@s9s_mb_2u_lib.s9s_mb_2u(sch_1):nc_pvccd_hv_cpu0_acsp4';
NODE_NAME     PU35 26
 '@S9S_MB_2U_LIB.S9S_MB_2U(SCH_1):PAGE264_I53@PURE_QUANTA.ISL69260IRAZT(CHIPS)':
 'CS4': CDS_PINID='CS4';
NODE_NAME     PR4232 1
 '@S9S_MB_2U_LIB.S9S_MB_2U(SCH_1):PAGE264_I68@PURE_QUANTA.Q_RES(CHIPS)':
 'A': CDS_PINID='A';
NET_NAME
'NC_PVCCD_HV_CPU0_ACSP5'
 '@S9S_MB_2U_LIB.S9S_MB_2U(SCH_1):NC_PVCCD_HV_CPU0_ACSP5':
 C_SIGNAL='@s9s_mb_2u_lib.s9s_mb_2u(sch_1):nc_pvccd_hv_cpu0_acsp5';
NODE_NAME     PU35 27
 '@S9S_MB_2U_LIB.S9S_MB_2U(SCH_1):PAGE264_I53@PURE_QUANTA.ISL69260IRAZT(CHIPS)':
 'CS3': CDS_PINID='CS3';
NODE_NAME     PR4233 1
 '@S9S_MB_2U_LIB.S9S_MB_2U(SCH_1):PAGE264_I67@PURE_QUANTA.Q_RES(CHIPS)':
 'A': CDS_PINID='A';
NET_NAME
'NC_PVCCD_HV_CPU0_ACSP6'
 '@S9S_MB_2U_LIB.S9S_MB_2U(SCH_1):NC_PVCCD_HV_CPU0_ACSP6':
 C_SIGNAL='@s9s_mb_2u_lib.s9s_mb_2u(sch_1):nc_pvccd_hv_cpu0_acsp6';
NODE_NAME     PU35 28
 '@S9S_MB_2U_LIB.S9S_MB_2U(SCH_1):PAGE264_I53@PURE_QUANTA.ISL69260IRAZT(CHIPS)':
 'CS2': CDS_PINID='CS2';
NODE_NAME     PR4234 1
 '@S9S_MB_2U_LIB.S9S_MB_2U(SCH_1):PAGE264_I66@PURE_QUANTA.Q_RES(CHIPS)':
 'A': CDS_PINID='A';
NET_NAME
'NC_PVCCD_HV_CPU0_ACSP7'
 '@S9S_MB_2U_LIB.S9S_MB_2U(SCH_1):NC_PVCCD_HV_CPU0_ACSP7':
 C_SIGNAL='@s9s_mb_2u_lib.s9s_mb_2u(sch_1):nc_pvccd_hv_cpu0_acsp7';
NODE_NAME     PU35 29
 '@S9S_MB_2U_LIB.S9S_MB_2U(SCH_1):PAGE264_I53@PURE_QUANTA.ISL69260IRAZT(CHIPS)':
 'CS1': CDS_PINID='CS1';
NODE_NAME     PR4235 1
 '@S9S_MB_2U_LIB.S9S_MB_2U(SCH_1):PAGE264_I62@PURE_QUANTA.Q_RES(CHIPS)':
 'A': CDS_PINID='A';
NET_NAME
'NC_PVCCD_HV_CPU0_ACSP8'
 '@S9S_MB_2U_LIB.S9S_MB_2U(SCH_1):NC_PVCCD_HV_CPU0_ACSP8':
 C_SIGNAL='@s9s_mb_2u_lib.s9s_mb_2u(sch_1):nc_pvccd_hv_cpu0_acsp8';
NODE_NAME     PU35 30
 '@S9S_MB_2U_LIB.S9S_MB_2U(SCH_1):PAGE264_I53@PURE_QUANTA.ISL69260IRAZT(CHIPS)':
 'CS0': CDS_PINID='CS0';
NODE_NAME     PR4236 1
 '@S9S_MB_2U_LIB.S9S_MB_2U(SCH_1):PAGE264_I61@PURE_QUANTA.Q_RES(CHIPS)':
 'A': CDS_PINID='A';
NET_NAME
'NC_PVCCD_HV_CPU0_APWM2'
 '@S9S_MB_2U_LIB.S9S_MB_2U(SCH_1):NC_PVCCD_HV_CPU0_APWM2':
 C_SIGNAL='@s9s_mb_2u_lib.s9s_mb_2u(sch_1):nc_pvccd_hv_cpu0_apwm2';
NODE_NAME     PU35 7
 '@S9S_MB_2U_LIB.S9S_MB_2U(SCH_1):PAGE264_I53@PURE_QUANTA.ISL69260IRAZT(CHIPS)':
 'PWM6': CDS_PINID='PWM6';
NET_NAME
'NC_PVCCD_HV_CPU0_APWM3'
 '@S9S_MB_2U_LIB.S9S_MB_2U(SCH_1):NC_PVCCD_HV_CPU0_APWM3':
 C_SIGNAL='@s9s_mb_2u_lib.s9s_mb_2u(sch_1):nc_pvccd_hv_cpu0_apwm3';
NODE_NAME     PU35 6
 '@S9S_MB_2U_LIB.S9S_MB_2U(SCH_1):PAGE264_I53@PURE_QUANTA.ISL69260IRAZT(CHIPS)':
 'PWM5': CDS_PINID='PWM5';
NET_NAME
'NC_PVCCD_HV_CPU0_APWM4'
 '@S9S_MB_2U_LIB.S9S_MB_2U(SCH_1):NC_PVCCD_HV_CPU0_APWM4':
 C_SIGNAL='@s9s_mb_2u_lib.s9s_mb_2u(sch_1):nc_pvccd_hv_cpu0_apwm4';
NODE_NAME     PU35 5
 '@S9S_MB_2U_LIB.S9S_MB_2U(SCH_1):PAGE264_I53@PURE_QUANTA.ISL69260IRAZT(CHIPS)':
 'PWM4': CDS_PINID='PWM4';
NET_NAME
'NC_PVCCD_HV_CPU0_APWM5'
 '@S9S_MB_2U_LIB.S9S_MB_2U(SCH_1):NC_PVCCD_HV_CPU0_APWM5':
 C_SIGNAL='@s9s_mb_2u_lib.s9s_mb_2u(sch_1):nc_pvccd_hv_cpu0_apwm5';
NODE_NAME     PU35 4
 '@S9S_MB_2U_LIB.S9S_MB_2U(SCH_1):PAGE264_I53@PURE_QUANTA.ISL69260IRAZT(CHIPS)':
 'PWM3': CDS_PINID='PWM3';
NET_NAME
'NC_PVCCD_HV_CPU0_APWM6'
 '@S9S_MB_2U_LIB.S9S_MB_2U(SCH_1):NC_PVCCD_HV_CPU0_APWM6':
 C_SIGNAL='@s9s_mb_2u_lib.s9s_mb_2u(sch_1):nc_pvccd_hv_cpu0_apwm6';
NODE_NAME     PU35 3
 '@S9S_MB_2U_LIB.S9S_MB_2U(SCH_1):PAGE264_I53@PURE_QUANTA.ISL69260IRAZT(CHIPS)':
 'PWM2': CDS_PINID='PWM2';
NET_NAME
'NC_PVCCD_HV_CPU0_APWM7'
 '@S9S_MB_2U_LIB.S9S_MB_2U(SCH_1):NC_PVCCD_HV_CPU0_APWM7':
 C_SIGNAL='@s9s_mb_2u_lib.s9s_mb_2u(sch_1):nc_pvccd_hv_cpu0_apwm7';
NODE_NAME     PU35 2
 '@S9S_MB_2U_LIB.S9S_MB_2U(SCH_1):PAGE264_I53@PURE_QUANTA.ISL69260IRAZT(CHIPS)':
 'PWM1': CDS_PINID='PWM1';
NET_NAME
'NC_PVCCD_HV_CPU0_APWM8'
 '@S9S_MB_2U_LIB.S9S_MB_2U(SCH_1):NC_PVCCD_HV_CPU0_APWM8':
 C_SIGNAL='@s9s_mb_2u_lib.s9s_mb_2u(sch_1):nc_pvccd_hv_cpu0_apwm8';
NODE_NAME     PU35 1
 '@S9S_MB_2U_LIB.S9S_MB_2U(SCH_1):PAGE264_I53@PURE_QUANTA.ISL69260IRAZT(CHIPS)':
 'PWM0': CDS_PINID='PWM0';
NET_NAME
'NC_PVCCD_HV_CPU0_BVR_RDY'
 '@S9S_MB_2U_LIB.S9S_MB_2U(SCH_1):NC_PVCCD_HV_CPU0_BVR_RDY':
 C_SIGNAL='@s9s_mb_2u_lib.s9s_mb_2u(sch_1):nc_pvccd_hv_cpu0_bvr_rdy';
NODE_NAME     PU35 16
 '@S9S_MB_2U_LIB.S9S_MB_2U(SCH_1):PAGE264_I53@PURE_QUANTA.ISL69260IRAZT(CHIPS)':
 'PG1': CDS_PINID='PG1';
NET_NAME
'NC_PVCCD_HV_CPU0_SMB_ALERT'
 '@S9S_MB_2U_LIB.S9S_MB_2U(SCH_1):NC_PVCCD_HV_CPU0_SMB_ALERT':
 C_SIGNAL='@s9s_mb_2u_lib.s9s_mb_2u(sch_1):nc_pvccd_hv_cpu0_smb_alert';
NODE_NAME     PU35 11
 '@S9S_MB_2U_LIB.S9S_MB_2U(SCH_1):PAGE264_I53@PURE_QUANTA.ISL69260IRAZT(CHIPS)':
 'NPMALERT#': CDS_PINID='\npmalert#\';
NET_NAME
'NC_PVCCD_HV_CPU1_ACSP2'
 '@S9S_MB_2U_LIB.S9S_MB_2U(SCH_1):NC_PVCCD_HV_CPU1_ACSP2':
 C_SIGNAL='@s9s_mb_2u_lib.s9s_mb_2u(sch_1):nc_pvccd_hv_cpu1_acsp2';
NODE_NAME     PU18 24
 '@S9S_MB_2U_LIB.S9S_MB_2U(SCH_1):PAGE282_I53@PURE_QUANTA.ISL69260IRAZT(CHIPS)':
 'CS6': CDS_PINID='CS6';
NODE_NAME     PR4251 1
 '@S9S_MB_2U_LIB.S9S_MB_2U(SCH_1):PAGE282_I70@PURE_QUANTA.Q_RES(CHIPS)':
 'A': CDS_PINID='A';
NET_NAME
'NC_PVCCD_HV_CPU1_ACSP3'
 '@S9S_MB_2U_LIB.S9S_MB_2U(SCH_1):NC_PVCCD_HV_CPU1_ACSP3':
 C_SIGNAL='@s9s_mb_2u_lib.s9s_mb_2u(sch_1):nc_pvccd_hv_cpu1_acsp3';
NODE_NAME     PU18 25
 '@S9S_MB_2U_LIB.S9S_MB_2U(SCH_1):PAGE282_I53@PURE_QUANTA.ISL69260IRAZT(CHIPS)':
 'CS5': CDS_PINID='CS5';
NODE_NAME     PR4252 1
 '@S9S_MB_2U_LIB.S9S_MB_2U(SCH_1):PAGE282_I64@PURE_QUANTA.Q_RES(CHIPS)':
 'A': CDS_PINID='A';
NET_NAME
'NC_PVCCD_HV_CPU1_ACSP4'
 '@S9S_MB_2U_LIB.S9S_MB_2U(SCH_1):NC_PVCCD_HV_CPU1_ACSP4':
 C_SIGNAL='@s9s_mb_2u_lib.s9s_mb_2u(sch_1):nc_pvccd_hv_cpu1_acsp4';
NODE_NAME     PU18 26
 '@S9S_MB_2U_LIB.S9S_MB_2U(SCH_1):PAGE282_I53@PURE_QUANTA.ISL69260IRAZT(CHIPS)':
 'CS4': CDS_PINID='CS4';
NODE_NAME     PR4253 1
 '@S9S_MB_2U_LIB.S9S_MB_2U(SCH_1):PAGE282_I65@PURE_QUANTA.Q_RES(CHIPS)':
 'A': CDS_PINID='A';
NET_NAME
'NC_PVCCD_HV_CPU1_ACSP5'
 '@S9S_MB_2U_LIB.S9S_MB_2U(SCH_1):NC_PVCCD_HV_CPU1_ACSP5':
 C_SIGNAL='@s9s_mb_2u_lib.s9s_mb_2u(sch_1):nc_pvccd_hv_cpu1_acsp5';
NODE_NAME     PU18 27
 '@S9S_MB_2U_LIB.S9S_MB_2U(SCH_1):PAGE282_I53@PURE_QUANTA.ISL69260IRAZT(CHIPS)':
 'CS3': CDS_PINID='CS3';
NODE_NAME     PR4254 1
 '@S9S_MB_2U_LIB.S9S_MB_2U(SCH_1):PAGE282_I66@PURE_QUANTA.Q_RES(CHIPS)':
 'A': CDS_PINID='A';
NET_NAME
'NC_PVCCD_HV_CPU1_ACSP6'
 '@S9S_MB_2U_LIB.S9S_MB_2U(SCH_1):NC_PVCCD_HV_CPU1_ACSP6':
 C_SIGNAL='@s9s_mb_2u_lib.s9s_mb_2u(sch_1):nc_pvccd_hv_cpu1_acsp6';
NODE_NAME     PU18 28
 '@S9S_MB_2U_LIB.S9S_MB_2U(SCH_1):PAGE282_I53@PURE_QUANTA.ISL69260IRAZT(CHIPS)':
 'CS2': CDS_PINID='CS2';
NODE_NAME     PR4255 1
 '@S9S_MB_2U_LIB.S9S_MB_2U(SCH_1):PAGE282_I62@PURE_QUANTA.Q_RES(CHIPS)':
 'A': CDS_PINID='A';
NET_NAME
'NC_PVCCD_HV_CPU1_ACSP7'
 '@S9S_MB_2U_LIB.S9S_MB_2U(SCH_1):NC_PVCCD_HV_CPU1_ACSP7':
 C_SIGNAL='@s9s_mb_2u_lib.s9s_mb_2u(sch_1):nc_pvccd_hv_cpu1_acsp7';
NODE_NAME     PU18 29
 '@S9S_MB_2U_LIB.S9S_MB_2U(SCH_1):PAGE282_I53@PURE_QUANTA.ISL69260IRAZT(CHIPS)':
 'CS1': CDS_PINID='CS1';
NODE_NAME     PR4256 1
 '@S9S_MB_2U_LIB.S9S_MB_2U(SCH_1):PAGE282_I63@PURE_QUANTA.Q_RES(CHIPS)':
 'A': CDS_PINID='A';
NET_NAME
'NC_PVCCD_HV_CPU1_ACSP8'
 '@S9S_MB_2U_LIB.S9S_MB_2U(SCH_1):NC_PVCCD_HV_CPU1_ACSP8':
 C_SIGNAL='@s9s_mb_2u_lib.s9s_mb_2u(sch_1):nc_pvccd_hv_cpu1_acsp8';
NODE_NAME     PU18 30
 '@S9S_MB_2U_LIB.S9S_MB_2U(SCH_1):PAGE282_I53@PURE_QUANTA.ISL69260IRAZT(CHIPS)':
 'CS0': CDS_PINID='CS0';
NODE_NAME     PR4257 1
 '@S9S_MB_2U_LIB.S9S_MB_2U(SCH_1):PAGE282_I59@PURE_QUANTA.Q_RES(CHIPS)':
 'A': CDS_PINID='A';
NET_NAME
'NC_PVCCD_HV_CPU1_APWM2'
 '@S9S_MB_2U_LIB.S9S_MB_2U(SCH_1):NC_PVCCD_HV_CPU1_APWM2':
 C_SIGNAL='@s9s_mb_2u_lib.s9s_mb_2u(sch_1):nc_pvccd_hv_cpu1_apwm2';
NODE_NAME     PU18 7
 '@S9S_MB_2U_LIB.S9S_MB_2U(SCH_1):PAGE282_I53@PURE_QUANTA.ISL69260IRAZT(CHIPS)':
 'PWM6': CDS_PINID='PWM6';
NET_NAME
'NC_PVCCD_HV_CPU1_APWM3'
 '@S9S_MB_2U_LIB.S9S_MB_2U(SCH_1):NC_PVCCD_HV_CPU1_APWM3':
 C_SIGNAL='@s9s_mb_2u_lib.s9s_mb_2u(sch_1):nc_pvccd_hv_cpu1_apwm3';
NODE_NAME     PU18 6
 '@S9S_MB_2U_LIB.S9S_MB_2U(SCH_1):PAGE282_I53@PURE_QUANTA.ISL69260IRAZT(CHIPS)':
 'PWM5': CDS_PINID='PWM5';
NET_NAME
'NC_PVCCD_HV_CPU1_APWM4'
 '@S9S_MB_2U_LIB.S9S_MB_2U(SCH_1):NC_PVCCD_HV_CPU1_APWM4':
 C_SIGNAL='@s9s_mb_2u_lib.s9s_mb_2u(sch_1):nc_pvccd_hv_cpu1_apwm4';
NODE_NAME     PU18 5
 '@S9S_MB_2U_LIB.S9S_MB_2U(SCH_1):PAGE282_I53@PURE_QUANTA.ISL69260IRAZT(CHIPS)':
 'PWM4': CDS_PINID='PWM4';
NET_NAME
'NC_PVCCD_HV_CPU1_APWM5'
 '@S9S_MB_2U_LIB.S9S_MB_2U(SCH_1):NC_PVCCD_HV_CPU1_APWM5':
 C_SIGNAL='@s9s_mb_2u_lib.s9s_mb_2u(sch_1):nc_pvccd_hv_cpu1_apwm5';
NODE_NAME     PU18 4
 '@S9S_MB_2U_LIB.S9S_MB_2U(SCH_1):PAGE282_I53@PURE_QUANTA.ISL69260IRAZT(CHIPS)':
 'PWM3': CDS_PINID='PWM3';
NET_NAME
'NC_PVCCD_HV_CPU1_APWM6'
 '@S9S_MB_2U_LIB.S9S_MB_2U(SCH_1):NC_PVCCD_HV_CPU1_APWM6':
 C_SIGNAL='@s9s_mb_2u_lib.s9s_mb_2u(sch_1):nc_pvccd_hv_cpu1_apwm6';
NODE_NAME     PU18 3
 '@S9S_MB_2U_LIB.S9S_MB_2U(SCH_1):PAGE282_I53@PURE_QUANTA.ISL69260IRAZT(CHIPS)':
 'PWM2': CDS_PINID='PWM2';
NET_NAME
'NC_PVCCD_HV_CPU1_APWM7'
 '@S9S_MB_2U_LIB.S9S_MB_2U(SCH_1):NC_PVCCD_HV_CPU1_APWM7':
 C_SIGNAL='@s9s_mb_2u_lib.s9s_mb_2u(sch_1):nc_pvccd_hv_cpu1_apwm7';
NODE_NAME     PU18 2
 '@S9S_MB_2U_LIB.S9S_MB_2U(SCH_1):PAGE282_I53@PURE_QUANTA.ISL69260IRAZT(CHIPS)':
 'PWM1': CDS_PINID='PWM1';
NET_NAME
'NC_PVCCD_HV_CPU1_APWM8'
 '@S9S_MB_2U_LIB.S9S_MB_2U(SCH_1):NC_PVCCD_HV_CPU1_APWM8':
 C_SIGNAL='@s9s_mb_2u_lib.s9s_mb_2u(sch_1):nc_pvccd_hv_cpu1_apwm8';
NODE_NAME     PU18 1
 '@S9S_MB_2U_LIB.S9S_MB_2U(SCH_1):PAGE282_I53@PURE_QUANTA.ISL69260IRAZT(CHIPS)':
 'PWM0': CDS_PINID='PWM0';
NET_NAME
'NC_PVCCD_HV_CPU1_BVR_RDY'
 '@S9S_MB_2U_LIB.S9S_MB_2U(SCH_1):NC_PVCCD_HV_CPU1_BVR_RDY':
 C_SIGNAL='@s9s_mb_2u_lib.s9s_mb_2u(sch_1):nc_pvccd_hv_cpu1_bvr_rdy';
NODE_NAME     PU18 16
 '@S9S_MB_2U_LIB.S9S_MB_2U(SCH_1):PAGE282_I53@PURE_QUANTA.ISL69260IRAZT(CHIPS)':
 'PG1': CDS_PINID='PG1';
NET_NAME
'NC_PVCCD_HV_CPU1_SMB_ALERT'
 '@S9S_MB_2U_LIB.S9S_MB_2U(SCH_1):NC_PVCCD_HV_CPU1_SMB_ALERT':
 C_SIGNAL='@s9s_mb_2u_lib.s9s_mb_2u(sch_1):nc_pvccd_hv_cpu1_smb_alert';
NODE_NAME     PU18 11
 '@S9S_MB_2U_LIB.S9S_MB_2U(SCH_1):PAGE282_I53@PURE_QUANTA.ISL69260IRAZT(CHIPS)':
 'NPMALERT#': CDS_PINID='\npmalert#\';
NET_NAME
'NC_PVCCINFAON_CPU0_ACSP3'
 '@S9S_MB_2U_LIB.S9S_MB_2U(SCH_1):NC_PVCCINFAON_CPU0_ACSP3':
 C_SIGNAL='@s9s_mb_2u_lib.s9s_mb_2u(sch_1):nc_pvccinfaon_cpu0_acsp3';
NODE_NAME     PU5 25
 '@S9S_MB_2U_LIB.S9S_MB_2U(SCH_1):PAGE260_I65@PURE_QUANTA.ISL69260IRAZT(CHIPS)':
 'CS5': CDS_PINID='CS5';
NODE_NAME     PR4221 1
 '@S9S_MB_2U_LIB.S9S_MB_2U(SCH_1):PAGE260_I87@PURE_QUANTA.Q_RES(CHIPS)':
 'A': CDS_PINID='A';
NET_NAME
'NC_PVCCINFAON_CPU0_ACSP4'
 '@S9S_MB_2U_LIB.S9S_MB_2U(SCH_1):NC_PVCCINFAON_CPU0_ACSP4':
 C_SIGNAL='@s9s_mb_2u_lib.s9s_mb_2u(sch_1):nc_pvccinfaon_cpu0_acsp4';
NODE_NAME     PU5 26
 '@S9S_MB_2U_LIB.S9S_MB_2U(SCH_1):PAGE260_I65@PURE_QUANTA.ISL69260IRAZT(CHIPS)':
 'CS4': CDS_PINID='CS4';
NODE_NAME     PR4222 1
 '@S9S_MB_2U_LIB.S9S_MB_2U(SCH_1):PAGE260_I86@PURE_QUANTA.Q_RES(CHIPS)':
 'A': CDS_PINID='A';
NET_NAME
'NC_PVCCINFAON_CPU0_ACSP5'
 '@S9S_MB_2U_LIB.S9S_MB_2U(SCH_1):NC_PVCCINFAON_CPU0_ACSP5':
 C_SIGNAL='@s9s_mb_2u_lib.s9s_mb_2u(sch_1):nc_pvccinfaon_cpu0_acsp5';
NODE_NAME     PU5 27
 '@S9S_MB_2U_LIB.S9S_MB_2U(SCH_1):PAGE260_I65@PURE_QUANTA.ISL69260IRAZT(CHIPS)':
 'CS3': CDS_PINID='CS3';
NODE_NAME     PR4223 1
 '@S9S_MB_2U_LIB.S9S_MB_2U(SCH_1):PAGE260_I85@PURE_QUANTA.Q_RES(CHIPS)':
 'A': CDS_PINID='A';
NET_NAME
'NC_PVCCINFAON_CPU0_ACSP6'
 '@S9S_MB_2U_LIB.S9S_MB_2U(SCH_1):NC_PVCCINFAON_CPU0_ACSP6':
 C_SIGNAL='@s9s_mb_2u_lib.s9s_mb_2u(sch_1):nc_pvccinfaon_cpu0_acsp6';
NODE_NAME     PU5 28
 '@S9S_MB_2U_LIB.S9S_MB_2U(SCH_1):PAGE260_I65@PURE_QUANTA.ISL69260IRAZT(CHIPS)':
 'CS2': CDS_PINID='CS2';
NODE_NAME     PR4224 1
 '@S9S_MB_2U_LIB.S9S_MB_2U(SCH_1):PAGE260_I84@PURE_QUANTA.Q_RES(CHIPS)':
 'A': CDS_PINID='A';
NET_NAME
'NC_PVCCINFAON_CPU0_ACSP7'
 '@S9S_MB_2U_LIB.S9S_MB_2U(SCH_1):NC_PVCCINFAON_CPU0_ACSP7':
 C_SIGNAL='@s9s_mb_2u_lib.s9s_mb_2u(sch_1):nc_pvccinfaon_cpu0_acsp7';
NODE_NAME     PU5 29
 '@S9S_MB_2U_LIB.S9S_MB_2U(SCH_1):PAGE260_I65@PURE_QUANTA.ISL69260IRAZT(CHIPS)':
 'CS1': CDS_PINID='CS1';
NODE_NAME     PR4225 1
 '@S9S_MB_2U_LIB.S9S_MB_2U(SCH_1):PAGE260_I76@PURE_QUANTA.Q_RES(CHIPS)':
 'A': CDS_PINID='A';
NET_NAME
'NC_PVCCINFAON_CPU0_APWM3'
 '@S9S_MB_2U_LIB.S9S_MB_2U(SCH_1):NC_PVCCINFAON_CPU0_APWM3':
 C_SIGNAL='@s9s_mb_2u_lib.s9s_mb_2u(sch_1):nc_pvccinfaon_cpu0_apwm3';
NODE_NAME     PU5 6
 '@S9S_MB_2U_LIB.S9S_MB_2U(SCH_1):PAGE260_I65@PURE_QUANTA.ISL69260IRAZT(CHIPS)':
 'PWM5': CDS_PINID='PWM5';
NET_NAME
'NC_PVCCINFAON_CPU0_APWM4'
 '@S9S_MB_2U_LIB.S9S_MB_2U(SCH_1):NC_PVCCINFAON_CPU0_APWM4':
 C_SIGNAL='@s9s_mb_2u_lib.s9s_mb_2u(sch_1):nc_pvccinfaon_cpu0_apwm4';
NODE_NAME     PU5 5
 '@S9S_MB_2U_LIB.S9S_MB_2U(SCH_1):PAGE260_I65@PURE_QUANTA.ISL69260IRAZT(CHIPS)':
 'PWM4': CDS_PINID='PWM4';
NET_NAME
'NC_PVCCINFAON_CPU0_APWM5'
 '@S9S_MB_2U_LIB.S9S_MB_2U(SCH_1):NC_PVCCINFAON_CPU0_APWM5':
 C_SIGNAL='@s9s_mb_2u_lib.s9s_mb_2u(sch_1):nc_pvccinfaon_cpu0_apwm5';
NODE_NAME     PU5 4
 '@S9S_MB_2U_LIB.S9S_MB_2U(SCH_1):PAGE260_I65@PURE_QUANTA.ISL69260IRAZT(CHIPS)':
 'PWM3': CDS_PINID='PWM3';
NET_NAME
'NC_PVCCINFAON_CPU0_APWM6'
 '@S9S_MB_2U_LIB.S9S_MB_2U(SCH_1):NC_PVCCINFAON_CPU0_APWM6':
 C_SIGNAL='@s9s_mb_2u_lib.s9s_mb_2u(sch_1):nc_pvccinfaon_cpu0_apwm6';
NODE_NAME     PU5 3
 '@S9S_MB_2U_LIB.S9S_MB_2U(SCH_1):PAGE260_I65@PURE_QUANTA.ISL69260IRAZT(CHIPS)':
 'PWM2': CDS_PINID='PWM2';
NET_NAME
'NC_PVCCINFAON_CPU0_APWM7'
 '@S9S_MB_2U_LIB.S9S_MB_2U(SCH_1):NC_PVCCINFAON_CPU0_APWM7':
 C_SIGNAL='@s9s_mb_2u_lib.s9s_mb_2u(sch_1):nc_pvccinfaon_cpu0_apwm7';
NODE_NAME     PU5 2
 '@S9S_MB_2U_LIB.S9S_MB_2U(SCH_1):PAGE260_I65@PURE_QUANTA.ISL69260IRAZT(CHIPS)':
 'PWM1': CDS_PINID='PWM1';
NET_NAME
'NC_PVCCINFAON_CPU0_SMB_ALERT'
 '@S9S_MB_2U_LIB.S9S_MB_2U(SCH_1):NC_PVCCINFAON_CPU0_SMB_ALERT':
 C_SIGNAL='@s9s_mb_2u_lib.s9s_mb_2u(sch_1):nc_pvccinfaon_cpu0_smb_alert';
NODE_NAME     PU5 11
 '@S9S_MB_2U_LIB.S9S_MB_2U(SCH_1):PAGE260_I65@PURE_QUANTA.ISL69260IRAZT(CHIPS)':
 'NPMALERT#': CDS_PINID='\npmalert#\';
NET_NAME
'NC_PVCCINFAON_CPU1_ACSP3'
 '@S9S_MB_2U_LIB.S9S_MB_2U(SCH_1):NC_PVCCINFAON_CPU1_ACSP3':
 C_SIGNAL='@s9s_mb_2u_lib.s9s_mb_2u(sch_1):nc_pvccinfaon_cpu1_acsp3';
NODE_NAME     PU22 25
 '@S9S_MB_2U_LIB.S9S_MB_2U(SCH_1):PAGE278_I38@PURE_QUANTA.ISL69260IRAZT(CHIPS)':
 'CS5': CDS_PINID='CS5';
NODE_NAME     PR4242 1
 '@S9S_MB_2U_LIB.S9S_MB_2U(SCH_1):PAGE278_I89@PURE_QUANTA.Q_RES(CHIPS)':
 'A': CDS_PINID='A';
NET_NAME
'NC_PVCCINFAON_CPU1_ACSP4'
 '@S9S_MB_2U_LIB.S9S_MB_2U(SCH_1):NC_PVCCINFAON_CPU1_ACSP4':
 C_SIGNAL='@s9s_mb_2u_lib.s9s_mb_2u(sch_1):nc_pvccinfaon_cpu1_acsp4';
NODE_NAME     PR4243 1
 '@S9S_MB_2U_LIB.S9S_MB_2U(SCH_1):PAGE278_I81@PURE_QUANTA.Q_RES(CHIPS)':
 'A': CDS_PINID='A';
NODE_NAME     PU22 26
 '@S9S_MB_2U_LIB.S9S_MB_2U(SCH_1):PAGE278_I38@PURE_QUANTA.ISL69260IRAZT(CHIPS)':
 'CS4': CDS_PINID='CS4';
NET_NAME
'NC_PVCCINFAON_CPU1_ACSP5'
 '@S9S_MB_2U_LIB.S9S_MB_2U(SCH_1):NC_PVCCINFAON_CPU1_ACSP5':
 C_SIGNAL='@s9s_mb_2u_lib.s9s_mb_2u(sch_1):nc_pvccinfaon_cpu1_acsp5';
NODE_NAME     PR4244 1
 '@S9S_MB_2U_LIB.S9S_MB_2U(SCH_1):PAGE278_I80@PURE_QUANTA.Q_RES(CHIPS)':
 'A': CDS_PINID='A';
NODE_NAME     PU22 27
 '@S9S_MB_2U_LIB.S9S_MB_2U(SCH_1):PAGE278_I38@PURE_QUANTA.ISL69260IRAZT(CHIPS)':
 'CS3': CDS_PINID='CS3';
NET_NAME
'NC_PVCCINFAON_CPU1_ACSP6'
 '@S9S_MB_2U_LIB.S9S_MB_2U(SCH_1):NC_PVCCINFAON_CPU1_ACSP6':
 C_SIGNAL='@s9s_mb_2u_lib.s9s_mb_2u(sch_1):nc_pvccinfaon_cpu1_acsp6';
NODE_NAME     PR4245 1
 '@S9S_MB_2U_LIB.S9S_MB_2U(SCH_1):PAGE278_I79@PURE_QUANTA.Q_RES(CHIPS)':
 'A': CDS_PINID='A';
NODE_NAME     PU22 28
 '@S9S_MB_2U_LIB.S9S_MB_2U(SCH_1):PAGE278_I38@PURE_QUANTA.ISL69260IRAZT(CHIPS)':
 'CS2': CDS_PINID='CS2';
NET_NAME
'NC_PVCCINFAON_CPU1_ACSP7'
 '@S9S_MB_2U_LIB.S9S_MB_2U(SCH_1):NC_PVCCINFAON_CPU1_ACSP7':
 C_SIGNAL='@s9s_mb_2u_lib.s9s_mb_2u(sch_1):nc_pvccinfaon_cpu1_acsp7';
NODE_NAME     PR4246 1
 '@S9S_MB_2U_LIB.S9S_MB_2U(SCH_1):PAGE278_I78@PURE_QUANTA.Q_RES(CHIPS)':
 'A': CDS_PINID='A';
NODE_NAME     PU22 29
 '@S9S_MB_2U_LIB.S9S_MB_2U(SCH_1):PAGE278_I38@PURE_QUANTA.ISL69260IRAZT(CHIPS)':
 'CS1': CDS_PINID='CS1';
NET_NAME
'NC_PVCCINFAON_CPU1_APWM3'
 '@S9S_MB_2U_LIB.S9S_MB_2U(SCH_1):NC_PVCCINFAON_CPU1_APWM3':
 C_SIGNAL='@s9s_mb_2u_lib.s9s_mb_2u(sch_1):nc_pvccinfaon_cpu1_apwm3';
NODE_NAME     PU22 6
 '@S9S_MB_2U_LIB.S9S_MB_2U(SCH_1):PAGE278_I38@PURE_QUANTA.ISL69260IRAZT(CHIPS)':
 'PWM5': CDS_PINID='PWM5';
NET_NAME
'NC_PVCCINFAON_CPU1_APWM4'
 '@S9S_MB_2U_LIB.S9S_MB_2U(SCH_1):NC_PVCCINFAON_CPU1_APWM4':
 C_SIGNAL='@s9s_mb_2u_lib.s9s_mb_2u(sch_1):nc_pvccinfaon_cpu1_apwm4';
NODE_NAME     PU22 5
 '@S9S_MB_2U_LIB.S9S_MB_2U(SCH_1):PAGE278_I38@PURE_QUANTA.ISL69260IRAZT(CHIPS)':
 'PWM4': CDS_PINID='PWM4';
NET_NAME
'NC_PVCCINFAON_CPU1_APWM5'
 '@S9S_MB_2U_LIB.S9S_MB_2U(SCH_1):NC_PVCCINFAON_CPU1_APWM5':
 C_SIGNAL='@s9s_mb_2u_lib.s9s_mb_2u(sch_1):nc_pvccinfaon_cpu1_apwm5';
NODE_NAME     PU22 4
 '@S9S_MB_2U_LIB.S9S_MB_2U(SCH_1):PAGE278_I38@PURE_QUANTA.ISL69260IRAZT(CHIPS)':
 'PWM3': CDS_PINID='PWM3';
NET_NAME
'NC_PVCCINFAON_CPU1_APWM6'
 '@S9S_MB_2U_LIB.S9S_MB_2U(SCH_1):NC_PVCCINFAON_CPU1_APWM6':
 C_SIGNAL='@s9s_mb_2u_lib.s9s_mb_2u(sch_1):nc_pvccinfaon_cpu1_apwm6';
NODE_NAME     PU22 3
 '@S9S_MB_2U_LIB.S9S_MB_2U(SCH_1):PAGE278_I38@PURE_QUANTA.ISL69260IRAZT(CHIPS)':
 'PWM2': CDS_PINID='PWM2';
NET_NAME
'NC_PVCCINFAON_CPU1_APWM7'
 '@S9S_MB_2U_LIB.S9S_MB_2U(SCH_1):NC_PVCCINFAON_CPU1_APWM7':
 C_SIGNAL='@s9s_mb_2u_lib.s9s_mb_2u(sch_1):nc_pvccinfaon_cpu1_apwm7';
NODE_NAME     PU22 2
 '@S9S_MB_2U_LIB.S9S_MB_2U(SCH_1):PAGE278_I38@PURE_QUANTA.ISL69260IRAZT(CHIPS)':
 'PWM1': CDS_PINID='PWM1';
NET_NAME
'NC_PVCCINFAON_CPU1_SMB_ALERT'
 '@S9S_MB_2U_LIB.S9S_MB_2U(SCH_1):NC_PVCCINFAON_CPU1_SMB_ALERT':
 C_SIGNAL='@s9s_mb_2u_lib.s9s_mb_2u(sch_1):nc_pvccinfaon_cpu1_smb_alert';
NODE_NAME     PU22 11
 '@S9S_MB_2U_LIB.S9S_MB_2U(SCH_1):PAGE278_I38@PURE_QUANTA.ISL69260IRAZT(CHIPS)':
 'NPMALERT#': CDS_PINID='\npmalert#\';
NET_NAME
'NC_PVCCIN_CPU0_SMB_ALERT'
 '@S9S_MB_2U_LIB.S9S_MB_2U(SCH_1):NC_PVCCIN_CPU0_SMB_ALERT':
 C_SIGNAL='@s9s_mb_2u_lib.s9s_mb_2u(sch_1):nc_pvccin_cpu0_smb_alert';
NODE_NAME     PU14 15
 '@S9S_MB_2U_LIB.S9S_MB_2U(SCH_1):PAGE252_I63@PURE_QUANTA.RAA229126GNPHA0(CHIPS)':
 'NPMALERT': CDS_PINID='NPMALERT';
NET_NAME
'NC_PVCCIN_CPU1_SMB_ALERT'
 '@S9S_MB_2U_LIB.S9S_MB_2U(SCH_1):NC_PVCCIN_CPU1_SMB_ALERT':
 C_SIGNAL='@s9s_mb_2u_lib.s9s_mb_2u(sch_1):nc_pvccin_cpu1_smb_alert';
NODE_NAME     PU29 15
 '@S9S_MB_2U_LIB.S9S_MB_2U(SCH_1):PAGE270_I33@PURE_QUANTA.RAA229126GNPHA0(CHIPS)':
 'NPMALERT': CDS_PINID='NPMALERT';
NET_NAME
'NC_Q95_D2'
 '@S9S_MB_2U_LIB.S9S_MB_2U(SCH_1):NC_Q95_D2':
 C_SIGNAL='@s9s_mb_2u_lib.s9s_mb_2u(sch_1):nc_q95_d2';
NODE_NAME     Q95 3
 '@S9S_MB_2U_LIB.S9S_MB_2U(SCH_1):PAGE182_I343@PURE_QUANTA.MOSFET_NCH_DUAL(CHIPS)':
 'D2': CDS_PINID='D2';
NET_NAME
'NC_Q95_G2'
 '@S9S_MB_2U_LIB.S9S_MB_2U(SCH_1):NC_Q95_G2':
 C_SIGNAL='@s9s_mb_2u_lib.s9s_mb_2u(sch_1):nc_q95_g2';
NODE_NAME     Q95 5
 '@S9S_MB_2U_LIB.S9S_MB_2U(SCH_1):PAGE182_I343@PURE_QUANTA.MOSFET_NCH_DUAL(CHIPS)':
 'G2': CDS_PINID='G2';
NET_NAME
'NC_Q95_S2'
 '@S9S_MB_2U_LIB.S9S_MB_2U(SCH_1):NC_Q95_S2':
 C_SIGNAL='@s9s_mb_2u_lib.s9s_mb_2u(sch_1):nc_q95_s2';
NODE_NAME     Q95 4
 '@S9S_MB_2U_LIB.S9S_MB_2U(SCH_1):PAGE182_I343@PURE_QUANTA.MOSFET_NCH_DUAL(CHIPS)':
 'S2': CDS_PINID='S2';
NET_NAME
'NC_RES'
 '@S9S_MB_2U_LIB.S9S_MB_2U(SCH_1):NC_RES':
 C_SIGNAL='@s9s_mb_2u_lib.s9s_mb_2u(sch_1):nc_res';
NODE_NAME     U328 13
 '@S9S_MB_2U_LIB.S9S_MB_2U(SCH_1):PAGE159_I95@PURE_QUANTA.DS125BR111RTWR(CHIPS)':
 'RES': CDS_PINID='RES';
NET_NAME
'NC_SPI_CPU1_NCM_CLK'
 '@S9S_MB_2U_LIB.S9S_MB_2U(SCH_1):NC_SPI_CPU1_NCM_CLK':
 C_SIGNAL='@s9s_mb_2u_lib.s9s_mb_2u(sch_1):nc_spi_cpu1_ncm_clk';
NODE_NAME     U1 AU62
 '@S9S_MB_2U_LIB.S9S_MB_2U(SCH_1):PAGE46_I5@PURE_QUANTA.SOCKET4677_AZIF0045P001C01CS(CHIPS)':
 'RSVD11': CDS_PINID='RSVD11';
NET_NAME
'NC_SPI_CPU1_NCM_CS0_N'
 '@S9S_MB_2U_LIB.S9S_MB_2U(SCH_1):NC_SPI_CPU1_NCM_CS0_N':
 C_SIGNAL='@s9s_mb_2u_lib.s9s_mb_2u(sch_1):nc_spi_cpu1_ncm_cs0_n';
NODE_NAME     U1 AY67
 '@S9S_MB_2U_LIB.S9S_MB_2U(SCH_1):PAGE46_I5@PURE_QUANTA.SOCKET4677_AZIF0045P001C01CS(CHIPS)':
 'RSVD30': CDS_PINID='RSVD30';
NET_NAME
'NC_SPI_CPU1_NCM_IO0'
 '@S9S_MB_2U_LIB.S9S_MB_2U(SCH_1):NC_SPI_CPU1_NCM_IO0':
 C_SIGNAL='@s9s_mb_2u_lib.s9s_mb_2u(sch_1):nc_spi_cpu1_ncm_io0';
NODE_NAME     U1 BA66
 '@S9S_MB_2U_LIB.S9S_MB_2U(SCH_1):PAGE46_I5@PURE_QUANTA.SOCKET4677_AZIF0045P001C01CS(CHIPS)':
 'RSVD33': CDS_PINID='RSVD33';
NET_NAME
'NC_SPI_CPU1_NCM_IO1'
 '@S9S_MB_2U_LIB.S9S_MB_2U(SCH_1):NC_SPI_CPU1_NCM_IO1':
 C_SIGNAL='@s9s_mb_2u_lib.s9s_mb_2u(sch_1):nc_spi_cpu1_ncm_io1';
NODE_NAME     U1 AY61
 '@S9S_MB_2U_LIB.S9S_MB_2U(SCH_1):PAGE46_I5@PURE_QUANTA.SOCKET4677_AZIF0045P001C01CS(CHIPS)':
 'RSVD28': CDS_PINID='RSVD28';
NET_NAME
'NC_SPI_CPU1_NCM_OE_N'
 '@S9S_MB_2U_LIB.S9S_MB_2U(SCH_1):NC_SPI_CPU1_NCM_OE_N':
 C_SIGNAL='@s9s_mb_2u_lib.s9s_mb_2u(sch_1):nc_spi_cpu1_ncm_oe_n';
NODE_NAME     U1 BB67
 '@S9S_MB_2U_LIB.S9S_MB_2U(SCH_1):PAGE46_I5@PURE_QUANTA.SOCKET4677_AZIF0045P001C01CS(CHIPS)':
 'RSVD36': CDS_PINID='RSVD36';
NET_NAME
'NC_SPI_S3M_CPU1_CLK_LVC1_R'
 '@S9S_MB_2U_LIB.S9S_MB_2U(SCH_1):NC_SPI_S3M_CPU1_CLK_LVC1_R':
 C_SIGNAL='@s9s_mb_2u_lib.s9s_mb_2u(sch_1):nc_spi_s3m_cpu1_clk_lvc1_r';
NODE_NAME     U1 BC64
 '@S9S_MB_2U_LIB.S9S_MB_2U(SCH_1):PAGE46_I5@PURE_QUANTA.SOCKET4677_AZIF0045P001C01CS(CHIPS)':
 'RSVD39': CDS_PINID='RSVD39';
NET_NAME
'NC_SPI_S3M_CPU1_CS0_LVC1_R_N'
 '@S9S_MB_2U_LIB.S9S_MB_2U(SCH_1):NC_SPI_S3M_CPU1_CS0_LVC1_R_N':
 C_SIGNAL='@s9s_mb_2u_lib.s9s_mb_2u(sch_1):nc_spi_s3m_cpu1_cs0_lvc1_r_n';
NODE_NAME     U1 BB61
 '@S9S_MB_2U_LIB.S9S_MB_2U(SCH_1):PAGE46_I5@PURE_QUANTA.SOCKET4677_AZIF0045P001C01CS(CHIPS)':
 'RSVD35': CDS_PINID='RSVD35';
NET_NAME
'NC_SPI_S3M_CPU1_CS1_LVC1_R_N'
 '@S9S_MB_2U_LIB.S9S_MB_2U(SCH_1):NC_SPI_S3M_CPU1_CS1_LVC1_R_N':
 C_SIGNAL='@s9s_mb_2u_lib.s9s_mb_2u(sch_1):nc_spi_s3m_cpu1_cs1_lvc1_r_n';
NODE_NAME     U1 AV63
 '@S9S_MB_2U_LIB.S9S_MB_2U(SCH_1):PAGE46_I5@PURE_QUANTA.SOCKET4677_AZIF0045P001C01CS(CHIPS)':
 'RSVD20': CDS_PINID='RSVD20';
NET_NAME
'NC_SPI_S3M_CPU1_IO0_LVC1_R'
 '@S9S_MB_2U_LIB.S9S_MB_2U(SCH_1):NC_SPI_S3M_CPU1_IO0_LVC1_R':
 C_SIGNAL='@s9s_mb_2u_lib.s9s_mb_2u(sch_1):nc_spi_s3m_cpu1_io0_lvc1_r';
NODE_NAME     U1 BA62
 '@S9S_MB_2U_LIB.S9S_MB_2U(SCH_1):PAGE46_I5@PURE_QUANTA.SOCKET4677_AZIF0045P001C01CS(CHIPS)':
 'RSVD32': CDS_PINID='RSVD32';
NET_NAME
'NC_SPI_S3M_CPU1_IO1_LVC1_R'
 '@S9S_MB_2U_LIB.S9S_MB_2U(SCH_1):NC_SPI_S3M_CPU1_IO1_LVC1_R':
 C_SIGNAL='@s9s_mb_2u_lib.s9s_mb_2u(sch_1):nc_spi_s3m_cpu1_io1_lvc1_r';
NODE_NAME     U1 AW64
 '@S9S_MB_2U_LIB.S9S_MB_2U(SCH_1):PAGE46_I5@PURE_QUANTA.SOCKET4677_AZIF0045P001C01CS(CHIPS)':
 'RSVD24': CDS_PINID='RSVD24';
NET_NAME
'NC_SPI_S3M_CPU1_IO2_LVC1_R'
 '@S9S_MB_2U_LIB.S9S_MB_2U(SCH_1):NC_SPI_S3M_CPU1_IO2_LVC1_R':
 C_SIGNAL='@s9s_mb_2u_lib.s9s_mb_2u(sch_1):nc_spi_s3m_cpu1_io2_lvc1_r';
NODE_NAME     U1 BD65
 '@S9S_MB_2U_LIB.S9S_MB_2U(SCH_1):PAGE46_I5@PURE_QUANTA.SOCKET4677_AZIF0045P001C01CS(CHIPS)':
 'RSVD42': CDS_PINID='RSVD42';
NET_NAME
'NC_SPI_S3M_CPU1_IO3_LVC1_R'
 '@S9S_MB_2U_LIB.S9S_MB_2U(SCH_1):NC_SPI_S3M_CPU1_IO3_LVC1_R':
 C_SIGNAL='@s9s_mb_2u_lib.s9s_mb_2u(sch_1):nc_spi_s3m_cpu1_io3_lvc1_r';
NODE_NAME     U1 BD61
 '@S9S_MB_2U_LIB.S9S_MB_2U(SCH_1):PAGE46_I5@PURE_QUANTA.SOCKET4677_AZIF0045P001C01CS(CHIPS)':
 'RSVD40': CDS_PINID='RSVD40';
NET_NAME
'NC_SPI_S3M_CPU1_OE_LVC1_R_N'
 '@S9S_MB_2U_LIB.S9S_MB_2U(SCH_1):NC_SPI_S3M_CPU1_OE_LVC1_R_N':
 C_SIGNAL='@s9s_mb_2u_lib.s9s_mb_2u(sch_1):nc_spi_s3m_cpu1_oe_lvc1_r_n';
NODE_NAME     U1 BA68
 '@S9S_MB_2U_LIB.S9S_MB_2U(SCH_1):PAGE46_I5@PURE_QUANTA.SOCKET4677_AZIF0045P001C01CS(CHIPS)':
 'RSVD34': CDS_PINID='RSVD34';
NET_NAME
'NC_U104_NC1'
 '@S9S_MB_2U_LIB.S9S_MB_2U(SCH_1):NC_U104_NC1':
 C_SIGNAL='@s9s_mb_2u_lib.s9s_mb_2u(sch_1):nc_u104_nc1';
NODE_NAME     U104 1
 '@S9S_MB_2U_LIB.S9S_MB_2U(SCH_1):PAGE152_I63@PURE_QUANTA.74LVC1G07GV(CHIPS)':
 'NC1': CDS_PINID='NC1';
NET_NAME
'NC_U150_A1'
 '@S9S_MB_2U_LIB.S9S_MB_2U(SCH_1):NC_U150_A1':
 C_SIGNAL='@s9s_mb_2u_lib.s9s_mb_2u(sch_1):nc_u150_a1';
NODE_NAME     U150 3
 '@S9S_MB_2U_LIB.S9S_MB_2U(SCH_1):PAGE213_I2@PURE_QUANTA.74LVC2G17GW(CHIPS)':
 'A1': CDS_PINID='A1';
NET_NAME
'NC_U150_B1'
 '@S9S_MB_2U_LIB.S9S_MB_2U(SCH_1):NC_U150_B1':
 C_SIGNAL='@s9s_mb_2u_lib.s9s_mb_2u(sch_1):nc_u150_b1';
NODE_NAME     U150 4
 '@S9S_MB_2U_LIB.S9S_MB_2U(SCH_1):PAGE213_I2@PURE_QUANTA.74LVC2G17GW(CHIPS)':
 'B1': CDS_PINID='B1';
NET_NAME
'NC_U157_NC1'
 '@S9S_MB_2U_LIB.S9S_MB_2U(SCH_1):NC_U157_NC1':
 C_SIGNAL='@s9s_mb_2u_lib.s9s_mb_2u(sch_1):nc_u157_nc1';
NODE_NAME     U157 1
 '@S9S_MB_2U_LIB.S9S_MB_2U(SCH_1):PAGE152_I65@PURE_QUANTA.74LVC1G07GV(CHIPS)':
 'NC1': CDS_PINID='NC1';
NET_NAME
'NC_U205_INB-'
 '@S9S_MB_2U_LIB.S9S_MB_2U(SCH_1):NC_U205_INB-':
 C_SIGNAL='@s9s_mb_2u_lib.s9s_mb_2u(sch_1):\nc_u205_inb-\';
NODE_NAME     U205 4
 '@S9S_MB_2U_LIB.S9S_MB_2U(SCH_1):PAGE326_I5@PURE_QUANTA.TPS3700DDCR(CHIPS)':
 'INB-': CDS_PINID='\inb-\';
NET_NAME
'NC_U205_OUTB'
 '@S9S_MB_2U_LIB.S9S_MB_2U(SCH_1):NC_U205_OUTB':
 C_SIGNAL='@s9s_mb_2u_lib.s9s_mb_2u(sch_1):nc_u205_outb';
NODE_NAME     U205 6
 '@S9S_MB_2U_LIB.S9S_MB_2U(SCH_1):PAGE326_I5@PURE_QUANTA.TPS3700DDCR(CHIPS)':
 'OUTB': CDS_PINID='OUTB';
NET_NAME
'NC_U218_NC1'
 '@S9S_MB_2U_LIB.S9S_MB_2U(SCH_1):NC_U218_NC1':
 C_SIGNAL='@s9s_mb_2u_lib.s9s_mb_2u(sch_1):nc_u218_nc1';
NODE_NAME     U218 1
 '@S9S_MB_2U_LIB.S9S_MB_2U(SCH_1):PAGE156_I31@PURE_QUANTA.74LVC1G07GV(CHIPS)':
 'NC1': CDS_PINID='NC1';
NET_NAME
'NC_U219_NC1'
 '@S9S_MB_2U_LIB.S9S_MB_2U(SCH_1):NC_U219_NC1':
 C_SIGNAL='@s9s_mb_2u_lib.s9s_mb_2u(sch_1):nc_u219_nc1';
NODE_NAME     U219 1
 '@S9S_MB_2U_LIB.S9S_MB_2U(SCH_1):PAGE156_I61@PURE_QUANTA.74LVC1G07GV(CHIPS)':
 'NC1': CDS_PINID='NC1';
NET_NAME
'NC_U257_2Y'
 '@S9S_MB_2U_LIB.S9S_MB_2U(SCH_1):NC_U257_2Y':
 C_SIGNAL='@s9s_mb_2u_lib.s9s_mb_2u(sch_1):nc_u257_2y';
NODE_NAME     U257 4
 '@S9S_MB_2U_LIB.S9S_MB_2U(SCH_1):PAGE296_I50@PURE_QUANTA.74LVC2G07DW7(CHIPS)':
 '2Y': CDS_PINID='\2y\';
NET_NAME
'NC_U306_A0'
 '@S9S_MB_2U_LIB.S9S_MB_2U(SCH_1):NC_U306_A0':
 C_SIGNAL='@s9s_mb_2u_lib.s9s_mb_2u(sch_1):nc_u306_a0';
NODE_NAME     U306 13
 '@S9S_MB_2U_LIB.S9S_MB_2U(SCH_1):PAGE322_I80@PURE_QUANTA.GTL2014PW(CHIPS)':
 'A0': CDS_PINID='A0';
NET_NAME
'NC_U314_FBOUT'
 '@S9S_MB_2U_LIB.S9S_MB_2U(SCH_1):NC_U314_FBOUT':
 C_SIGNAL='@s9s_mb_2u_lib.s9s_mb_2u(sch_1):nc_u314_fbout';
NODE_NAME     U314 9
 '@S9S_MB_2U_LIB.S9S_MB_2U(SCH_1):PAGE200_I1@PURE_QUANTA.9ZXL0451EKILFT(CHIPS)':
 'FBOUT_NC': CDS_PINID='FBOUT_NC';
NET_NAME
'NC_U314_FBOUT_N'
 '@S9S_MB_2U_LIB.S9S_MB_2U(SCH_1):NC_U314_FBOUT_N':
 C_SIGNAL='@s9s_mb_2u_lib.s9s_mb_2u(sch_1):nc_u314_fbout_n';
NODE_NAME     U314 8
 '@S9S_MB_2U_LIB.S9S_MB_2U(SCH_1):PAGE200_I1@PURE_QUANTA.9ZXL0451EKILFT(CHIPS)':
 'FBOUT_NC#': CDS_PINID='\fbout_nc#\';
NET_NAME
'NC_U314_NC0'
 '@S9S_MB_2U_LIB.S9S_MB_2U(SCH_1):NC_U314_NC0':
 C_SIGNAL='@s9s_mb_2u_lib.s9s_mb_2u(sch_1):nc_u314_nc0';
NODE_NAME     U314 10
 '@S9S_MB_2U_LIB.S9S_MB_2U(SCH_1):PAGE200_I1@PURE_QUANTA.9ZXL0451EKILFT(CHIPS)':
 'NC0': CDS_PINID='NC0';
NET_NAME
'NC_U314_NC1'
 '@S9S_MB_2U_LIB.S9S_MB_2U(SCH_1):NC_U314_NC1':
 C_SIGNAL='@s9s_mb_2u_lib.s9s_mb_2u(sch_1):nc_u314_nc1';
NODE_NAME     U314 11
 '@S9S_MB_2U_LIB.S9S_MB_2U(SCH_1):PAGE200_I1@PURE_QUANTA.9ZXL0451EKILFT(CHIPS)':
 'NC1': CDS_PINID='NC1';
NET_NAME
'NC_U314_NC2'
 '@S9S_MB_2U_LIB.S9S_MB_2U(SCH_1):NC_U314_NC2':
 C_SIGNAL='@s9s_mb_2u_lib.s9s_mb_2u(sch_1):nc_u314_nc2';
NODE_NAME     U314 17
 '@S9S_MB_2U_LIB.S9S_MB_2U(SCH_1):PAGE200_I1@PURE_QUANTA.9ZXL0451EKILFT(CHIPS)':
 'NC2': CDS_PINID='NC2';
NET_NAME
'NC_U314_NC3'
 '@S9S_MB_2U_LIB.S9S_MB_2U(SCH_1):NC_U314_NC3':
 C_SIGNAL='@s9s_mb_2u_lib.s9s_mb_2u(sch_1):nc_u314_nc3';
NODE_NAME     U314 30
 '@S9S_MB_2U_LIB.S9S_MB_2U(SCH_1):PAGE200_I1@PURE_QUANTA.9ZXL0451EKILFT(CHIPS)':
 'NC3': CDS_PINID='NC3';
NET_NAME
'NC_U316_2Y'
 '@S9S_MB_2U_LIB.S9S_MB_2U(SCH_1):NC_U316_2Y':
 C_SIGNAL='@s9s_mb_2u_lib.s9s_mb_2u(sch_1):nc_u316_2y';
NODE_NAME     U316 4
 '@S9S_MB_2U_LIB.S9S_MB_2U(SCH_1):PAGE139_I86@PURE_QUANTA.74LVC2G17GW(CHIPS)':
 'B1': CDS_PINID='B1';
NET_NAME
'NC_UART_IBL_CPU0_CTS'
 '@S9S_MB_2U_LIB.S9S_MB_2U(SCH_1):NC_UART_IBL_CPU0_CTS':
 C_SIGNAL='@s9s_mb_2u_lib.s9s_mb_2u(sch_1):nc_uart_ibl_cpu0_cts';
NODE_NAME     U2 CV71
 '@S9S_MB_2U_LIB.S9S_MB_2U(SCH_1):PAGE15_I1@PURE_QUANTA.SOCKET4677_AZIF0045P001C01CS(CHIPS)':
 'RSVD143': CDS_PINID='RSVD143';
NET_NAME
'NC_UART_IBL_CPU0_RTS'
 '@S9S_MB_2U_LIB.S9S_MB_2U(SCH_1):NC_UART_IBL_CPU0_RTS':
 C_SIGNAL='@s9s_mb_2u_lib.s9s_mb_2u(sch_1):nc_uart_ibl_cpu0_rts';
NODE_NAME     U2 CY71
 '@S9S_MB_2U_LIB.S9S_MB_2U(SCH_1):PAGE15_I1@PURE_QUANTA.SOCKET4677_AZIF0045P001C01CS(CHIPS)':
 'RSVD156': CDS_PINID='RSVD156';
NET_NAME
'NC_UART_IBL_CPU0_RXD'
 '@S9S_MB_2U_LIB.S9S_MB_2U(SCH_1):NC_UART_IBL_CPU0_RXD':
 C_SIGNAL='@s9s_mb_2u_lib.s9s_mb_2u(sch_1):nc_uart_ibl_cpu0_rxd';
NODE_NAME     U2 CY69
 '@S9S_MB_2U_LIB.S9S_MB_2U(SCH_1):PAGE15_I1@PURE_QUANTA.SOCKET4677_AZIF0045P001C01CS(CHIPS)':
 'RSVD155': CDS_PINID='RSVD155';
NET_NAME
'NC_UART_IBL_CPU0_TXD'
 '@S9S_MB_2U_LIB.S9S_MB_2U(SCH_1):NC_UART_IBL_CPU0_TXD':
 C_SIGNAL='@s9s_mb_2u_lib.s9s_mb_2u(sch_1):nc_uart_ibl_cpu0_txd';
NODE_NAME     U2 CV69
 '@S9S_MB_2U_LIB.S9S_MB_2U(SCH_1):PAGE15_I1@PURE_QUANTA.SOCKET4677_AZIF0045P001C01CS(CHIPS)':
 'RSVD142': CDS_PINID='RSVD142';
NET_NAME
'NC_UART_IBL_CPU1_CTS'
 '@S9S_MB_2U_LIB.S9S_MB_2U(SCH_1):NC_UART_IBL_CPU1_CTS':
 C_SIGNAL='@s9s_mb_2u_lib.s9s_mb_2u(sch_1):nc_uart_ibl_cpu1_cts';
NODE_NAME     U1 CV71
 '@S9S_MB_2U_LIB.S9S_MB_2U(SCH_1):PAGE46_I5@PURE_QUANTA.SOCKET4677_AZIF0045P001C01CS(CHIPS)':
 'RSVD143': CDS_PINID='RSVD143';
NET_NAME
'NC_UART_IBL_CPU1_RTS'
 '@S9S_MB_2U_LIB.S9S_MB_2U(SCH_1):NC_UART_IBL_CPU1_RTS':
 C_SIGNAL='@s9s_mb_2u_lib.s9s_mb_2u(sch_1):nc_uart_ibl_cpu1_rts';
NODE_NAME     U1 CY71
 '@S9S_MB_2U_LIB.S9S_MB_2U(SCH_1):PAGE46_I5@PURE_QUANTA.SOCKET4677_AZIF0045P001C01CS(CHIPS)':
 'RSVD156': CDS_PINID='RSVD156';
NET_NAME
'NC_UART_IBL_CPU1_RXD'
 '@S9S_MB_2U_LIB.S9S_MB_2U(SCH_1):NC_UART_IBL_CPU1_RXD':
 C_SIGNAL='@s9s_mb_2u_lib.s9s_mb_2u(sch_1):nc_uart_ibl_cpu1_rxd';
NODE_NAME     U1 CY69
 '@S9S_MB_2U_LIB.S9S_MB_2U(SCH_1):PAGE46_I5@PURE_QUANTA.SOCKET4677_AZIF0045P001C01CS(CHIPS)':
 'RSVD155': CDS_PINID='RSVD155';
NET_NAME
'NC_UART_IBL_CPU1_TXD'
 '@S9S_MB_2U_LIB.S9S_MB_2U(SCH_1):NC_UART_IBL_CPU1_TXD':
 C_SIGNAL='@s9s_mb_2u_lib.s9s_mb_2u(sch_1):nc_uart_ibl_cpu1_txd';
NODE_NAME     U1 CV69
 '@S9S_MB_2U_LIB.S9S_MB_2U(SCH_1):PAGE46_I5@PURE_QUANTA.SOCKET4677_AZIF0045P001C01CS(CHIPS)':
 'RSVD142': CDS_PINID='RSVD142';
NET_NAME
'NC_USB_HUB_2_DM2'
 '@S9S_MB_2U_LIB.S9S_MB_2U(SCH_1):NC_USB_HUB_2_DM2':
 C_SIGNAL='@s9s_mb_2u_lib.s9s_mb_2u(sch_1):nc_usb_hub_2_dm2';
NODE_NAME     U313 6
 '@S9S_MB_2U_LIB.S9S_MB_2U(SCH_1):PAGE194_I40@PURE_QUANTA.GL852GOHY60(CHIPS)':
 'DM2': CDS_PINID='DM2';
NET_NAME
'NC_USB_HUB_2_DM3'
 '@S9S_MB_2U_LIB.S9S_MB_2U(SCH_1):NC_USB_HUB_2_DM3':
 C_SIGNAL='@s9s_mb_2u_lib.s9s_mb_2u(sch_1):nc_usb_hub_2_dm3';
NODE_NAME     U313 12
 '@S9S_MB_2U_LIB.S9S_MB_2U(SCH_1):PAGE194_I40@PURE_QUANTA.GL852GOHY60(CHIPS)':
 'DM3': CDS_PINID='DM3';
NET_NAME
'NC_USB_HUB_2_DM4'
 '@S9S_MB_2U_LIB.S9S_MB_2U(SCH_1):NC_USB_HUB_2_DM4':
 C_SIGNAL='@s9s_mb_2u_lib.s9s_mb_2u(sch_1):nc_usb_hub_2_dm4';
NODE_NAME     U313 15
 '@S9S_MB_2U_LIB.S9S_MB_2U(SCH_1):PAGE194_I40@PURE_QUANTA.GL852GOHY60(CHIPS)':
 'DM4': CDS_PINID='DM4';
NET_NAME
'NC_USB_HUB_2_DP2'
 '@S9S_MB_2U_LIB.S9S_MB_2U(SCH_1):NC_USB_HUB_2_DP2':
 C_SIGNAL='@s9s_mb_2u_lib.s9s_mb_2u(sch_1):nc_usb_hub_2_dp2';
NODE_NAME     U313 7
 '@S9S_MB_2U_LIB.S9S_MB_2U(SCH_1):PAGE194_I40@PURE_QUANTA.GL852GOHY60(CHIPS)':
 'DP2': CDS_PINID='DP2';
NET_NAME
'NC_USB_HUB_2_DP3'
 '@S9S_MB_2U_LIB.S9S_MB_2U(SCH_1):NC_USB_HUB_2_DP3':
 C_SIGNAL='@s9s_mb_2u_lib.s9s_mb_2u(sch_1):nc_usb_hub_2_dp3';
NODE_NAME     U313 13
 '@S9S_MB_2U_LIB.S9S_MB_2U(SCH_1):PAGE194_I40@PURE_QUANTA.GL852GOHY60(CHIPS)':
 'DP3': CDS_PINID='DP3';
NET_NAME
'NC_USB_HUB_2_DP4'
 '@S9S_MB_2U_LIB.S9S_MB_2U(SCH_1):NC_USB_HUB_2_DP4':
 C_SIGNAL='@s9s_mb_2u_lib.s9s_mb_2u(sch_1):nc_usb_hub_2_dp4';
NODE_NAME     U313 16
 '@S9S_MB_2U_LIB.S9S_MB_2U(SCH_1):PAGE194_I40@PURE_QUANTA.GL852GOHY60(CHIPS)':
 'DP4': CDS_PINID='DP4';
NET_NAME
'NC_USB_HUB_2_SDA'
 '@S9S_MB_2U_LIB.S9S_MB_2U(SCH_1):NC_USB_HUB_2_SDA':
 C_SIGNAL='@s9s_mb_2u_lib.s9s_mb_2u(sch_1):nc_usb_hub_2_sda';
NODE_NAME     U313 26
 '@S9S_MB_2U_LIB.S9S_MB_2U(SCH_1):PAGE194_I40@PURE_QUANTA.GL852GOHY60(CHIPS)':
 'SDA': CDS_PINID='SDA';
NET_NAME
'NC_USB_HUB_DM2'
 '@S9S_MB_2U_LIB.S9S_MB_2U(SCH_1):NC_USB_HUB_DM2':
 C_SIGNAL='@s9s_mb_2u_lib.s9s_mb_2u(sch_1):nc_usb_hub_dm2';
NODE_NAME     U268 6
 '@S9S_MB_2U_LIB.S9S_MB_2U(SCH_1):PAGE155_I100@PURE_QUANTA.GL852GOHY60(CHIPS)':
 'DM2': CDS_PINID='DM2';
NET_NAME
'NC_USB_HUB_DM3'
 '@S9S_MB_2U_LIB.S9S_MB_2U(SCH_1):NC_USB_HUB_DM3':
 C_SIGNAL='@s9s_mb_2u_lib.s9s_mb_2u(sch_1):nc_usb_hub_dm3';
NODE_NAME     U268 12
 '@S9S_MB_2U_LIB.S9S_MB_2U(SCH_1):PAGE155_I100@PURE_QUANTA.GL852GOHY60(CHIPS)':
 'DM3': CDS_PINID='DM3';
NET_NAME
'NC_USB_HUB_DM4'
 '@S9S_MB_2U_LIB.S9S_MB_2U(SCH_1):NC_USB_HUB_DM4':
 C_SIGNAL='@s9s_mb_2u_lib.s9s_mb_2u(sch_1):nc_usb_hub_dm4';
NODE_NAME     U268 15
 '@S9S_MB_2U_LIB.S9S_MB_2U(SCH_1):PAGE155_I100@PURE_QUANTA.GL852GOHY60(CHIPS)':
 'DM4': CDS_PINID='DM4';
NET_NAME
'NC_USB_HUB_DP2'
 '@S9S_MB_2U_LIB.S9S_MB_2U(SCH_1):NC_USB_HUB_DP2':
 C_SIGNAL='@s9s_mb_2u_lib.s9s_mb_2u(sch_1):nc_usb_hub_dp2';
NODE_NAME     U268 7
 '@S9S_MB_2U_LIB.S9S_MB_2U(SCH_1):PAGE155_I100@PURE_QUANTA.GL852GOHY60(CHIPS)':
 'DP2': CDS_PINID='DP2';
NET_NAME
'NC_USB_HUB_DP3'
 '@S9S_MB_2U_LIB.S9S_MB_2U(SCH_1):NC_USB_HUB_DP3':
 C_SIGNAL='@s9s_mb_2u_lib.s9s_mb_2u(sch_1):nc_usb_hub_dp3';
NODE_NAME     U268 13
 '@S9S_MB_2U_LIB.S9S_MB_2U(SCH_1):PAGE155_I100@PURE_QUANTA.GL852GOHY60(CHIPS)':
 'DP3': CDS_PINID='DP3';
NET_NAME
'NC_USB_HUB_DP4'
 '@S9S_MB_2U_LIB.S9S_MB_2U(SCH_1):NC_USB_HUB_DP4':
 C_SIGNAL='@s9s_mb_2u_lib.s9s_mb_2u(sch_1):nc_usb_hub_dp4';
NODE_NAME     U268 16
 '@S9S_MB_2U_LIB.S9S_MB_2U(SCH_1):PAGE155_I100@PURE_QUANTA.GL852GOHY60(CHIPS)':
 'DP4': CDS_PINID='DP4';
NET_NAME
'NC_USB_HUB_SDA'
 '@S9S_MB_2U_LIB.S9S_MB_2U(SCH_1):NC_USB_HUB_SDA':
 C_SIGNAL='@s9s_mb_2u_lib.s9s_mb_2u(sch_1):nc_usb_hub_sda';
NODE_NAME     U268 26
 '@S9S_MB_2U_LIB.S9S_MB_2U(SCH_1):PAGE155_I100@PURE_QUANTA.GL852GOHY60(CHIPS)':
 'SDA': CDS_PINID='SDA';
NET_NAME
'NC_UXX_2Y'
 '@S9S_MB_2U_LIB.S9S_MB_2U(SCH_1):NC_UXX_2Y':
 C_SIGNAL='@s9s_mb_2u_lib.s9s_mb_2u(sch_1):nc_uxx_2y';
NODE_NAME     U332 4
 '@S9S_MB_2U_LIB.S9S_MB_2U(SCH_1):PAGE213_I37@PURE_QUANTA.74LVC2G07DW7(CHIPS)':
 '2Y': CDS_PINID='\2y\';
NET_NAME
'NC_XTAL_CPU0_25M_IN'
 '@S9S_MB_2U_LIB.S9S_MB_2U(SCH_1):NC_XTAL_CPU0_25M_IN':
 C_SIGNAL='@s9s_mb_2u_lib.s9s_mb_2u(sch_1):nc_xtal_cpu0_25m_in';
NODE_NAME     U2 G5
 '@S9S_MB_2U_LIB.S9S_MB_2U(SCH_1):PAGE13_I57@PURE_QUANTA.SOCKET4677_AZIF0045P001C01CS(CHIPS)':
 'RSVD161': CDS_PINID='RSVD161';
NET_NAME
'NC_XTAL_CPU0_25M_OUT'
 '@S9S_MB_2U_LIB.S9S_MB_2U(SCH_1):NC_XTAL_CPU0_25M_OUT':
 C_SIGNAL='@s9s_mb_2u_lib.s9s_mb_2u(sch_1):nc_xtal_cpu0_25m_out';
NODE_NAME     U2 D4
 '@S9S_MB_2U_LIB.S9S_MB_2U(SCH_1):PAGE13_I57@PURE_QUANTA.SOCKET4677_AZIF0045P001C01CS(CHIPS)':
 'RSVD157': CDS_PINID='RSVD157';
NET_NAME
'OCP_SFF_AUX_PWR_EN'
 '@S9S_MB_2U_LIB.S9S_MB_2U(SCH_1):OCP_SFF_AUX_PWR_EN':
 C_SIGNAL='@s9s_mb_2u_lib.s9s_mb_2u(sch_1):ocp_sff_aux_pwr_en';
NODE_NAME     R1929 2
 '@S9S_MB_2U_LIB.S9S_MB_2U(SCH_1):PAGE150_I37@PURE_QUANTA.Q_RES(CHIPS)':
 'B': CDS_PINID='B';
NODE_NAME     R1671 1
 '@S9S_MB_2U_LIB.S9S_MB_2U(SCH_1):PAGE150_I51@PURE_QUANTA.Q_RES(CHIPS)':
 'A': CDS_PINID='A';
NODE_NAME     R3231 1
 '@S9S_MB_2U_LIB.S9S_MB_2U(SCH_1):PAGE151_I3@PURE_QUANTA.Q_RES(CHIPS)':
 'A': CDS_PINID='A';
NODE_NAME     R1719 1
 '@S9S_MB_2U_LIB.S9S_MB_2U(SCH_1):PAGE151_I5@PURE_QUANTA.Q_RES(CHIPS)':
 'A': CDS_PINID='A';
NODE_NAME     R4750 2
 '@S9S_MB_2U_LIB.S9S_MB_2U(SCH_1):PAGE154_I247@PURE_QUANTA.Q_RES(CHIPS)':
 'B': CDS_PINID='B';
NET_NAME
'OCP_SFF_AUX_PWR_EN_R'
 '@S9S_MB_2U_LIB.S9S_MB_2U(SCH_1):OCP_SFF_AUX_PWR_EN_R':
 C_SIGNAL='@s9s_mb_2u_lib.s9s_mb_2u(sch_1):ocp_sff_aux_pwr_en_r';
NODE_NAME     R1671 2
 '@S9S_MB_2U_LIB.S9S_MB_2U(SCH_1):PAGE150_I51@PURE_QUANTA.Q_RES(CHIPS)':
 'B': CDS_PINID='B';
NODE_NAME     J37 B12
 '@S9S_MB_2U_LIB.S9S_MB_2U(SCH_1):PAGE150_I199@PURE_QUANTA.SCONN168_ME1016810202011(CHIPS)':
 'AUX_PWR_EN': CDS_PINID='AUX_PWR_EN';
NET_NAME
'OCP_SFF_AUX_PWR_EN_R1'
 '@S9S_MB_2U_LIB.S9S_MB_2U(SCH_1):OCP_SFF_AUX_PWR_EN_R1':
 C_SIGNAL='@s9s_mb_2u_lib.s9s_mb_2u(sch_1):ocp_sff_aux_pwr_en_r1';
NODE_NAME     R1719 2
 '@S9S_MB_2U_LIB.S9S_MB_2U(SCH_1):PAGE151_I5@PURE_QUANTA.Q_RES(CHIPS)':
 'B': CDS_PINID='B';
NODE_NAME     U66 1
 '@S9S_MB_2U_LIB.S9S_MB_2U(SCH_1):PAGE151_I15@PURE_QUANTA.74LVC1G126SE7(CHIPS)':
 'OE': CDS_PINID='OE';
NET_NAME
'OCP_SFF_AUX_PWR_EN_R2'
 '@S9S_MB_2U_LIB.S9S_MB_2U(SCH_1):OCP_SFF_AUX_PWR_EN_R2':
 C_SIGNAL='@s9s_mb_2u_lib.s9s_mb_2u(sch_1):ocp_sff_aux_pwr_en_r2';
NODE_NAME     U334 4
 '@S9S_MB_2U_LIB.S9S_MB_2U(SCH_1):PAGE154_I243@PURE_QUANTA.74LVC1G08W57(CHIPS)':
 'Y': CDS_PINID='Y';
NODE_NAME     R4750 1
 '@S9S_MB_2U_LIB.S9S_MB_2U(SCH_1):PAGE154_I247@PURE_QUANTA.Q_RES(CHIPS)':
 'A': CDS_PINID='A';
NODE_NAME     R4748 2
 '@S9S_MB_2U_LIB.S9S_MB_2U(SCH_1):PAGE154_I253@PURE_QUANTA.Q_RES(CHIPS)':
 'B': CDS_PINID='B';
NODE_NAME     R4749 2
 '@S9S_MB_2U_LIB.S9S_MB_2U(SCH_1):PAGE154_I254@PURE_QUANTA.Q_RES(CHIPS)':
 'B': CDS_PINID='B';
NET_NAME
'OCP_SFF_AUX_PWR_EN_R4'
 '@S9S_MB_2U_LIB.S9S_MB_2U(SCH_1):OCP_SFF_AUX_PWR_EN_R4':
 C_SIGNAL='@s9s_mb_2u_lib.s9s_mb_2u(sch_1):ocp_sff_aux_pwr_en_r4';
NODE_NAME     R3231 2
 '@S9S_MB_2U_LIB.S9S_MB_2U(SCH_1):PAGE151_I3@PURE_QUANTA.Q_RES(CHIPS)':
 'B': CDS_PINID='B';
NODE_NAME     U224 1
 '@S9S_MB_2U_LIB.S9S_MB_2U(SCH_1):PAGE151_I7@PURE_QUANTA.74LVC1G126SE7(CHIPS)':
 'OE': CDS_PINID='OE';
NET_NAME
'OCP_SFF_AUX_PWR_PLD_EN'
 '@S9S_MB_2U_LIB.S9S_MB_2U(SCH_1):OCP_SFF_AUX_PWR_PLD_EN':
 C_SIGNAL='@s9s_mb_2u_lib.s9s_mb_2u(sch_1):ocp_sff_aux_pwr_pld_en';
NODE_NAME     U249 E7
 '@S9S_MB_2U_LIB.S9S_MB_2U(SCH_1):PAGE314_I188@PURE_QUANTA.LCMXO3LF9400C5BG484C(CHIPS)':
 'PT13D': CDS_PINID='PT13D';
NODE_NAME     R4747 1
 '@S9S_MB_2U_LIB.S9S_MB_2U(SCH_1):PAGE154_I249@PURE_QUANTA.Q_RES(CHIPS)':
 'A': CDS_PINID='A';
NET_NAME
'OCP_SFF_AUX_PWR_PLD_EN_R'
 '@S9S_MB_2U_LIB.S9S_MB_2U(SCH_1):OCP_SFF_AUX_PWR_PLD_EN_R':
 C_SIGNAL='@s9s_mb_2u_lib.s9s_mb_2u(sch_1):ocp_sff_aux_pwr_pld_en_r';
NODE_NAME     U334 2
 '@S9S_MB_2U_LIB.S9S_MB_2U(SCH_1):PAGE154_I243@PURE_QUANTA.74LVC1G08W57(CHIPS)':
 'B': CDS_PINID='B';
NODE_NAME     R4747 2
 '@S9S_MB_2U_LIB.S9S_MB_2U(SCH_1):PAGE154_I249@PURE_QUANTA.Q_RES(CHIPS)':
 'B': CDS_PINID='B';
NODE_NAME     R4749 1
 '@S9S_MB_2U_LIB.S9S_MB_2U(SCH_1):PAGE154_I254@PURE_QUANTA.Q_RES(CHIPS)':
 'A': CDS_PINID='A';
NODE_NAME     R4745 2
 '@S9S_MB_2U_LIB.S9S_MB_2U(SCH_1):PAGE154_I256@PURE_QUANTA.Q_RES(CHIPS)':
 'B': CDS_PINID='B';
NET_NAME
'OCP_SFF_BIF0_R_N'
 '@S9S_MB_2U_LIB.S9S_MB_2U(SCH_1):OCP_SFF_BIF0_R_N':
 C_SIGNAL='@s9s_mb_2u_lib.s9s_mb_2u(sch_1):ocp_sff_bif0_r_n';
NODE_NAME     R416 2
 '@S9S_MB_2U_LIB.S9S_MB_2U(SCH_1):PAGE150_I54@PURE_QUANTA.Q_RES(CHIPS)':
 'B': CDS_PINID='B';
NODE_NAME     J37 B7
 '@S9S_MB_2U_LIB.S9S_MB_2U(SCH_1):PAGE150_I199@PURE_QUANTA.SCONN168_ME1016810202011(CHIPS)':
 'BIF0#': CDS_PINID='\bif0#\';
NET_NAME
'OCP_SFF_BIF1_R_N'
 '@S9S_MB_2U_LIB.S9S_MB_2U(SCH_1):OCP_SFF_BIF1_R_N':
 C_SIGNAL='@s9s_mb_2u_lib.s9s_mb_2u(sch_1):ocp_sff_bif1_r_n';
NODE_NAME     R417 2
 '@S9S_MB_2U_LIB.S9S_MB_2U(SCH_1):PAGE150_I53@PURE_QUANTA.Q_RES(CHIPS)':
 'B': CDS_PINID='B';
NODE_NAME     J37 B8
 '@S9S_MB_2U_LIB.S9S_MB_2U(SCH_1):PAGE150_I199@PURE_QUANTA.SCONN168_ME1016810202011(CHIPS)':
 'BIF1#': CDS_PINID='\bif1#\';
NET_NAME
'OCP_SFF_BIF2_R_N'
 '@S9S_MB_2U_LIB.S9S_MB_2U(SCH_1):OCP_SFF_BIF2_R_N':
 C_SIGNAL='@s9s_mb_2u_lib.s9s_mb_2u(sch_1):ocp_sff_bif2_r_n';
NODE_NAME     R418 2
 '@S9S_MB_2U_LIB.S9S_MB_2U(SCH_1):PAGE150_I52@PURE_QUANTA.Q_RES(CHIPS)':
 'B': CDS_PINID='B';
NODE_NAME     J37 B9
 '@S9S_MB_2U_LIB.S9S_MB_2U(SCH_1):PAGE150_I199@PURE_QUANTA.SCONN168_ME1016810202011(CHIPS)':
 'BIF2#': CDS_PINID='\bif2#\';
NET_NAME
'OCP_SFF_CLK_OE_N'
 '@S9S_MB_2U_LIB.S9S_MB_2U(SCH_1):OCP_SFF_CLK_OE_N':
 C_SIGNAL='@s9s_mb_2u_lib.s9s_mb_2u(sch_1):ocp_sff_clk_oe_n';
NODE_NAME     R1543 1
 '@S9S_MB_2U_LIB.S9S_MB_2U(SCH_1):PAGE195_I534@PURE_QUANTA.Q_RES(CHIPS)':
 'A': CDS_PINID='A';
NODE_NAME     R2562 1
 '@S9S_MB_2U_LIB.S9S_MB_2U(SCH_1):PAGE195_I535@PURE_QUANTA.Q_RES(CHIPS)':
 'A': CDS_PINID='A';
NODE_NAME     R3636 1
 '@S9S_MB_2U_LIB.S9S_MB_2U(SCH_1):PAGE195_I536@PURE_QUANTA.Q_RES(CHIPS)':
 'A': CDS_PINID='A';
NODE_NAME     R3637 1
 '@S9S_MB_2U_LIB.S9S_MB_2U(SCH_1):PAGE195_I537@PURE_QUANTA.Q_RES(CHIPS)':
 'A': CDS_PINID='A';
NODE_NAME     R4517 2
 '@S9S_MB_2U_LIB.S9S_MB_2U(SCH_1):PAGE195_I540@PURE_QUANTA.Q_RES(CHIPS)':
 'B': CDS_PINID='B';
NODE_NAME     R4495 2
 '@S9S_MB_2U_LIB.S9S_MB_2U(SCH_1):PAGE314_I141@PURE_QUANTA.Q_RES(CHIPS)':
 'B': CDS_PINID='B';
NET_NAME
'OCP_SFF_CLK_OE_R_N'
 '@S9S_MB_2U_LIB.S9S_MB_2U(SCH_1):OCP_SFF_CLK_OE_R_N':
 C_SIGNAL='@s9s_mb_2u_lib.s9s_mb_2u(sch_1):ocp_sff_clk_oe_r_n';
NODE_NAME     R4495 1
 '@S9S_MB_2U_LIB.S9S_MB_2U(SCH_1):PAGE314_I141@PURE_QUANTA.Q_RES(CHIPS)':
 'A': CDS_PINID='A';
NODE_NAME     U249 C8
 '@S9S_MB_2U_LIB.S9S_MB_2U(SCH_1):PAGE314_I188@PURE_QUANTA.LCMXO3LF9400C5BG484C(CHIPS)':
 'PT15A': CDS_PINID='PT15A';
NET_NAME
'OCP_SFF_ID0'
 '@S9S_MB_2U_LIB.S9S_MB_2U(SCH_1):OCP_SFF_ID0':
 C_SIGNAL='@s9s_mb_2u_lib.s9s_mb_2u(sch_1):ocp_sff_id0';
NODE_NAME     R410 1
 '@S9S_MB_2U_LIB.S9S_MB_2U(SCH_1):PAGE150_I2@PURE_QUANTA.Q_RES(CHIPS)':
 'A': CDS_PINID='A';
NODE_NAME     R409 2
 '@S9S_MB_2U_LIB.S9S_MB_2U(SCH_1):PAGE150_I5@PURE_QUANTA.Q_RES(CHIPS)':
 'B': CDS_PINID='B';
NODE_NAME     J37 OB7
 '@S9S_MB_2U_LIB.S9S_MB_2U(SCH_1):PAGE150_I199@PURE_QUANTA.SCONN168_ME1016810202011(CHIPS)':
 'SLOT_ID0': CDS_PINID='SLOT_ID0';
NET_NAME
'OCP_SFF_ID1'
 '@S9S_MB_2U_LIB.S9S_MB_2U(SCH_1):OCP_SFF_ID1':
 C_SIGNAL='@s9s_mb_2u_lib.s9s_mb_2u(sch_1):ocp_sff_id1';
NODE_NAME     R415 1
 '@S9S_MB_2U_LIB.S9S_MB_2U(SCH_1):PAGE150_I4@PURE_QUANTA.Q_RES(CHIPS)':
 'A': CDS_PINID='A';
NODE_NAME     R414 2
 '@S9S_MB_2U_LIB.S9S_MB_2U(SCH_1):PAGE150_I6@PURE_QUANTA.Q_RES(CHIPS)':
 'B': CDS_PINID='B';
NODE_NAME     J37 OA6
 '@S9S_MB_2U_LIB.S9S_MB_2U(SCH_1):PAGE150_I199@PURE_QUANTA.SCONN168_ME1016810202011(CHIPS)':
 'SLOT_ID1': CDS_PINID='SLOT_ID1';
NET_NAME
'OCP_SFF_ISO1_RBT_ARB_IN'
 '@S9S_MB_2U_LIB.S9S_MB_2U(SCH_1):OCP_SFF_ISO1_RBT_ARB_IN':
 C_SIGNAL='@s9s_mb_2u_lib.s9s_mb_2u(sch_1):ocp_sff_iso1_rbt_arb_in';
NODE_NAME     J37 OA4
 '@S9S_MB_2U_LIB.S9S_MB_2U(SCH_1):PAGE150_I199@PURE_QUANTA.SCONN168_ME1016810202011(CHIPS)':
 'RBT_ARB_IN': CDS_PINID='RBT_ARB_IN';
NODE_NAME     U67 11
 '@S9S_MB_2U_LIB.S9S_MB_2U(SCH_1):PAGE151_I39@PURE_QUANTA.74CBTLV3126PW(CHIPS)':
 '4B': CDS_PINID='\4b\';
NET_NAME
'OCP_SFF_ISO2_RBT_ARB_OUT'
 '@S9S_MB_2U_LIB.S9S_MB_2U(SCH_1):OCP_SFF_ISO2_RBT_ARB_OUT':
 C_SIGNAL='@s9s_mb_2u_lib.s9s_mb_2u(sch_1):ocp_sff_iso2_rbt_arb_out';
NODE_NAME     J37 OA5
 '@S9S_MB_2U_LIB.S9S_MB_2U(SCH_1):PAGE150_I199@PURE_QUANTA.SCONN168_ME1016810202011(CHIPS)':
 'RBT_ARB_OUT': CDS_PINID='RBT_ARB_OUT';
NODE_NAME     U68 11
 '@S9S_MB_2U_LIB.S9S_MB_2U(SCH_1):PAGE151_I30@PURE_QUANTA.74CBTLV3126PW(CHIPS)':
 '4B': CDS_PINID='\4b\';
NET_NAME
'OCP_SFF_ISO_BIF0_EN'
 '@S9S_MB_2U_LIB.S9S_MB_2U(SCH_1):OCP_SFF_ISO_BIF0_EN':
 C_SIGNAL='@s9s_mb_2u_lib.s9s_mb_2u(sch_1):ocp_sff_iso_bif0_en';
NODE_NAME     R416 1
 '@S9S_MB_2U_LIB.S9S_MB_2U(SCH_1):PAGE150_I54@PURE_QUANTA.Q_RES(CHIPS)':
 'A': CDS_PINID='A';
NODE_NAME     R1896 1
 '@S9S_MB_2U_LIB.S9S_MB_2U(SCH_1):PAGE151_I43@PURE_QUANTA.Q_RES(CHIPS)':
 'A': CDS_PINID='A';
NET_NAME
'OCP_SFF_ISO_BIF1_EN'
 '@S9S_MB_2U_LIB.S9S_MB_2U(SCH_1):OCP_SFF_ISO_BIF1_EN':
 C_SIGNAL='@s9s_mb_2u_lib.s9s_mb_2u(sch_1):ocp_sff_iso_bif1_en';
NODE_NAME     R417 1
 '@S9S_MB_2U_LIB.S9S_MB_2U(SCH_1):PAGE150_I53@PURE_QUANTA.Q_RES(CHIPS)':
 'A': CDS_PINID='A';
NODE_NAME     R1897 1
 '@S9S_MB_2U_LIB.S9S_MB_2U(SCH_1):PAGE151_I50@PURE_QUANTA.Q_RES(CHIPS)':
 'A': CDS_PINID='A';
NET_NAME
'OCP_SFF_ISO_BIF2_EN'
 '@S9S_MB_2U_LIB.S9S_MB_2U(SCH_1):OCP_SFF_ISO_BIF2_EN':
 C_SIGNAL='@s9s_mb_2u_lib.s9s_mb_2u(sch_1):ocp_sff_iso_bif2_en';
NODE_NAME     R418 1
 '@S9S_MB_2U_LIB.S9S_MB_2U(SCH_1):PAGE150_I52@PURE_QUANTA.Q_RES(CHIPS)':
 'A': CDS_PINID='A';
NODE_NAME     R1898 1
 '@S9S_MB_2U_LIB.S9S_MB_2U(SCH_1):PAGE151_I52@PURE_QUANTA.Q_RES(CHIPS)':
 'A': CDS_PINID='A';
NET_NAME
'OCP_SFF_MAIN_PWR_EN'
 '@S9S_MB_2U_LIB.S9S_MB_2U(SCH_1):OCP_SFF_MAIN_PWR_EN':
 C_SIGNAL='@s9s_mb_2u_lib.s9s_mb_2u(sch_1):ocp_sff_main_pwr_en';
NODE_NAME     R1930 2
 '@S9S_MB_2U_LIB.S9S_MB_2U(SCH_1):PAGE150_I36@PURE_QUANTA.Q_RES(CHIPS)':
 'B': CDS_PINID='B';
NODE_NAME     R429 1
 '@S9S_MB_2U_LIB.S9S_MB_2U(SCH_1):PAGE150_I58@PURE_QUANTA.Q_RES(CHIPS)':
 'A': CDS_PINID='A';
NODE_NAME     U249 T18
 '@S9S_MB_2U_LIB.S9S_MB_2U(SCH_1):PAGE313_I1@PURE_QUANTA.LCMXO3LF9400C5BG484C(CHIPS)':
 'PR27B': CDS_PINID='PR27B';
NET_NAME
'OCP_SFF_MAIN_PWR_EN_R'
 '@S9S_MB_2U_LIB.S9S_MB_2U(SCH_1):OCP_SFF_MAIN_PWR_EN_R':
 C_SIGNAL='@s9s_mb_2u_lib.s9s_mb_2u(sch_1):ocp_sff_main_pwr_en_r';
NODE_NAME     R429 2
 '@S9S_MB_2U_LIB.S9S_MB_2U(SCH_1):PAGE150_I58@PURE_QUANTA.Q_RES(CHIPS)':
 'B': CDS_PINID='B';
NODE_NAME     J37 OB2
 '@S9S_MB_2U_LIB.S9S_MB_2U(SCH_1):PAGE150_I199@PURE_QUANTA.SCONN168_ME1016810202011(CHIPS)':
 'MAIN_PWR_EN': CDS_PINID='MAIN_PWR_EN';
NET_NAME
'OCP_SFF_NOT_PRSNT_RBT_ARB_IN'
 '@S9S_MB_2U_LIB.S9S_MB_2U(SCH_1):OCP_SFF_NOT_PRSNT_RBT_ARB_IN':
 C_SIGNAL='@s9s_mb_2u_lib.s9s_mb_2u(sch_1):ocp_sff_not_prsnt_rbt_arb_in';
NODE_NAME     U243 1
 '@S9S_MB_2U_LIB.S9S_MB_2U(SCH_1):PAGE170_I15@PURE_QUANTA.NC7SB3157(CHIPS)':
 'B1': CDS_PINID='B1';
NODE_NAME     U244 1
 '@S9S_MB_2U_LIB.S9S_MB_2U(SCH_1):PAGE170_I16@PURE_QUANTA.NC7SB3157(CHIPS)':
 'B1': CDS_PINID='B1';
NET_NAME
'OCP_SFF_P3V3_ADC_ALERT'
 '@S9S_MB_2U_LIB.S9S_MB_2U(SCH_1):OCP_SFF_P3V3_ADC_ALERT':
 C_SIGNAL='@s9s_mb_2u_lib.s9s_mb_2u(sch_1):ocp_sff_p3v3_adc_alert';
NODE_NAME     U249 K20
 '@S9S_MB_2U_LIB.S9S_MB_2U(SCH_1):PAGE313_I1@PURE_QUANTA.LCMXO3LF9400C5BG484C(CHIPS)':
 'PR12D': CDS_PINID='PR12D';
NODE_NAME     R3563 2
 '@S9S_MB_2U_LIB.S9S_MB_2U(SCH_1):PAGE295_I35@PURE_QUANTA.Q_RES(CHIPS)':
 'B': CDS_PINID='B';
NET_NAME
'OCP_SFF_P3V3_ADC_ALERT_R'
 '@S9S_MB_2U_LIB.S9S_MB_2U(SCH_1):OCP_SFF_P3V3_ADC_ALERT_R':
 C_SIGNAL='@s9s_mb_2u_lib.s9s_mb_2u(sch_1):ocp_sff_p3v3_adc_alert_r';
NODE_NAME     U266 3
 '@S9S_MB_2U_LIB.S9S_MB_2U(SCH_1):PAGE295_I30@PURE_QUANTA.INA230AIRGTR(CHIPS)':
 'ALERT': CDS_PINID='ALERT';
NODE_NAME     R3563 1
 '@S9S_MB_2U_LIB.S9S_MB_2U(SCH_1):PAGE295_I35@PURE_QUANTA.Q_RES(CHIPS)':
 'A': CDS_PINID='A';
NODE_NAME     R4094 2
 '@S9S_MB_2U_LIB.S9S_MB_2U(SCH_1):PAGE295_I151@PURE_QUANTA.Q_RES(CHIPS)':
 'B': CDS_PINID='B';
NET_NAME
'OCP_SFF_PRSNT01_R_N'
 '@S9S_MB_2U_LIB.S9S_MB_2U(SCH_1):OCP_SFF_PRSNT01_R_N':
 C_SIGNAL='@s9s_mb_2u_lib.s9s_mb_2u(sch_1):ocp_sff_prsnt01_r_n';
NODE_NAME     U240 7
 '@S9S_MB_2U_LIB.S9S_MB_2U(SCH_1):PAGE170_I11@PURE_QUANTA.74LVC2G08DP(CHIPS)':
 '1Y': CDS_PINID='\1y\';
NODE_NAME     U242 1
 '@S9S_MB_2U_LIB.S9S_MB_2U(SCH_1):PAGE170_I13@PURE_QUANTA.74LVC2G08DP(CHIPS)':
 '1A': CDS_PINID='\1a\';
NET_NAME
'OCP_SFF_PRSNT0_R_N'
 '@S9S_MB_2U_LIB.S9S_MB_2U(SCH_1):OCP_SFF_PRSNT0_R_N':
 C_SIGNAL='@s9s_mb_2u_lib.s9s_mb_2u(sch_1):ocp_sff_prsnt0_r_n';
NODE_NAME     U240 1
 '@S9S_MB_2U_LIB.S9S_MB_2U(SCH_1):PAGE170_I11@PURE_QUANTA.74LVC2G08DP(CHIPS)':
 '1A': CDS_PINID='\1a\';
NODE_NAME     J37 B42
 '@S9S_MB_2U_LIB.S9S_MB_2U(SCH_1):PAGE150_I199@PURE_QUANTA.SCONN168_ME1016810202011(CHIPS)':
 'PRSNTB0#': CDS_PINID='\prsntb0#\';
NODE_NAME     U211 1
 '@S9S_MB_2U_LIB.S9S_MB_2U(SCH_1):PAGE153_I26@PURE_QUANTA.74LVC2G07DW7(CHIPS)':
 '1A': CDS_PINID='\1a\';
NODE_NAME     R1905 2
 '@S9S_MB_2U_LIB.S9S_MB_2U(SCH_1):PAGE153_I13@PURE_QUANTA.Q_RES(CHIPS)':
 'B': CDS_PINID='B';
NET_NAME
'OCP_SFF_PRSNT1_R_N'
 '@S9S_MB_2U_LIB.S9S_MB_2U(SCH_1):OCP_SFF_PRSNT1_R_N':
 C_SIGNAL='@s9s_mb_2u_lib.s9s_mb_2u(sch_1):ocp_sff_prsnt1_r_n';
NODE_NAME     U240 2
 '@S9S_MB_2U_LIB.S9S_MB_2U(SCH_1):PAGE170_I11@PURE_QUANTA.74LVC2G08DP(CHIPS)':
 '1B': CDS_PINID='\1b\';
NODE_NAME     J37 A42
 '@S9S_MB_2U_LIB.S9S_MB_2U(SCH_1):PAGE150_I199@PURE_QUANTA.SCONN168_ME1016810202011(CHIPS)':
 'PRSNTB1#': CDS_PINID='\prsntb1#\';
NODE_NAME     U211 3
 '@S9S_MB_2U_LIB.S9S_MB_2U(SCH_1):PAGE153_I26@PURE_QUANTA.74LVC2G07DW7(CHIPS)':
 '2A': CDS_PINID='\2a\';
NODE_NAME     R1907 2
 '@S9S_MB_2U_LIB.S9S_MB_2U(SCH_1):PAGE153_I25@PURE_QUANTA.Q_RES(CHIPS)':
 'B': CDS_PINID='B';
NET_NAME
'OCP_SFF_PRSNT23_R_N'
 '@S9S_MB_2U_LIB.S9S_MB_2U(SCH_1):OCP_SFF_PRSNT23_R_N':
 C_SIGNAL='@s9s_mb_2u_lib.s9s_mb_2u(sch_1):ocp_sff_prsnt23_r_n';
NODE_NAME     U240 3
 '@S9S_MB_2U_LIB.S9S_MB_2U(SCH_1):PAGE170_I12@PURE_QUANTA.74LVC2G08DP(CHIPS)':
 '2Y': CDS_PINID='\2y\';
NODE_NAME     U242 2
 '@S9S_MB_2U_LIB.S9S_MB_2U(SCH_1):PAGE170_I13@PURE_QUANTA.74LVC2G08DP(CHIPS)':
 '1B': CDS_PINID='\1b\';
NET_NAME
'OCP_SFF_PRSNT2_R_N'
 '@S9S_MB_2U_LIB.S9S_MB_2U(SCH_1):OCP_SFF_PRSNT2_R_N':
 C_SIGNAL='@s9s_mb_2u_lib.s9s_mb_2u(sch_1):ocp_sff_prsnt2_r_n';
NODE_NAME     U240 5
 '@S9S_MB_2U_LIB.S9S_MB_2U(SCH_1):PAGE170_I12@PURE_QUANTA.74LVC2G08DP(CHIPS)':
 '2A': CDS_PINID='\2a\';
NODE_NAME     J37 A12
 '@S9S_MB_2U_LIB.S9S_MB_2U(SCH_1):PAGE150_I199@PURE_QUANTA.SCONN168_ME1016810202011(CHIPS)':
 'PRSNTB2#': CDS_PINID='\prsntb2#\';
NODE_NAME     U212 1
 '@S9S_MB_2U_LIB.S9S_MB_2U(SCH_1):PAGE153_I23@PURE_QUANTA.74LVC2G07DW7(CHIPS)':
 '1A': CDS_PINID='\1a\';
NODE_NAME     R1906 2
 '@S9S_MB_2U_LIB.S9S_MB_2U(SCH_1):PAGE153_I7@PURE_QUANTA.Q_RES(CHIPS)':
 'B': CDS_PINID='B';
NET_NAME
'OCP_SFF_PRSNT3_R_N'
 '@S9S_MB_2U_LIB.S9S_MB_2U(SCH_1):OCP_SFF_PRSNT3_R_N':
 C_SIGNAL='@s9s_mb_2u_lib.s9s_mb_2u(sch_1):ocp_sff_prsnt3_r_n';
NODE_NAME     U240 6
 '@S9S_MB_2U_LIB.S9S_MB_2U(SCH_1):PAGE170_I12@PURE_QUANTA.74LVC2G08DP(CHIPS)':
 '2B': CDS_PINID='\2b\';
NODE_NAME     J37 B70
 '@S9S_MB_2U_LIB.S9S_MB_2U(SCH_1):PAGE150_I199@PURE_QUANTA.SCONN168_ME1016810202011(CHIPS)':
 'PRSNTB3#': CDS_PINID='\prsntb3#\';
NODE_NAME     R1908 2
 '@S9S_MB_2U_LIB.S9S_MB_2U(SCH_1):PAGE153_I22@PURE_QUANTA.Q_RES(CHIPS)':
 'B': CDS_PINID='B';
NODE_NAME     U212 3
 '@S9S_MB_2U_LIB.S9S_MB_2U(SCH_1):PAGE153_I23@PURE_QUANTA.74LVC2G07DW7(CHIPS)':
 '2A': CDS_PINID='\2a\';
NET_NAME
'OCP_SFF_PRSNTA_R_N'
 '@S9S_MB_2U_LIB.S9S_MB_2U(SCH_1):OCP_SFF_PRSNTA_R_N':
 C_SIGNAL='@s9s_mb_2u_lib.s9s_mb_2u(sch_1):ocp_sff_prsnta_r_n';
NODE_NAME     R1895 1
 '@S9S_MB_2U_LIB.S9S_MB_2U(SCH_1):PAGE150_I149@PURE_QUANTA.Q_RES(CHIPS)':
 'A': CDS_PINID='A';
NODE_NAME     J37 A10
 '@S9S_MB_2U_LIB.S9S_MB_2U(SCH_1):PAGE150_I199@PURE_QUANTA.SCONN168_ME1016810202011(CHIPS)':
 'PRSNTA#': CDS_PINID='\prsnta#\';
NET_NAME
'OCP_SFF_PRSNT_ALL_R1_N'
 '@S9S_MB_2U_LIB.S9S_MB_2U(SCH_1):OCP_SFF_PRSNT_ALL_R1_N':
 C_SIGNAL='@s9s_mb_2u_lib.s9s_mb_2u(sch_1):ocp_sff_prsnt_all_r1_n';
NODE_NAME     U243 6
 '@S9S_MB_2U_LIB.S9S_MB_2U(SCH_1):PAGE170_I15@PURE_QUANTA.NC7SB3157(CHIPS)':
 'S': CDS_PINID='S';
NODE_NAME     R3303 2
 '@S9S_MB_2U_LIB.S9S_MB_2U(SCH_1):PAGE170_I44@PURE_QUANTA.Q_RES(CHIPS)':
 'B': CDS_PINID='B';
NET_NAME
'OCP_SFF_PRSNT_ALL_R3_N'
 '@S9S_MB_2U_LIB.S9S_MB_2U(SCH_1):OCP_SFF_PRSNT_ALL_R3_N':
 C_SIGNAL='@s9s_mb_2u_lib.s9s_mb_2u(sch_1):ocp_sff_prsnt_all_r3_n';
NODE_NAME     U244 6
 '@S9S_MB_2U_LIB.S9S_MB_2U(SCH_1):PAGE170_I16@PURE_QUANTA.NC7SB3157(CHIPS)':
 'S': CDS_PINID='S';
NODE_NAME     R3304 2
 '@S9S_MB_2U_LIB.S9S_MB_2U(SCH_1):PAGE170_I45@PURE_QUANTA.Q_RES(CHIPS)':
 'B': CDS_PINID='B';
NET_NAME
'OCP_SFF_PRSNT_ALL_R_N'
 '@S9S_MB_2U_LIB.S9S_MB_2U(SCH_1):OCP_SFF_PRSNT_ALL_R_N':
 C_SIGNAL='@s9s_mb_2u_lib.s9s_mb_2u(sch_1):ocp_sff_prsnt_all_r_n';
NODE_NAME     U242 7
 '@S9S_MB_2U_LIB.S9S_MB_2U(SCH_1):PAGE170_I13@PURE_QUANTA.74LVC2G08DP(CHIPS)':
 '1Y': CDS_PINID='\1y\';
NODE_NAME     R3303 1
 '@S9S_MB_2U_LIB.S9S_MB_2U(SCH_1):PAGE170_I44@PURE_QUANTA.Q_RES(CHIPS)':
 'A': CDS_PINID='A';
NODE_NAME     R3304 1
 '@S9S_MB_2U_LIB.S9S_MB_2U(SCH_1):PAGE170_I45@PURE_QUANTA.Q_RES(CHIPS)':
 'A': CDS_PINID='A';
NET_NAME
'OCP_SFF_PWRBRK_BUFF_N'
 '@S9S_MB_2U_LIB.S9S_MB_2U(SCH_1):OCP_SFF_PWRBRK_BUFF_N':
 C_SIGNAL='@s9s_mb_2u_lib.s9s_mb_2u(sch_1):ocp_sff_pwrbrk_buff_n';
NODE_NAME     R1595 1
 '@S9S_MB_2U_LIB.S9S_MB_2U(SCH_1):PAGE152_I40@PURE_QUANTA.Q_RES(CHIPS)':
 'A': CDS_PINID='A';
NODE_NAME     R1593 2
 '@S9S_MB_2U_LIB.S9S_MB_2U(SCH_1):PAGE152_I42@PURE_QUANTA.Q_RES(CHIPS)':
 'B': CDS_PINID='B';
NODE_NAME     U104 4
 '@S9S_MB_2U_LIB.S9S_MB_2U(SCH_1):PAGE152_I63@PURE_QUANTA.74LVC1G07GV(CHIPS)':
 'Y': CDS_PINID='Y';
NET_NAME
'OCP_SFF_PWRBRK_N'
 '@S9S_MB_2U_LIB.S9S_MB_2U(SCH_1):OCP_SFF_PWRBRK_N':
 C_SIGNAL='@s9s_mb_2u_lib.s9s_mb_2u(sch_1):ocp_sff_pwrbrk_n';
NODE_NAME     R1595 2
 '@S9S_MB_2U_LIB.S9S_MB_2U(SCH_1):PAGE152_I40@PURE_QUANTA.Q_RES(CHIPS)':
 'B': CDS_PINID='B';
NODE_NAME     J37 A70
 '@S9S_MB_2U_LIB.S9S_MB_2U(SCH_1):PAGE150_I199@PURE_QUANTA.SCONN168_ME1016810202011(CHIPS)':
 'PWRBRK0#': CDS_PINID='\pwrbrk0#\';
NET_NAME
'OCP_SFF_RBT_ARB_IN'
 '@S9S_MB_2U_LIB.S9S_MB_2U(SCH_1):OCP_SFF_RBT_ARB_IN':
 C_SIGNAL='@s9s_mb_2u_lib.s9s_mb_2u(sch_1):ocp_sff_rbt_arb_in';
NODE_NAME     U244 3
 '@S9S_MB_2U_LIB.S9S_MB_2U(SCH_1):PAGE170_I16@PURE_QUANTA.NC7SB3157(CHIPS)':
 'B0': CDS_PINID='B0';
NODE_NAME     R1290 2
 '@S9S_MB_2U_LIB.S9S_MB_2U(SCH_1):PAGE151_I81@PURE_QUANTA.Q_RES(CHIPS)':
 'B': CDS_PINID='B';
NET_NAME
'OCP_SFF_RBT_ARB_IN_MUX1'
 '@S9S_MB_2U_LIB.S9S_MB_2U(SCH_1):OCP_SFF_RBT_ARB_IN_MUX1':
 C_SIGNAL='@s9s_mb_2u_lib.s9s_mb_2u(sch_1):ocp_sff_rbt_arb_in_mux1';
NODE_NAME     U246 4
 '@S9S_MB_2U_LIB.S9S_MB_2U(SCH_1):PAGE170_I17@PURE_QUANTA.NC7SB3157(CHIPS)':
 'A': CDS_PINID='A';
NODE_NAME     R3305 1
 '@S9S_MB_2U_LIB.S9S_MB_2U(SCH_1):PAGE170_I50@PURE_QUANTA.Q_RES(CHIPS)':
 'A': CDS_PINID='A';
NET_NAME
'OCP_SFF_RBT_ARB_IN_MUX1_R'
 '@S9S_MB_2U_LIB.S9S_MB_2U(SCH_1):OCP_SFF_RBT_ARB_IN_MUX1_R':
 C_SIGNAL='@s9s_mb_2u_lib.s9s_mb_2u(sch_1):ocp_sff_rbt_arb_in_mux1_r';
NODE_NAME     U244 4
 '@S9S_MB_2U_LIB.S9S_MB_2U(SCH_1):PAGE170_I16@PURE_QUANTA.NC7SB3157(CHIPS)':
 'A': CDS_PINID='A';
NODE_NAME     R3305 2
 '@S9S_MB_2U_LIB.S9S_MB_2U(SCH_1):PAGE170_I50@PURE_QUANTA.Q_RES(CHIPS)':
 'B': CDS_PINID='B';
NET_NAME
'OCP_SFF_RBT_ARB_IN_MUX2'
 '@S9S_MB_2U_LIB.S9S_MB_2U(SCH_1):OCP_SFF_RBT_ARB_IN_MUX2':
 C_SIGNAL='@s9s_mb_2u_lib.s9s_mb_2u(sch_1):ocp_sff_rbt_arb_in_mux2';
NODE_NAME     U243 4
 '@S9S_MB_2U_LIB.S9S_MB_2U(SCH_1):PAGE170_I15@PURE_QUANTA.NC7SB3157(CHIPS)':
 'A': CDS_PINID='A';
NODE_NAME     R3307 1
 '@S9S_MB_2U_LIB.S9S_MB_2U(SCH_1):PAGE170_I52@PURE_QUANTA.Q_RES(CHIPS)':
 'A': CDS_PINID='A';
NET_NAME
'OCP_SFF_RBT_ARB_IN_MUX2_R'
 '@S9S_MB_2U_LIB.S9S_MB_2U(SCH_1):OCP_SFF_RBT_ARB_IN_MUX2_R':
 C_SIGNAL='@s9s_mb_2u_lib.s9s_mb_2u(sch_1):ocp_sff_rbt_arb_in_mux2_r';
NODE_NAME     U245 4
 '@S9S_MB_2U_LIB.S9S_MB_2U(SCH_1):PAGE170_I18@PURE_QUANTA.NC7SB3157(CHIPS)':
 'A': CDS_PINID='A';
NODE_NAME     R3307 2
 '@S9S_MB_2U_LIB.S9S_MB_2U(SCH_1):PAGE170_I52@PURE_QUANTA.Q_RES(CHIPS)':
 'B': CDS_PINID='B';
NET_NAME
'OCP_SFF_RBT_ARB_IN_R'
 '@S9S_MB_2U_LIB.S9S_MB_2U(SCH_1):OCP_SFF_RBT_ARB_IN_R':
 C_SIGNAL='@s9s_mb_2u_lib.s9s_mb_2u(sch_1):ocp_sff_rbt_arb_in_r';
NODE_NAME     U67 12
 '@S9S_MB_2U_LIB.S9S_MB_2U(SCH_1):PAGE151_I39@PURE_QUANTA.74CBTLV3126PW(CHIPS)':
 '4A': CDS_PINID='\4a\';
NODE_NAME     R3237 2
 '@S9S_MB_2U_LIB.S9S_MB_2U(SCH_1):PAGE151_I80@PURE_QUANTA.Q_RES(CHIPS)':
 'B': CDS_PINID='B';
NODE_NAME     R1290 1
 '@S9S_MB_2U_LIB.S9S_MB_2U(SCH_1):PAGE151_I81@PURE_QUANTA.Q_RES(CHIPS)':
 'A': CDS_PINID='A';
NET_NAME
'OCP_SFF_RBT_ARB_OUT'
 '@S9S_MB_2U_LIB.S9S_MB_2U(SCH_1):OCP_SFF_RBT_ARB_OUT':
 C_SIGNAL='@s9s_mb_2u_lib.s9s_mb_2u(sch_1):ocp_sff_rbt_arb_out';
NODE_NAME     U243 3
 '@S9S_MB_2U_LIB.S9S_MB_2U(SCH_1):PAGE170_I15@PURE_QUANTA.NC7SB3157(CHIPS)':
 'B0': CDS_PINID='B0';
NODE_NAME     U68 12
 '@S9S_MB_2U_LIB.S9S_MB_2U(SCH_1):PAGE151_I30@PURE_QUANTA.74CBTLV3126PW(CHIPS)':
 '4A': CDS_PINID='\4a\';
NODE_NAME     R3237 1
 '@S9S_MB_2U_LIB.S9S_MB_2U(SCH_1):PAGE151_I80@PURE_QUANTA.Q_RES(CHIPS)':
 'A': CDS_PINID='A';
NET_NAME
'OCP_SFF_USB2_3_DN'
 '@S9S_MB_2U_LIB.S9S_MB_2U(SCH_1):OCP_SFF_USB2_3_DN':
 C_SIGNAL='@s9s_mb_2u_lib.s9s_mb_2u(sch_1):ocp_sff_usb2_3_dn';
NODE_NAME     R444 1
 '@S9S_MB_2U_LIB.S9S_MB_2U(SCH_1):PAGE150_I118@PURE_QUANTA.Q_RES(CHIPS)':
 'A': CDS_PINID='A';
NODE_NAME     J37 A68
 '@S9S_MB_2U_LIB.S9S_MB_2U(SCH_1):PAGE150_I199@PURE_QUANTA.SCONN168_ME1016810202011(CHIPS)':
 'USB_DATN': CDS_PINID='USB_DATN';
NET_NAME
'OCP_SFF_USB2_3_DP'
 '@S9S_MB_2U_LIB.S9S_MB_2U(SCH_1):OCP_SFF_USB2_3_DP':
 C_SIGNAL='@s9s_mb_2u_lib.s9s_mb_2u(sch_1):ocp_sff_usb2_3_dp';
NODE_NAME     R445 1
 '@S9S_MB_2U_LIB.S9S_MB_2U(SCH_1):PAGE150_I119@PURE_QUANTA.Q_RES(CHIPS)':
 'A': CDS_PINID='A';
NODE_NAME     J37 A69
 '@S9S_MB_2U_LIB.S9S_MB_2U(SCH_1):PAGE150_I199@PURE_QUANTA.SCONN168_ME1016810202011(CHIPS)':
 'USB_DATP': CDS_PINID='USB_DATP';
NET_NAME
'OCP_SFF_WAKE_BUFF_N'
 '@S9S_MB_2U_LIB.S9S_MB_2U(SCH_1):OCP_SFF_WAKE_BUFF_N':
 C_SIGNAL='@s9s_mb_2u_lib.s9s_mb_2u(sch_1):ocp_sff_wake_buff_n';
NODE_NAME     R1594 1
 '@S9S_MB_2U_LIB.S9S_MB_2U(SCH_1):PAGE152_I26@PURE_QUANTA.Q_RES(CHIPS)':
 'A': CDS_PINID='A';
NODE_NAME     R2488 2
 '@S9S_MB_2U_LIB.S9S_MB_2U(SCH_1):PAGE152_I74@PURE_QUANTA.Q_RES(CHIPS)':
 'B': CDS_PINID='B';
NODE_NAME     U82 4
 '@S9S_MB_2U_LIB.S9S_MB_2U(SCH_1):PAGE152_I79@PURE_QUANTA.74LVC1G126SE7(CHIPS)':
 'Y': CDS_PINID='Y';
NET_NAME
'OCP_SFF_WAKE_BUFF_R_N'
 '@S9S_MB_2U_LIB.S9S_MB_2U(SCH_1):OCP_SFF_WAKE_BUFF_R_N':
 C_SIGNAL='@s9s_mb_2u_lib.s9s_mb_2u(sch_1):ocp_sff_wake_buff_r_n';
NODE_NAME     R1594 2
 '@S9S_MB_2U_LIB.S9S_MB_2U(SCH_1):PAGE152_I26@PURE_QUANTA.Q_RES(CHIPS)':
 'B': CDS_PINID='B';
NODE_NAME     U157 2
 '@S9S_MB_2U_LIB.S9S_MB_2U(SCH_1):PAGE152_I65@PURE_QUANTA.74LVC1G07GV(CHIPS)':
 'A': CDS_PINID='A';
NET_NAME
'OCP_V3_1_P3V3_PWRGD'
 '@S9S_MB_2U_LIB.S9S_MB_2U(SCH_1):OCP_V3_1_P3V3_PWRGD':
 C_SIGNAL='@s9s_mb_2u_lib.s9s_mb_2u(sch_1):ocp_v3_1_p3v3_pwrgd';
NODE_NAME     R3794 2
 '@S9S_MB_2U_LIB.S9S_MB_2U(SCH_1):PAGE153_I105@PURE_QUANTA.Q_RES(CHIPS)':
 'B': CDS_PINID='B';
NODE_NAME     R4613 1
 '@S9S_MB_2U_LIB.S9S_MB_2U(SCH_1):PAGE154_I232@PURE_QUANTA.Q_RES(CHIPS)':
 'A': CDS_PINID='A';
NODE_NAME     R3783 2
 '@S9S_MB_2U_LIB.S9S_MB_2U(SCH_1):PAGE153_I110@PURE_QUANTA.Q_RES(CHIPS)':
 'B': CDS_PINID='B';
NET_NAME
'OCP_V3_1_PRSNTA_R_N'
 '@S9S_MB_2U_LIB.S9S_MB_2U(SCH_1):OCP_V3_1_PRSNTA_R_N':
 C_SIGNAL='@s9s_mb_2u_lib.s9s_mb_2u(sch_1):ocp_v3_1_prsnta_r_n';
NODE_NAME     R3180 1
 '@S9S_MB_2U_LIB.S9S_MB_2U(SCH_1):PAGE146_I152@PURE_QUANTA.Q_RES(CHIPS)':
 'A': CDS_PINID='A';
NODE_NAME     J35 A10
 '@S9S_MB_2U_LIB.S9S_MB_2U(SCH_1):PAGE146_I303@PURE_QUANTA.SCONN168_ME1016810202011(CHIPS)':
 'PRSNTA#': CDS_PINID='\prsnta#\';
NET_NAME
'OCP_V3_2_AUX_PWR_EN'
 '@S9S_MB_2U_LIB.S9S_MB_2U(SCH_1):OCP_V3_2_AUX_PWR_EN':
 C_SIGNAL='@s9s_mb_2u_lib.s9s_mb_2u(sch_1):ocp_v3_2_aux_pwr_en';
NODE_NAME     R3172 1
 '@S9S_MB_2U_LIB.S9S_MB_2U(SCH_1):PAGE146_I36@PURE_QUANTA.Q_RES(CHIPS)':
 'A': CDS_PINID='A';
NODE_NAME     R3164 2
 '@S9S_MB_2U_LIB.S9S_MB_2U(SCH_1):PAGE146_I38@PURE_QUANTA.Q_RES(CHIPS)':
 'B': CDS_PINID='B';
NODE_NAME     R3203 1
 '@S9S_MB_2U_LIB.S9S_MB_2U(SCH_1):PAGE307_I81@PURE_QUANTA.Q_RES(CHIPS)':
 'A': CDS_PINID='A';
NODE_NAME     R3234 1
 '@S9S_MB_2U_LIB.S9S_MB_2U(SCH_1):PAGE156_I75@PURE_QUANTA.Q_RES(CHIPS)':
 'A': CDS_PINID='A';
NODE_NAME     R4759 2
 '@S9S_MB_2U_LIB.S9S_MB_2U(SCH_1):PAGE132_I111@PURE_QUANTA.Q_RES(CHIPS)':
 'B': CDS_PINID='B';
NET_NAME
'OCP_V3_2_AUX_PWR_EN_R'
 '@S9S_MB_2U_LIB.S9S_MB_2U(SCH_1):OCP_V3_2_AUX_PWR_EN_R':
 C_SIGNAL='@s9s_mb_2u_lib.s9s_mb_2u(sch_1):ocp_v3_2_aux_pwr_en_r';
NODE_NAME     R3172 2
 '@S9S_MB_2U_LIB.S9S_MB_2U(SCH_1):PAGE146_I36@PURE_QUANTA.Q_RES(CHIPS)':
 'B': CDS_PINID='B';
NODE_NAME     J35 B12
 '@S9S_MB_2U_LIB.S9S_MB_2U(SCH_1):PAGE146_I303@PURE_QUANTA.SCONN168_ME1016810202011(CHIPS)':
 'AUX_PWR_EN': CDS_PINID='AUX_PWR_EN';
NET_NAME
'OCP_V3_2_AUX_PWR_EN_R1'
 '@S9S_MB_2U_LIB.S9S_MB_2U(SCH_1):OCP_V3_2_AUX_PWR_EN_R1':
 C_SIGNAL='@s9s_mb_2u_lib.s9s_mb_2u(sch_1):ocp_v3_2_aux_pwr_en_r1';
NODE_NAME     U286 1
 '@S9S_MB_2U_LIB.S9S_MB_2U(SCH_1):PAGE307_I80@PURE_QUANTA.74LVC1G126SE7(CHIPS)':
 'OE': CDS_PINID='OE';
NODE_NAME     R3203 2
 '@S9S_MB_2U_LIB.S9S_MB_2U(SCH_1):PAGE307_I81@PURE_QUANTA.Q_RES(CHIPS)':
 'B': CDS_PINID='B';
NET_NAME
'OCP_V3_2_AUX_PWR_EN_R2'
 '@S9S_MB_2U_LIB.S9S_MB_2U(SCH_1):OCP_V3_2_AUX_PWR_EN_R2':
 C_SIGNAL='@s9s_mb_2u_lib.s9s_mb_2u(sch_1):ocp_v3_2_aux_pwr_en_r2';
NODE_NAME     R4758 2
 '@S9S_MB_2U_LIB.S9S_MB_2U(SCH_1):PAGE132_I107@PURE_QUANTA.Q_RES(CHIPS)':
 'B': CDS_PINID='B';
NODE_NAME     U335 4
 '@S9S_MB_2U_LIB.S9S_MB_2U(SCH_1):PAGE132_I108@PURE_QUANTA.74LVC1G08W57(CHIPS)':
 'Y': CDS_PINID='Y';
NODE_NAME     R4759 1
 '@S9S_MB_2U_LIB.S9S_MB_2U(SCH_1):PAGE132_I111@PURE_QUANTA.Q_RES(CHIPS)':
 'A': CDS_PINID='A';
NODE_NAME     R4757 2
 '@S9S_MB_2U_LIB.S9S_MB_2U(SCH_1):PAGE132_I112@PURE_QUANTA.Q_RES(CHIPS)':
 'B': CDS_PINID='B';
NET_NAME
'OCP_V3_2_AUX_PWR_EN_R3'
 '@S9S_MB_2U_LIB.S9S_MB_2U(SCH_1):OCP_V3_2_AUX_PWR_EN_R3':
 C_SIGNAL='@s9s_mb_2u_lib.s9s_mb_2u(sch_1):ocp_v3_2_aux_pwr_en_r3';
NODE_NAME     U225 1
 '@S9S_MB_2U_LIB.S9S_MB_2U(SCH_1):PAGE156_I74@PURE_QUANTA.74LVC1G126SE7(CHIPS)':
 'OE': CDS_PINID='OE';
NODE_NAME     R3234 2
 '@S9S_MB_2U_LIB.S9S_MB_2U(SCH_1):PAGE156_I75@PURE_QUANTA.Q_RES(CHIPS)':
 'B': CDS_PINID='B';
NET_NAME
'OCP_V3_2_AUX_PWR_PLD_EN'
 '@S9S_MB_2U_LIB.S9S_MB_2U(SCH_1):OCP_V3_2_AUX_PWR_PLD_EN':
 C_SIGNAL='@s9s_mb_2u_lib.s9s_mb_2u(sch_1):ocp_v3_2_aux_pwr_pld_en';
NODE_NAME     U249 D6
 '@S9S_MB_2U_LIB.S9S_MB_2U(SCH_1):PAGE314_I188@PURE_QUANTA.LCMXO3LF9400C5BG484C(CHIPS)':
 'PT13C': CDS_PINID='PT13C';
NODE_NAME     R4755 1
 '@S9S_MB_2U_LIB.S9S_MB_2U(SCH_1):PAGE132_I103@PURE_QUANTA.Q_RES(CHIPS)':
 'A': CDS_PINID='A';
NET_NAME
'OCP_V3_2_AUX_PWR_PLD_EN_R'
 '@S9S_MB_2U_LIB.S9S_MB_2U(SCH_1):OCP_V3_2_AUX_PWR_PLD_EN_R':
 C_SIGNAL='@s9s_mb_2u_lib.s9s_mb_2u(sch_1):ocp_v3_2_aux_pwr_pld_en_r';
NODE_NAME     R4755 2
 '@S9S_MB_2U_LIB.S9S_MB_2U(SCH_1):PAGE132_I103@PURE_QUANTA.Q_RES(CHIPS)':
 'B': CDS_PINID='B';
NODE_NAME     R4756 2
 '@S9S_MB_2U_LIB.S9S_MB_2U(SCH_1):PAGE132_I105@PURE_QUANTA.Q_RES(CHIPS)':
 'B': CDS_PINID='B';
NODE_NAME     R4758 1
 '@S9S_MB_2U_LIB.S9S_MB_2U(SCH_1):PAGE132_I107@PURE_QUANTA.Q_RES(CHIPS)':
 'A': CDS_PINID='A';
NODE_NAME     U335 2
 '@S9S_MB_2U_LIB.S9S_MB_2U(SCH_1):PAGE132_I108@PURE_QUANTA.74LVC1G08W57(CHIPS)':
 'B': CDS_PINID='B';
NET_NAME
'OCP_V3_2_BIF0_R_N'
 '@S9S_MB_2U_LIB.S9S_MB_2U(SCH_1):OCP_V3_2_BIF0_R_N':
 C_SIGNAL='@s9s_mb_2u_lib.s9s_mb_2u(sch_1):ocp_v3_2_bif0_r_n';
NODE_NAME     R3169 2
 '@S9S_MB_2U_LIB.S9S_MB_2U(SCH_1):PAGE146_I33@PURE_QUANTA.Q_RES(CHIPS)':
 'B': CDS_PINID='B';
NODE_NAME     J35 B7
 '@S9S_MB_2U_LIB.S9S_MB_2U(SCH_1):PAGE146_I303@PURE_QUANTA.SCONN168_ME1016810202011(CHIPS)':
 'BIF0#': CDS_PINID='\bif0#\';
NET_NAME
'OCP_V3_2_BIF1_R_N'
 '@S9S_MB_2U_LIB.S9S_MB_2U(SCH_1):OCP_V3_2_BIF1_R_N':
 C_SIGNAL='@s9s_mb_2u_lib.s9s_mb_2u(sch_1):ocp_v3_2_bif1_r_n';
NODE_NAME     R3170 2
 '@S9S_MB_2U_LIB.S9S_MB_2U(SCH_1):PAGE146_I32@PURE_QUANTA.Q_RES(CHIPS)':
 'B': CDS_PINID='B';
NODE_NAME     J35 B8
 '@S9S_MB_2U_LIB.S9S_MB_2U(SCH_1):PAGE146_I303@PURE_QUANTA.SCONN168_ME1016810202011(CHIPS)':
 'BIF1#': CDS_PINID='\bif1#\';
NET_NAME
'OCP_V3_2_BIF2_R_N'
 '@S9S_MB_2U_LIB.S9S_MB_2U(SCH_1):OCP_V3_2_BIF2_R_N':
 C_SIGNAL='@s9s_mb_2u_lib.s9s_mb_2u(sch_1):ocp_v3_2_bif2_r_n';
NODE_NAME     R3171 2
 '@S9S_MB_2U_LIB.S9S_MB_2U(SCH_1):PAGE146_I31@PURE_QUANTA.Q_RES(CHIPS)':
 'B': CDS_PINID='B';
NODE_NAME     J35 B9
 '@S9S_MB_2U_LIB.S9S_MB_2U(SCH_1):PAGE146_I303@PURE_QUANTA.SCONN168_ME1016810202011(CHIPS)':
 'BIF2#': CDS_PINID='\bif2#\';
NET_NAME
'OCP_V3_2_ID0'
 '@S9S_MB_2U_LIB.S9S_MB_2U(SCH_1):OCP_V3_2_ID0':
 C_SIGNAL='@s9s_mb_2u_lib.s9s_mb_2u(sch_1):ocp_v3_2_id0';
NODE_NAME     R3163 1
 '@S9S_MB_2U_LIB.S9S_MB_2U(SCH_1):PAGE146_I25@PURE_QUANTA.Q_RES(CHIPS)':
 'A': CDS_PINID='A';
NODE_NAME     R3162 2
 '@S9S_MB_2U_LIB.S9S_MB_2U(SCH_1):PAGE146_I26@PURE_QUANTA.Q_RES(CHIPS)':
 'B': CDS_PINID='B';
NODE_NAME     J35 OB7
 '@S9S_MB_2U_LIB.S9S_MB_2U(SCH_1):PAGE146_I303@PURE_QUANTA.SCONN168_ME1016810202011(CHIPS)':
 'SLOT_ID0': CDS_PINID='SLOT_ID0';
NET_NAME
'OCP_V3_2_ID1'
 '@S9S_MB_2U_LIB.S9S_MB_2U(SCH_1):OCP_V3_2_ID1':
 C_SIGNAL='@s9s_mb_2u_lib.s9s_mb_2u(sch_1):ocp_v3_2_id1';
NODE_NAME     R3167 1
 '@S9S_MB_2U_LIB.S9S_MB_2U(SCH_1):PAGE146_I20@PURE_QUANTA.Q_RES(CHIPS)':
 'A': CDS_PINID='A';
NODE_NAME     R3166 2
 '@S9S_MB_2U_LIB.S9S_MB_2U(SCH_1):PAGE146_I23@PURE_QUANTA.Q_RES(CHIPS)':
 'B': CDS_PINID='B';
NODE_NAME     J35 OA6
 '@S9S_MB_2U_LIB.S9S_MB_2U(SCH_1):PAGE146_I303@PURE_QUANTA.SCONN168_ME1016810202011(CHIPS)':
 'SLOT_ID1': CDS_PINID='SLOT_ID1';
NET_NAME
'OCP_V3_2_ISO1_RBT_ARB_IN'
 '@S9S_MB_2U_LIB.S9S_MB_2U(SCH_1):OCP_V3_2_ISO1_RBT_ARB_IN':
 C_SIGNAL='@s9s_mb_2u_lib.s9s_mb_2u(sch_1):ocp_v3_2_iso1_rbt_arb_in';
NODE_NAME     U222 11
 '@S9S_MB_2U_LIB.S9S_MB_2U(SCH_1):PAGE307_I32@PURE_QUANTA.74CBTLV3126PW(CHIPS)':
 '4B': CDS_PINID='\4b\';
NODE_NAME     J35 OA4
 '@S9S_MB_2U_LIB.S9S_MB_2U(SCH_1):PAGE146_I303@PURE_QUANTA.SCONN168_ME1016810202011(CHIPS)':
 'RBT_ARB_IN': CDS_PINID='RBT_ARB_IN';
NET_NAME
'OCP_V3_2_ISO2_RBT_ARB_OUT'
 '@S9S_MB_2U_LIB.S9S_MB_2U(SCH_1):OCP_V3_2_ISO2_RBT_ARB_OUT':
 C_SIGNAL='@s9s_mb_2u_lib.s9s_mb_2u(sch_1):ocp_v3_2_iso2_rbt_arb_out';
NODE_NAME     U223 11
 '@S9S_MB_2U_LIB.S9S_MB_2U(SCH_1):PAGE307_I78@PURE_QUANTA.74CBTLV3126PW(CHIPS)':
 '4B': CDS_PINID='\4b\';
NODE_NAME     J35 OA5
 '@S9S_MB_2U_LIB.S9S_MB_2U(SCH_1):PAGE146_I303@PURE_QUANTA.SCONN168_ME1016810202011(CHIPS)':
 'RBT_ARB_OUT': CDS_PINID='RBT_ARB_OUT';
NET_NAME
'OCP_V3_2_ISO_BIF0_EN'
 '@S9S_MB_2U_LIB.S9S_MB_2U(SCH_1):OCP_V3_2_ISO_BIF0_EN':
 C_SIGNAL='@s9s_mb_2u_lib.s9s_mb_2u(sch_1):ocp_v3_2_iso_bif0_en';
NODE_NAME     R3169 1
 '@S9S_MB_2U_LIB.S9S_MB_2U(SCH_1):PAGE146_I33@PURE_QUANTA.Q_RES(CHIPS)':
 'A': CDS_PINID='A';
NODE_NAME     R3208 1
 '@S9S_MB_2U_LIB.S9S_MB_2U(SCH_1):PAGE307_I37@PURE_QUANTA.Q_RES(CHIPS)':
 'A': CDS_PINID='A';
NET_NAME
'OCP_V3_2_ISO_BIF1_EN'
 '@S9S_MB_2U_LIB.S9S_MB_2U(SCH_1):OCP_V3_2_ISO_BIF1_EN':
 C_SIGNAL='@s9s_mb_2u_lib.s9s_mb_2u(sch_1):ocp_v3_2_iso_bif1_en';
NODE_NAME     R3170 1
 '@S9S_MB_2U_LIB.S9S_MB_2U(SCH_1):PAGE146_I32@PURE_QUANTA.Q_RES(CHIPS)':
 'A': CDS_PINID='A';
NODE_NAME     R3216 1
 '@S9S_MB_2U_LIB.S9S_MB_2U(SCH_1):PAGE307_I38@PURE_QUANTA.Q_RES(CHIPS)':
 'A': CDS_PINID='A';
NET_NAME
'OCP_V3_2_ISO_BIF2_EN'
 '@S9S_MB_2U_LIB.S9S_MB_2U(SCH_1):OCP_V3_2_ISO_BIF2_EN':
 C_SIGNAL='@s9s_mb_2u_lib.s9s_mb_2u(sch_1):ocp_v3_2_iso_bif2_en';
NODE_NAME     R3171 1
 '@S9S_MB_2U_LIB.S9S_MB_2U(SCH_1):PAGE146_I31@PURE_QUANTA.Q_RES(CHIPS)':
 'A': CDS_PINID='A';
NODE_NAME     R3217 1
 '@S9S_MB_2U_LIB.S9S_MB_2U(SCH_1):PAGE307_I40@PURE_QUANTA.Q_RES(CHIPS)':
 'A': CDS_PINID='A';
NET_NAME
'OCP_V3_2_MAIN_PWR_EN'
 '@S9S_MB_2U_LIB.S9S_MB_2U(SCH_1):OCP_V3_2_MAIN_PWR_EN':
 C_SIGNAL='@s9s_mb_2u_lib.s9s_mb_2u(sch_1):ocp_v3_2_main_pwr_en';
NODE_NAME     R3168 1
 '@S9S_MB_2U_LIB.S9S_MB_2U(SCH_1):PAGE146_I5@PURE_QUANTA.Q_RES(CHIPS)':
 'A': CDS_PINID='A';
NODE_NAME     R3165 2
 '@S9S_MB_2U_LIB.S9S_MB_2U(SCH_1):PAGE146_I37@PURE_QUANTA.Q_RES(CHIPS)':
 'B': CDS_PINID='B';
NODE_NAME     U249 T17
 '@S9S_MB_2U_LIB.S9S_MB_2U(SCH_1):PAGE313_I1@PURE_QUANTA.LCMXO3LF9400C5BG484C(CHIPS)':
 'PR27C': CDS_PINID='PR27C';
NET_NAME
'OCP_V3_2_MAIN_PWR_EN_R'
 '@S9S_MB_2U_LIB.S9S_MB_2U(SCH_1):OCP_V3_2_MAIN_PWR_EN_R':
 C_SIGNAL='@s9s_mb_2u_lib.s9s_mb_2u(sch_1):ocp_v3_2_main_pwr_en_r';
NODE_NAME     R3168 2
 '@S9S_MB_2U_LIB.S9S_MB_2U(SCH_1):PAGE146_I5@PURE_QUANTA.Q_RES(CHIPS)':
 'B': CDS_PINID='B';
NODE_NAME     J35 OB2
 '@S9S_MB_2U_LIB.S9S_MB_2U(SCH_1):PAGE146_I303@PURE_QUANTA.SCONN168_ME1016810202011(CHIPS)':
 'MAIN_PWR_EN': CDS_PINID='MAIN_PWR_EN';
NET_NAME
'OCP_V3_2_NOT_PRSNT_RBT_ARB_IN'
 '@S9S_MB_2U_LIB.S9S_MB_2U(SCH_1):OCP_V3_2_NOT_PRSNT_RBT_ARB_IN':
 C_SIGNAL='@s9s_mb_2u_lib.s9s_mb_2u(sch_1):ocp_v3_2_not_prsnt_rbt_arb_in';
NODE_NAME     U246 1
 '@S9S_MB_2U_LIB.S9S_MB_2U(SCH_1):PAGE170_I17@PURE_QUANTA.NC7SB3157(CHIPS)':
 'B1': CDS_PINID='B1';
NODE_NAME     U245 1
 '@S9S_MB_2U_LIB.S9S_MB_2U(SCH_1):PAGE170_I18@PURE_QUANTA.NC7SB3157(CHIPS)':
 'B1': CDS_PINID='B1';
NET_NAME
'OCP_V3_2_P3V3_ADC_ALERT'
 '@S9S_MB_2U_LIB.S9S_MB_2U(SCH_1):OCP_V3_2_P3V3_ADC_ALERT':
 C_SIGNAL='@s9s_mb_2u_lib.s9s_mb_2u(sch_1):ocp_v3_2_p3v3_adc_alert';
NODE_NAME     U249 K18
 '@S9S_MB_2U_LIB.S9S_MB_2U(SCH_1):PAGE313_I1@PURE_QUANTA.LCMXO3LF9400C5BG484C(CHIPS)':
 'PR13B': CDS_PINID='PR13B';
NODE_NAME     R3559 2
 '@S9S_MB_2U_LIB.S9S_MB_2U(SCH_1):PAGE163_I96@PURE_QUANTA.Q_RES(CHIPS)':
 'B': CDS_PINID='B';
NET_NAME
'OCP_V3_2_P3V3_ADC_ALERT_R'
 '@S9S_MB_2U_LIB.S9S_MB_2U(SCH_1):OCP_V3_2_P3V3_ADC_ALERT_R':
 C_SIGNAL='@s9s_mb_2u_lib.s9s_mb_2u(sch_1):ocp_v3_2_p3v3_adc_alert_r';
NODE_NAME     U263 3
 '@S9S_MB_2U_LIB.S9S_MB_2U(SCH_1):PAGE163_I94@PURE_QUANTA.INA230AIRGTR(CHIPS)':
 'ALERT': CDS_PINID='ALERT';
NODE_NAME     R3559 1
 '@S9S_MB_2U_LIB.S9S_MB_2U(SCH_1):PAGE163_I96@PURE_QUANTA.Q_RES(CHIPS)':
 'A': CDS_PINID='A';
NODE_NAME     R4092 2
 '@S9S_MB_2U_LIB.S9S_MB_2U(SCH_1):PAGE163_I126@PURE_QUANTA.Q_RES(CHIPS)':
 'B': CDS_PINID='B';
NET_NAME
'OCP_V3_2_P3V3_PWRGD'
 '@S9S_MB_2U_LIB.S9S_MB_2U(SCH_1):OCP_V3_2_P3V3_PWRGD':
 C_SIGNAL='@s9s_mb_2u_lib.s9s_mb_2u(sch_1):ocp_v3_2_p3v3_pwrgd';
NODE_NAME     R3832 2
 '@S9S_MB_2U_LIB.S9S_MB_2U(SCH_1):PAGE131_I97@PURE_QUANTA.Q_RES(CHIPS)':
 'B': CDS_PINID='B';
NODE_NAME     R4615 1
 '@S9S_MB_2U_LIB.S9S_MB_2U(SCH_1):PAGE132_I96@PURE_QUANTA.Q_RES(CHIPS)':
 'A': CDS_PINID='A';
NODE_NAME     R3826 2
 '@S9S_MB_2U_LIB.S9S_MB_2U(SCH_1):PAGE131_I110@PURE_QUANTA.Q_RES(CHIPS)':
 'B': CDS_PINID='B';
NET_NAME
'OCP_V3_2_PRSNT01_R_N'
 '@S9S_MB_2U_LIB.S9S_MB_2U(SCH_1):OCP_V3_2_PRSNT01_R_N':
 C_SIGNAL='@s9s_mb_2u_lib.s9s_mb_2u(sch_1):ocp_v3_2_prsnt01_r_n';
NODE_NAME     U241 7
 '@S9S_MB_2U_LIB.S9S_MB_2U(SCH_1):PAGE170_I1@PURE_QUANTA.74LVC2G08DP(CHIPS)':
 '1Y': CDS_PINID='\1y\';
NODE_NAME     U242 5
 '@S9S_MB_2U_LIB.S9S_MB_2U(SCH_1):PAGE170_I14@PURE_QUANTA.74LVC2G08DP(CHIPS)':
 '2A': CDS_PINID='\2a\';
NET_NAME
'OCP_V3_2_PRSNT0_R_N'
 '@S9S_MB_2U_LIB.S9S_MB_2U(SCH_1):OCP_V3_2_PRSNT0_R_N':
 C_SIGNAL='@s9s_mb_2u_lib.s9s_mb_2u(sch_1):ocp_v3_2_prsnt0_r_n';
NODE_NAME     U241 1
 '@S9S_MB_2U_LIB.S9S_MB_2U(SCH_1):PAGE170_I1@PURE_QUANTA.74LVC2G08DP(CHIPS)':
 '1A': CDS_PINID='\1a\';
NODE_NAME     J35 B42
 '@S9S_MB_2U_LIB.S9S_MB_2U(SCH_1):PAGE146_I303@PURE_QUANTA.SCONN168_ME1016810202011(CHIPS)':
 'PRSNTB0#': CDS_PINID='\prsntb0#\';
NODE_NAME     R3133 2
 '@S9S_MB_2U_LIB.S9S_MB_2U(SCH_1):PAGE131_I11@PURE_QUANTA.Q_RES(CHIPS)':
 'B': CDS_PINID='B';
NODE_NAME     U58 1
 '@S9S_MB_2U_LIB.S9S_MB_2U(SCH_1):PAGE131_I25@PURE_QUANTA.74LVC2G07DW7(CHIPS)':
 '1A': CDS_PINID='\1a\';
NET_NAME
'OCP_V3_2_PRSNT1_R_N'
 '@S9S_MB_2U_LIB.S9S_MB_2U(SCH_1):OCP_V3_2_PRSNT1_R_N':
 C_SIGNAL='@s9s_mb_2u_lib.s9s_mb_2u(sch_1):ocp_v3_2_prsnt1_r_n';
NODE_NAME     U241 2
 '@S9S_MB_2U_LIB.S9S_MB_2U(SCH_1):PAGE170_I1@PURE_QUANTA.74LVC2G08DP(CHIPS)':
 '1B': CDS_PINID='\1b\';
NODE_NAME     J35 A42
 '@S9S_MB_2U_LIB.S9S_MB_2U(SCH_1):PAGE146_I303@PURE_QUANTA.SCONN168_ME1016810202011(CHIPS)':
 'PRSNTB1#': CDS_PINID='\prsntb1#\';
NODE_NAME     R3135 2
 '@S9S_MB_2U_LIB.S9S_MB_2U(SCH_1):PAGE131_I13@PURE_QUANTA.Q_RES(CHIPS)':
 'B': CDS_PINID='B';
NODE_NAME     U58 3
 '@S9S_MB_2U_LIB.S9S_MB_2U(SCH_1):PAGE131_I25@PURE_QUANTA.74LVC2G07DW7(CHIPS)':
 '2A': CDS_PINID='\2a\';
NET_NAME
'OCP_V3_2_PRSNT23_R_N'
 '@S9S_MB_2U_LIB.S9S_MB_2U(SCH_1):OCP_V3_2_PRSNT23_R_N':
 C_SIGNAL='@s9s_mb_2u_lib.s9s_mb_2u(sch_1):ocp_v3_2_prsnt23_r_n';
NODE_NAME     U241 3
 '@S9S_MB_2U_LIB.S9S_MB_2U(SCH_1):PAGE170_I2@PURE_QUANTA.74LVC2G08DP(CHIPS)':
 '2Y': CDS_PINID='\2y\';
NODE_NAME     U242 6
 '@S9S_MB_2U_LIB.S9S_MB_2U(SCH_1):PAGE170_I14@PURE_QUANTA.74LVC2G08DP(CHIPS)':
 '2B': CDS_PINID='\2b\';
NET_NAME
'OCP_V3_2_PRSNT2_R_N'
 '@S9S_MB_2U_LIB.S9S_MB_2U(SCH_1):OCP_V3_2_PRSNT2_R_N':
 C_SIGNAL='@s9s_mb_2u_lib.s9s_mb_2u(sch_1):ocp_v3_2_prsnt2_r_n';
NODE_NAME     U241 5
 '@S9S_MB_2U_LIB.S9S_MB_2U(SCH_1):PAGE170_I2@PURE_QUANTA.74LVC2G08DP(CHIPS)':
 '2A': CDS_PINID='\2a\';
NODE_NAME     J35 A12
 '@S9S_MB_2U_LIB.S9S_MB_2U(SCH_1):PAGE146_I303@PURE_QUANTA.SCONN168_ME1016810202011(CHIPS)':
 'PRSNTB2#': CDS_PINID='\prsntb2#\';
NODE_NAME     R3134 2
 '@S9S_MB_2U_LIB.S9S_MB_2U(SCH_1):PAGE131_I3@PURE_QUANTA.Q_RES(CHIPS)':
 'B': CDS_PINID='B';
NODE_NAME     U59 1
 '@S9S_MB_2U_LIB.S9S_MB_2U(SCH_1):PAGE131_I19@PURE_QUANTA.74LVC2G07DW7(CHIPS)':
 '1A': CDS_PINID='\1a\';
NET_NAME
'OCP_V3_2_PRSNT3_R_N'
 '@S9S_MB_2U_LIB.S9S_MB_2U(SCH_1):OCP_V3_2_PRSNT3_R_N':
 C_SIGNAL='@s9s_mb_2u_lib.s9s_mb_2u(sch_1):ocp_v3_2_prsnt3_r_n';
NODE_NAME     U241 6
 '@S9S_MB_2U_LIB.S9S_MB_2U(SCH_1):PAGE170_I2@PURE_QUANTA.74LVC2G08DP(CHIPS)':
 '2B': CDS_PINID='\2b\';
NODE_NAME     J35 B70
 '@S9S_MB_2U_LIB.S9S_MB_2U(SCH_1):PAGE146_I303@PURE_QUANTA.SCONN168_ME1016810202011(CHIPS)':
 'PRSNTB3#': CDS_PINID='\prsntb3#\';
NODE_NAME     R3136 2
 '@S9S_MB_2U_LIB.S9S_MB_2U(SCH_1):PAGE131_I5@PURE_QUANTA.Q_RES(CHIPS)':
 'B': CDS_PINID='B';
NODE_NAME     U59 3
 '@S9S_MB_2U_LIB.S9S_MB_2U(SCH_1):PAGE131_I19@PURE_QUANTA.74LVC2G07DW7(CHIPS)':
 '2A': CDS_PINID='\2a\';
NET_NAME
'OCP_V3_2_PRSNT_ALL_R1_N'
 '@S9S_MB_2U_LIB.S9S_MB_2U(SCH_1):OCP_V3_2_PRSNT_ALL_R1_N':
 C_SIGNAL='@s9s_mb_2u_lib.s9s_mb_2u(sch_1):ocp_v3_2_prsnt_all_r1_n';
NODE_NAME     U246 6
 '@S9S_MB_2U_LIB.S9S_MB_2U(SCH_1):PAGE170_I17@PURE_QUANTA.NC7SB3157(CHIPS)':
 'S': CDS_PINID='S';
NODE_NAME     R3308 2
 '@S9S_MB_2U_LIB.S9S_MB_2U(SCH_1):PAGE170_I46@PURE_QUANTA.Q_RES(CHIPS)':
 'B': CDS_PINID='B';
NET_NAME
'OCP_V3_2_PRSNT_ALL_R3_N'
 '@S9S_MB_2U_LIB.S9S_MB_2U(SCH_1):OCP_V3_2_PRSNT_ALL_R3_N':
 C_SIGNAL='@s9s_mb_2u_lib.s9s_mb_2u(sch_1):ocp_v3_2_prsnt_all_r3_n';
NODE_NAME     U245 6
 '@S9S_MB_2U_LIB.S9S_MB_2U(SCH_1):PAGE170_I18@PURE_QUANTA.NC7SB3157(CHIPS)':
 'S': CDS_PINID='S';
NODE_NAME     R3306 2
 '@S9S_MB_2U_LIB.S9S_MB_2U(SCH_1):PAGE170_I47@PURE_QUANTA.Q_RES(CHIPS)':
 'B': CDS_PINID='B';
NET_NAME
'OCP_V3_2_PRSNT_ALL_R_N'
 '@S9S_MB_2U_LIB.S9S_MB_2U(SCH_1):OCP_V3_2_PRSNT_ALL_R_N':
 C_SIGNAL='@s9s_mb_2u_lib.s9s_mb_2u(sch_1):ocp_v3_2_prsnt_all_r_n';
NODE_NAME     U242 3
 '@S9S_MB_2U_LIB.S9S_MB_2U(SCH_1):PAGE170_I14@PURE_QUANTA.74LVC2G08DP(CHIPS)':
 '2Y': CDS_PINID='\2y\';
NODE_NAME     R3308 1
 '@S9S_MB_2U_LIB.S9S_MB_2U(SCH_1):PAGE170_I46@PURE_QUANTA.Q_RES(CHIPS)':
 'A': CDS_PINID='A';
NODE_NAME     R3306 1
 '@S9S_MB_2U_LIB.S9S_MB_2U(SCH_1):PAGE170_I47@PURE_QUANTA.Q_RES(CHIPS)':
 'A': CDS_PINID='A';
NET_NAME
'OCP_V3_2_PWRBRK_BUFF_N'
 '@S9S_MB_2U_LIB.S9S_MB_2U(SCH_1):OCP_V3_2_PWRBRK_BUFF_N':
 C_SIGNAL='@s9s_mb_2u_lib.s9s_mb_2u(sch_1):ocp_v3_2_pwrbrk_buff_n';
NODE_NAME     U218 4
 '@S9S_MB_2U_LIB.S9S_MB_2U(SCH_1):PAGE156_I31@PURE_QUANTA.74LVC1G07GV(CHIPS)':
 'Y': CDS_PINID='Y';
NODE_NAME     R3190 2
 '@S9S_MB_2U_LIB.S9S_MB_2U(SCH_1):PAGE156_I42@PURE_QUANTA.Q_RES(CHIPS)':
 'B': CDS_PINID='B';
NODE_NAME     R3191 1
 '@S9S_MB_2U_LIB.S9S_MB_2U(SCH_1):PAGE156_I44@PURE_QUANTA.Q_RES(CHIPS)':
 'A': CDS_PINID='A';
NET_NAME
'OCP_V3_2_PWRBRK_N'
 '@S9S_MB_2U_LIB.S9S_MB_2U(SCH_1):OCP_V3_2_PWRBRK_N':
 C_SIGNAL='@s9s_mb_2u_lib.s9s_mb_2u(sch_1):ocp_v3_2_pwrbrk_n';
NODE_NAME     R3191 2
 '@S9S_MB_2U_LIB.S9S_MB_2U(SCH_1):PAGE156_I44@PURE_QUANTA.Q_RES(CHIPS)':
 'B': CDS_PINID='B';
NODE_NAME     J35 A70
 '@S9S_MB_2U_LIB.S9S_MB_2U(SCH_1):PAGE146_I303@PURE_QUANTA.SCONN168_ME1016810202011(CHIPS)':
 'PWRBRK0#': CDS_PINID='\pwrbrk0#\';
NET_NAME
'OCP_V3_2_RBT_ARB_IN'
 '@S9S_MB_2U_LIB.S9S_MB_2U(SCH_1):OCP_V3_2_RBT_ARB_IN':
 C_SIGNAL='@s9s_mb_2u_lib.s9s_mb_2u(sch_1):ocp_v3_2_rbt_arb_in';
NODE_NAME     R3209 2
 '@S9S_MB_2U_LIB.S9S_MB_2U(SCH_1):PAGE307_I64@PURE_QUANTA.Q_RES(CHIPS)':
 'B': CDS_PINID='B';
NODE_NAME     U245 3
 '@S9S_MB_2U_LIB.S9S_MB_2U(SCH_1):PAGE170_I18@PURE_QUANTA.NC7SB3157(CHIPS)':
 'B0': CDS_PINID='B0';
NET_NAME
'OCP_V3_2_RBT_ARB_IN_R'
 '@S9S_MB_2U_LIB.S9S_MB_2U(SCH_1):OCP_V3_2_RBT_ARB_IN_R':
 C_SIGNAL='@s9s_mb_2u_lib.s9s_mb_2u(sch_1):ocp_v3_2_rbt_arb_in_r';
NODE_NAME     U222 12
 '@S9S_MB_2U_LIB.S9S_MB_2U(SCH_1):PAGE307_I32@PURE_QUANTA.74CBTLV3126PW(CHIPS)':
 '4A': CDS_PINID='\4a\';
NODE_NAME     R3209 1
 '@S9S_MB_2U_LIB.S9S_MB_2U(SCH_1):PAGE307_I64@PURE_QUANTA.Q_RES(CHIPS)':
 'A': CDS_PINID='A';
NODE_NAME     R3244 2
 '@S9S_MB_2U_LIB.S9S_MB_2U(SCH_1):PAGE307_I79@PURE_QUANTA.Q_RES(CHIPS)':
 'B': CDS_PINID='B';
NET_NAME
'OCP_V3_2_RBT_ARB_OUT'
 '@S9S_MB_2U_LIB.S9S_MB_2U(SCH_1):OCP_V3_2_RBT_ARB_OUT':
 C_SIGNAL='@s9s_mb_2u_lib.s9s_mb_2u(sch_1):ocp_v3_2_rbt_arb_out';
NODE_NAME     U223 12
 '@S9S_MB_2U_LIB.S9S_MB_2U(SCH_1):PAGE307_I78@PURE_QUANTA.74CBTLV3126PW(CHIPS)':
 '4A': CDS_PINID='\4a\';
NODE_NAME     R3244 1
 '@S9S_MB_2U_LIB.S9S_MB_2U(SCH_1):PAGE307_I79@PURE_QUANTA.Q_RES(CHIPS)':
 'A': CDS_PINID='A';
NODE_NAME     U246 3
 '@S9S_MB_2U_LIB.S9S_MB_2U(SCH_1):PAGE170_I17@PURE_QUANTA.NC7SB3157(CHIPS)':
 'B0': CDS_PINID='B0';
NET_NAME
'OCP_V3_2_WAKE_BUFF_N'
 '@S9S_MB_2U_LIB.S9S_MB_2U(SCH_1):OCP_V3_2_WAKE_BUFF_N':
 C_SIGNAL='@s9s_mb_2u_lib.s9s_mb_2u(sch_1):ocp_v3_2_wake_buff_n';
NODE_NAME     R3185 1
 '@S9S_MB_2U_LIB.S9S_MB_2U(SCH_1):PAGE156_I24@PURE_QUANTA.Q_RES(CHIPS)':
 'A': CDS_PINID='A';
NODE_NAME     R3184 2
 '@S9S_MB_2U_LIB.S9S_MB_2U(SCH_1):PAGE156_I28@PURE_QUANTA.Q_RES(CHIPS)':
 'B': CDS_PINID='B';
NODE_NAME     U217 4
 '@S9S_MB_2U_LIB.S9S_MB_2U(SCH_1):PAGE156_I79@PURE_QUANTA.74LVC1G126SE7(CHIPS)':
 'Y': CDS_PINID='Y';
NET_NAME
'OCP_V3_2_WAKE_BUFF_R_N'
 '@S9S_MB_2U_LIB.S9S_MB_2U(SCH_1):OCP_V3_2_WAKE_BUFF_R_N':
 C_SIGNAL='@s9s_mb_2u_lib.s9s_mb_2u(sch_1):ocp_v3_2_wake_buff_r_n';
NODE_NAME     R3185 2
 '@S9S_MB_2U_LIB.S9S_MB_2U(SCH_1):PAGE156_I24@PURE_QUANTA.Q_RES(CHIPS)':
 'B': CDS_PINID='B';
NODE_NAME     U219 2
 '@S9S_MB_2U_LIB.S9S_MB_2U(SCH_1):PAGE156_I61@PURE_QUANTA.74LVC1G07GV(CHIPS)':
 'A': CDS_PINID='A';
NET_NAME
'OC_P2V5_COMP'
 '@S9S_MB_2U_LIB.S9S_MB_2U(SCH_1):OC_P2V5_COMP':
 C_SIGNAL='@s9s_mb_2u_lib.s9s_mb_2u(sch_1):oc_p2v5_comp';
NODE_NAME     U343 1
 '@S9S_MB_2U_LIB.S9S_MB_2U(SCH_1):PAGE326_I56@PURE_QUANTA.LM4040AIM3X25NOPB(CHIPS)':
 '1+': CDS_PINID='\1+\';
NODE_NAME     R4792 2
 '@S9S_MB_2U_LIB.S9S_MB_2U(SCH_1):PAGE326_I57@PURE_QUANTA.Q_RES(CHIPS)':
 'B': CDS_PINID='B';
NODE_NAME     C2388 1
 '@S9S_MB_2U_LIB.S9S_MB_2U(SCH_1):PAGE326_I64@PURE_QUANTA.Q_CAP(CHIPS)':
 'A': CDS_PINID='A';
NODE_NAME     U344 1
 '@S9S_MB_2U_LIB.S9S_MB_2U(SCH_1):PAGE326_I66@PURE_QUANTA.AP331AWG7(CHIPS)':
 'IN-': CDS_PINID='\in-\';
NET_NAME
'P0V62_CPU0_ERRS_U306_VREF'
 '@S9S_MB_2U_LIB.S9S_MB_2U(SCH_1):P0V62_CPU0_ERRS_U306_VREF':
 C_SIGNAL='@s9s_mb_2u_lib.s9s_mb_2u(sch_1):p0v62_cpu0_errs_u306_vref';
NODE_NAME     U306 4
 '@S9S_MB_2U_LIB.S9S_MB_2U(SCH_1):PAGE322_I80@PURE_QUANTA.GTL2014PW(CHIPS)':
 'VREF': CDS_PINID='VREF';
NODE_NAME     C2254 1
 '@S9S_MB_2U_LIB.S9S_MB_2U(SCH_1):PAGE322_I111@PURE_QUANTA.Q_CAP(CHIPS)':
 'A': CDS_PINID='A';
NODE_NAME     R4041 1
 '@S9S_MB_2U_LIB.S9S_MB_2U(SCH_1):PAGE322_I181@PURE_QUANTA.Q_RES(CHIPS)':
 'A': CDS_PINID='A';
NODE_NAME     R4038 2
 '@S9S_MB_2U_LIB.S9S_MB_2U(SCH_1):PAGE322_I182@PURE_QUANTA.Q_RES(CHIPS)':
 'B': CDS_PINID='B';
NET_NAME
'P0V62_CPU0_ERRS_VREF'
 '@S9S_MB_2U_LIB.S9S_MB_2U(SCH_1):P0V62_CPU0_ERRS_VREF':
 C_SIGNAL='@s9s_mb_2u_lib.s9s_mb_2u(sch_1):p0v62_cpu0_errs_vref';
NODE_NAME     C2249 1
 '@S9S_MB_2U_LIB.S9S_MB_2U(SCH_1):PAGE321_I83@PURE_QUANTA.Q_CAP(CHIPS)':
 'A': CDS_PINID='A';
NODE_NAME     U301 4
 '@S9S_MB_2U_LIB.S9S_MB_2U(SCH_1):PAGE321_I91@PURE_QUANTA.GTL2014PW(CHIPS)':
 'VREF': CDS_PINID='VREF';
NODE_NAME     R4016 2
 '@S9S_MB_2U_LIB.S9S_MB_2U(SCH_1):PAGE321_I97@PURE_QUANTA.Q_RES(CHIPS)':
 'B': CDS_PINID='B';
NODE_NAME     R4019 1
 '@S9S_MB_2U_LIB.S9S_MB_2U(SCH_1):PAGE321_I98@PURE_QUANTA.Q_RES(CHIPS)':
 'A': CDS_PINID='A';
NET_NAME
'P0V62_CPU0_RST_DDR_VREF'
 '@S9S_MB_2U_LIB.S9S_MB_2U(SCH_1):P0V62_CPU0_RST_DDR_VREF':
 C_SIGNAL='@s9s_mb_2u_lib.s9s_mb_2u(sch_1):p0v62_cpu0_rst_ddr_vref';
NODE_NAME     U304 4
 '@S9S_MB_2U_LIB.S9S_MB_2U(SCH_1):PAGE322_I27@PURE_QUANTA.GTL2014PW(CHIPS)':
 'VREF': CDS_PINID='VREF';
NODE_NAME     C2252 1
 '@S9S_MB_2U_LIB.S9S_MB_2U(SCH_1):PAGE322_I101@PURE_QUANTA.Q_CAP(CHIPS)':
 'A': CDS_PINID='A';
NODE_NAME     R4036 2
 '@S9S_MB_2U_LIB.S9S_MB_2U(SCH_1):PAGE322_I128@PURE_QUANTA.Q_RES(CHIPS)':
 'B': CDS_PINID='B';
NODE_NAME     R4039 1
 '@S9S_MB_2U_LIB.S9S_MB_2U(SCH_1):PAGE322_I129@PURE_QUANTA.Q_RES(CHIPS)':
 'A': CDS_PINID='A';
NET_NAME
'P0V62_CPU1_RST_DDR_VREF'
 '@S9S_MB_2U_LIB.S9S_MB_2U(SCH_1):P0V62_CPU1_RST_DDR_VREF':
 C_SIGNAL='@s9s_mb_2u_lib.s9s_mb_2u(sch_1):p0v62_cpu1_rst_ddr_vref';
NODE_NAME     U305 4
 '@S9S_MB_2U_LIB.S9S_MB_2U(SCH_1):PAGE322_I44@PURE_QUANTA.GTL2014PW(CHIPS)':
 'VREF': CDS_PINID='VREF';
NODE_NAME     C2253 1
 '@S9S_MB_2U_LIB.S9S_MB_2U(SCH_1):PAGE322_I106@PURE_QUANTA.Q_CAP(CHIPS)':
 'A': CDS_PINID='A';
NODE_NAME     R4037 2
 '@S9S_MB_2U_LIB.S9S_MB_2U(SCH_1):PAGE322_I130@PURE_QUANTA.Q_RES(CHIPS)':
 'B': CDS_PINID='B';
NODE_NAME     R4040 1
 '@S9S_MB_2U_LIB.S9S_MB_2U(SCH_1):PAGE322_I131@PURE_QUANTA.Q_RES(CHIPS)':
 'A': CDS_PINID='A';
NET_NAME
'P0V7_JTAG_VREF_2'
 '@S9S_MB_2U_LIB.S9S_MB_2U(SCH_1):P0V7_JTAG_VREF_2':
 C_SIGNAL='@s9s_mb_2u_lib.s9s_mb_2u(sch_1):p0v7_jtag_vref_2';
NODE_NAME     R1346 1
 '@S9S_MB_2U_LIB.S9S_MB_2U(SCH_1):PAGE226_I34@PURE_QUANTA.Q_RES(CHIPS)':
 'A': CDS_PINID='A';
NODE_NAME     U83 4
 '@S9S_MB_2U_LIB.S9S_MB_2U(SCH_1):PAGE226_I45@PURE_QUANTA.GTL2014PW(CHIPS)':
 'VREF': CDS_PINID='VREF';
NODE_NAME     R2512 2
 '@S9S_MB_2U_LIB.S9S_MB_2U(SCH_1):PAGE226_I91@PURE_QUANTA.Q_RES(CHIPS)':
 'B': CDS_PINID='B';
NODE_NAME     C1664 1
 '@S9S_MB_2U_LIB.S9S_MB_2U(SCH_1):PAGE226_I93@PURE_QUANTA.Q_CAP(CHIPS)':
 'A': CDS_PINID='A';
NET_NAME
'P12V_AUX'
 '@S9S_MB_2U_LIB.S9S_MB_2U(SCH_1):P12V_AUX':
 C_SIGNAL='@s9s_mb_2u_lib.s9s_mb_2u(sch_1):p12v_aux',
 CDS_GLOBAL_NET='TRUE';
NODE_NAME     PC1656 1
 '@S9S_MB_2U_LIB.S9S_MB_2U(SCH_1):PAGE271_I79@PURE_QUANTA.Q_CAP(CHIPS)':
 'A': CDS_PINID='A';
NODE_NAME     PL32 1
 '@S9S_MB_2U_LIB.S9S_MB_2U(SCH_1):PAGE271_I83@PURE_QUANTA.Q_INDUCTOR(CHIPS)':
 '1': CDS_PINID='\1\';
NODE_NAME     PR260 1
 '@S9S_MB_2U_LIB.S9S_MB_2U(SCH_1):PAGE278_I22@PURE_QUANTA.Q_RES(CHIPS)':
 'A': CDS_PINID='A';
NODE_NAME     PC1659 1
 '@S9S_MB_2U_LIB.S9S_MB_2U(SCH_1):PAGE279_I68@PURE_QUANTA.Q_CAP(CHIPS)':
 'A': CDS_PINID='A';
NODE_NAME     R2528 1
 '@S9S_MB_2U_LIB.S9S_MB_2U(SCH_1):PAGE234_I8@PURE_QUANTA.Q_RES(CHIPS)':
 'A': CDS_PINID='A';
NODE_NAME     R2530 1
 '@S9S_MB_2U_LIB.S9S_MB_2U(SCH_1):PAGE234_I10@PURE_QUANTA.Q_RES(CHIPS)':
 'A': CDS_PINID='A';
NODE_NAME     R1799 1
 '@S9S_MB_2U_LIB.S9S_MB_2U(SCH_1):PAGE239_I173@PURE_QUANTA.Q_RES(CHIPS)':
 'A': CDS_PINID='A';
NODE_NAME     PR3830 1
 '@S9S_MB_2U_LIB.S9S_MB_2U(SCH_1):PAGE131_I85@PURE_QUANTA.Q_RES(CHIPS)':
 'A': CDS_PINID='A';
NODE_NAME     PR3966 1
 '@S9S_MB_2U_LIB.S9S_MB_2U(SCH_1):PAGE324_I61@PURE_QUANTA.Q_RES(CHIPS)':
 'A': CDS_PINID='A';
NODE_NAME     PU294 A3
 '@S9S_MB_2U_LIB.S9S_MB_2U(SCH_1):PAGE324_I62@PURE_QUANTA.MAX15090BEWIT(CHIPS)':
 'IN_A3': CDS_PINID='IN_A3';
NODE_NAME     PU294 A5
 '@S9S_MB_2U_LIB.S9S_MB_2U(SCH_1):PAGE324_I62@PURE_QUANTA.MAX15090BEWIT(CHIPS)':
 'IN_A5': CDS_PINID='IN_A5';
NODE_NAME     PU294 B3
 '@S9S_MB_2U_LIB.S9S_MB_2U(SCH_1):PAGE324_I62@PURE_QUANTA.MAX15090BEWIT(CHIPS)':
 'IN_B3': CDS_PINID='IN_B3';
NODE_NAME     PU294 B5
 '@S9S_MB_2U_LIB.S9S_MB_2U(SCH_1):PAGE324_I62@PURE_QUANTA.MAX15090BEWIT(CHIPS)':
 'IN_B5': CDS_PINID='IN_B5';
NODE_NAME     PU294 C3
 '@S9S_MB_2U_LIB.S9S_MB_2U(SCH_1):PAGE324_I62@PURE_QUANTA.MAX15090BEWIT(CHIPS)':
 'IN_C3': CDS_PINID='IN_C3';
NODE_NAME     PU294 C5
 '@S9S_MB_2U_LIB.S9S_MB_2U(SCH_1):PAGE324_I62@PURE_QUANTA.MAX15090BEWIT(CHIPS)':
 'IN_C5': CDS_PINID='IN_C5';
NODE_NAME     PU294 D5
 '@S9S_MB_2U_LIB.S9S_MB_2U(SCH_1):PAGE324_I62@PURE_QUANTA.MAX15090BEWIT(CHIPS)':
 'IN_D5': CDS_PINID='IN_D5';
NODE_NAME     PR4000 1
 '@S9S_MB_2U_LIB.S9S_MB_2U(SCH_1):PAGE229_I67@PURE_QUANTA.Q_RES(CHIPS)':
 'A': CDS_PINID='A';
NODE_NAME     PR3805 1
 '@S9S_MB_2U_LIB.S9S_MB_2U(SCH_1):PAGE131_I33@PURE_QUANTA.Q_RES(CHIPS)':
 'A': CDS_PINID='A';
NODE_NAME     R4067 1
 '@S9S_MB_2U_LIB.S9S_MB_2U(SCH_1):PAGE131_I40@PURE_QUANTA.Q_RES(CHIPS)':
 'A': CDS_PINID='A';
NODE_NAME     R4072 1
 '@S9S_MB_2U_LIB.S9S_MB_2U(SCH_1):PAGE324_I6@PURE_QUANTA.Q_RES(CHIPS)':
 'A': CDS_PINID='A';
NODE_NAME     PC2231 1
 '@S9S_MB_2U_LIB.S9S_MB_2U(SCH_1):PAGE229_I37@PURE_QUANTA.Q_CAP(CHIPS)':
 'A': CDS_PINID='A';
NODE_NAME     R1655 1
 '@S9S_MB_2U_LIB.S9S_MB_2U(SCH_1):PAGE246_I6@PURE_QUANTA.Q_RES(CHIPS)':
 'A': CDS_PINID='A';
NODE_NAME     R1643 1
 '@S9S_MB_2U_LIB.S9S_MB_2U(SCH_1):PAGE246_I17@PURE_QUANTA.Q_RES(CHIPS)':
 'A': CDS_PINID='A';
NODE_NAME     R1642 1
 '@S9S_MB_2U_LIB.S9S_MB_2U(SCH_1):PAGE246_I22@PURE_QUANTA.Q_RES(CHIPS)':
 'A': CDS_PINID='A';
NODE_NAME     PC1651 1
 '@S9S_MB_2U_LIB.S9S_MB_2U(SCH_1):PAGE249_I14@PURE_QUANTA.Q_CAP(CHIPS)':
 'A': CDS_PINID='A';
NODE_NAME     PR2556 1
 '@S9S_MB_2U_LIB.S9S_MB_2U(SCH_1):PAGE271_I82@PURE_QUANTA.Q_RES(CHIPS)':
 'A': CDS_PINID='A';
NODE_NAME     PL14 1
 '@S9S_MB_2U_LIB.S9S_MB_2U(SCH_1):PAGE276_I64@PURE_QUANTA.Q_INDUCTOR(CHIPS)':
 '1': CDS_PINID='\1\';
NODE_NAME     PU297 1
 '@S9S_MB_2U_LIB.S9S_MB_2U(SCH_1):PAGE325_I17@PURE_QUANTA.MP5991GLUZ(CHIPS)':
 'VOUT1': CDS_PINID='VOUT1';
NODE_NAME     PU297 2
 '@S9S_MB_2U_LIB.S9S_MB_2U(SCH_1):PAGE325_I17@PURE_QUANTA.MP5991GLUZ(CHIPS)':
 'VOUT2': CDS_PINID='VOUT2';
NODE_NAME     PU297 25
 '@S9S_MB_2U_LIB.S9S_MB_2U(SCH_1):PAGE325_I17@PURE_QUANTA.MP5991GLUZ(CHIPS)':
 'VOUT3': CDS_PINID='VOUT3';
NODE_NAME     PU297 26
 '@S9S_MB_2U_LIB.S9S_MB_2U(SCH_1):PAGE325_I17@PURE_QUANTA.MP5991GLUZ(CHIPS)':
 'VOUT4': CDS_PINID='VOUT4';
NODE_NAME     PU297 27
 '@S9S_MB_2U_LIB.S9S_MB_2U(SCH_1):PAGE325_I17@PURE_QUANTA.MP5991GLUZ(CHIPS)':
 'VOUT5': CDS_PINID='VOUT5';
NODE_NAME     PU297 28
 '@S9S_MB_2U_LIB.S9S_MB_2U(SCH_1):PAGE325_I17@PURE_QUANTA.MP5991GLUZ(CHIPS)':
 'VOUT6': CDS_PINID='VOUT6';
NODE_NAME     PU297 29
 '@S9S_MB_2U_LIB.S9S_MB_2U(SCH_1):PAGE325_I17@PURE_QUANTA.MP5991GLUZ(CHIPS)':
 'VOUT7': CDS_PINID='VOUT7';
NODE_NAME     PU297 30
 '@S9S_MB_2U_LIB.S9S_MB_2U(SCH_1):PAGE325_I17@PURE_QUANTA.MP5991GLUZ(CHIPS)':
 'VOUT8': CDS_PINID='VOUT8';
NODE_NAME     PU297 31
 '@S9S_MB_2U_LIB.S9S_MB_2U(SCH_1):PAGE325_I17@PURE_QUANTA.MP5991GLUZ(CHIPS)':
 'VOUT9': CDS_PINID='VOUT9';
NODE_NAME     PU297 32
 '@S9S_MB_2U_LIB.S9S_MB_2U(SCH_1):PAGE325_I17@PURE_QUANTA.MP5991GLUZ(CHIPS)':
 'VOUT10': CDS_PINID='VOUT10';
NODE_NAME     PR2554 1
 '@S9S_MB_2U_LIB.S9S_MB_2U(SCH_1):PAGE253_I81@PURE_QUANTA.Q_RES(CHIPS)':
 'A': CDS_PINID='A';
NODE_NAME     PC1655 1
 '@S9S_MB_2U_LIB.S9S_MB_2U(SCH_1):PAGE261_I60@PURE_QUANTA.Q_CAP(CHIPS)':
 'A': CDS_PINID='A';
NODE_NAME     PL6 1
 '@S9S_MB_2U_LIB.S9S_MB_2U(SCH_1):PAGE261_I62@PURE_QUANTA.Q_INDUCTOR(CHIPS)':
 '1': CDS_PINID='\1\';
NODE_NAME     PU289 27
 '@S9S_MB_2U_LIB.S9S_MB_2U(SCH_1):PAGE303_I56@PURE_QUANTA.MP5990GMA1111Z(CHIPS)':
 'VOUT1': CDS_PINID='VOUT1';
NODE_NAME     PU289 28
 '@S9S_MB_2U_LIB.S9S_MB_2U(SCH_1):PAGE303_I56@PURE_QUANTA.MP5990GMA1111Z(CHIPS)':
 'VOUT2': CDS_PINID='VOUT2';
NODE_NAME     PU289 29
 '@S9S_MB_2U_LIB.S9S_MB_2U(SCH_1):PAGE303_I56@PURE_QUANTA.MP5990GMA1111Z(CHIPS)':
 'VOUT3': CDS_PINID='VOUT3';
NODE_NAME     PU289 30
 '@S9S_MB_2U_LIB.S9S_MB_2U(SCH_1):PAGE303_I56@PURE_QUANTA.MP5990GMA1111Z(CHIPS)':
 'VOUT4': CDS_PINID='VOUT4';
NODE_NAME     PU289 31
 '@S9S_MB_2U_LIB.S9S_MB_2U(SCH_1):PAGE303_I56@PURE_QUANTA.MP5990GMA1111Z(CHIPS)':
 'VOUT5': CDS_PINID='VOUT5';
NODE_NAME     PU289 32
 '@S9S_MB_2U_LIB.S9S_MB_2U(SCH_1):PAGE303_I56@PURE_QUANTA.MP5990GMA1111Z(CHIPS)':
 'VOUT6': CDS_PINID='VOUT6';
NODE_NAME     PU289 33
 '@S9S_MB_2U_LIB.S9S_MB_2U(SCH_1):PAGE303_I56@PURE_QUANTA.MP5990GMA1111Z(CHIPS)':
 'VOUT7': CDS_PINID='VOUT7';
NODE_NAME     PU289 34
 '@S9S_MB_2U_LIB.S9S_MB_2U(SCH_1):PAGE303_I56@PURE_QUANTA.MP5990GMA1111Z(CHIPS)':
 'VOUT8': CDS_PINID='VOUT8';
NODE_NAME     PU289 35
 '@S9S_MB_2U_LIB.S9S_MB_2U(SCH_1):PAGE303_I56@PURE_QUANTA.MP5990GMA1111Z(CHIPS)':
 'VOUT9': CDS_PINID='VOUT9';
NODE_NAME     PU289 36
 '@S9S_MB_2U_LIB.S9S_MB_2U(SCH_1):PAGE303_I56@PURE_QUANTA.MP5990GMA1111Z(CHIPS)':
 'VOUT10': CDS_PINID='VOUT10';
NODE_NAME     PR3931 1
 '@S9S_MB_2U_LIB.S9S_MB_2U(SCH_1):PAGE303_I86@PURE_QUANTA.Q_RES(CHIPS)':
 'A': CDS_PINID='A';
NODE_NAME     PU296 1
 '@S9S_MB_2U_LIB.S9S_MB_2U(SCH_1):PAGE325_I35@PURE_QUANTA.MP5991GLUZ(CHIPS)':
 'VOUT1': CDS_PINID='VOUT1';
NODE_NAME     PU296 2
 '@S9S_MB_2U_LIB.S9S_MB_2U(SCH_1):PAGE325_I35@PURE_QUANTA.MP5991GLUZ(CHIPS)':
 'VOUT2': CDS_PINID='VOUT2';
NODE_NAME     PU296 25
 '@S9S_MB_2U_LIB.S9S_MB_2U(SCH_1):PAGE325_I35@PURE_QUANTA.MP5991GLUZ(CHIPS)':
 'VOUT3': CDS_PINID='VOUT3';
NODE_NAME     PU296 26
 '@S9S_MB_2U_LIB.S9S_MB_2U(SCH_1):PAGE325_I35@PURE_QUANTA.MP5991GLUZ(CHIPS)':
 'VOUT4': CDS_PINID='VOUT4';
NODE_NAME     PU296 27
 '@S9S_MB_2U_LIB.S9S_MB_2U(SCH_1):PAGE325_I35@PURE_QUANTA.MP5991GLUZ(CHIPS)':
 'VOUT5': CDS_PINID='VOUT5';
NODE_NAME     PU296 28
 '@S9S_MB_2U_LIB.S9S_MB_2U(SCH_1):PAGE325_I35@PURE_QUANTA.MP5991GLUZ(CHIPS)':
 'VOUT6': CDS_PINID='VOUT6';
NODE_NAME     PU296 29
 '@S9S_MB_2U_LIB.S9S_MB_2U(SCH_1):PAGE325_I35@PURE_QUANTA.MP5991GLUZ(CHIPS)':
 'VOUT7': CDS_PINID='VOUT7';
NODE_NAME     PU296 30
 '@S9S_MB_2U_LIB.S9S_MB_2U(SCH_1):PAGE325_I35@PURE_QUANTA.MP5991GLUZ(CHIPS)':
 'VOUT8': CDS_PINID='VOUT8';
NODE_NAME     PU296 31
 '@S9S_MB_2U_LIB.S9S_MB_2U(SCH_1):PAGE325_I35@PURE_QUANTA.MP5991GLUZ(CHIPS)':
 'VOUT9': CDS_PINID='VOUT9';
NODE_NAME     PU296 32
 '@S9S_MB_2U_LIB.S9S_MB_2U(SCH_1):PAGE325_I35@PURE_QUANTA.MP5991GLUZ(CHIPS)':
 'VOUT10': CDS_PINID='VOUT10';
NODE_NAME     PC1654 1
 '@S9S_MB_2U_LIB.S9S_MB_2U(SCH_1):PAGE258_I57@PURE_QUANTA.Q_CAP(CHIPS)':
 'A': CDS_PINID='A';
NODE_NAME     PR303 1
 '@S9S_MB_2U_LIB.S9S_MB_2U(SCH_1):PAGE270_I7@PURE_QUANTA.Q_RES(CHIPS)':
 'A': CDS_PINID='A';
NODE_NAME     PR156 1
 '@S9S_MB_2U_LIB.S9S_MB_2U(SCH_1):PAGE252_I10@PURE_QUANTA.Q_RES(CHIPS)':
 'A': CDS_PINID='A';
NODE_NAME     PR157 1
 '@S9S_MB_2U_LIB.S9S_MB_2U(SCH_1):PAGE252_I11@PURE_QUANTA.Q_RES(CHIPS)':
 'A': CDS_PINID='A';
NODE_NAME     PR261 1
 '@S9S_MB_2U_LIB.S9S_MB_2U(SCH_1):PAGE278_I21@PURE_QUANTA.Q_RES(CHIPS)':
 'A': CDS_PINID='A';
NODE_NAME     PU287 1
 '@S9S_MB_2U_LIB.S9S_MB_2U(SCH_1):PAGE301_I35@PURE_QUANTA.MP5991GLUZ(CHIPS)':
 'VOUT1': CDS_PINID='VOUT1';
NODE_NAME     PU287 2
 '@S9S_MB_2U_LIB.S9S_MB_2U(SCH_1):PAGE301_I35@PURE_QUANTA.MP5991GLUZ(CHIPS)':
 'VOUT2': CDS_PINID='VOUT2';
NODE_NAME     PU287 25
 '@S9S_MB_2U_LIB.S9S_MB_2U(SCH_1):PAGE301_I35@PURE_QUANTA.MP5991GLUZ(CHIPS)':
 'VOUT3': CDS_PINID='VOUT3';
NODE_NAME     PU287 26
 '@S9S_MB_2U_LIB.S9S_MB_2U(SCH_1):PAGE301_I35@PURE_QUANTA.MP5991GLUZ(CHIPS)':
 'VOUT4': CDS_PINID='VOUT4';
NODE_NAME     PU287 27
 '@S9S_MB_2U_LIB.S9S_MB_2U(SCH_1):PAGE301_I35@PURE_QUANTA.MP5991GLUZ(CHIPS)':
 'VOUT5': CDS_PINID='VOUT5';
NODE_NAME     PU287 28
 '@S9S_MB_2U_LIB.S9S_MB_2U(SCH_1):PAGE301_I35@PURE_QUANTA.MP5991GLUZ(CHIPS)':
 'VOUT6': CDS_PINID='VOUT6';
NODE_NAME     PU287 29
 '@S9S_MB_2U_LIB.S9S_MB_2U(SCH_1):PAGE301_I35@PURE_QUANTA.MP5991GLUZ(CHIPS)':
 'VOUT7': CDS_PINID='VOUT7';
NODE_NAME     PU287 30
 '@S9S_MB_2U_LIB.S9S_MB_2U(SCH_1):PAGE301_I35@PURE_QUANTA.MP5991GLUZ(CHIPS)':
 'VOUT8': CDS_PINID='VOUT8';
NODE_NAME     PU287 31
 '@S9S_MB_2U_LIB.S9S_MB_2U(SCH_1):PAGE301_I35@PURE_QUANTA.MP5991GLUZ(CHIPS)':
 'VOUT9': CDS_PINID='VOUT9';
NODE_NAME     PU287 32
 '@S9S_MB_2U_LIB.S9S_MB_2U(SCH_1):PAGE301_I35@PURE_QUANTA.MP5991GLUZ(CHIPS)':
 'VOUT10': CDS_PINID='VOUT10';
NODE_NAME     PD101 C
 '@S9S_MB_2U_LIB.S9S_MB_2U(SCH_1):PAGE153_I38@PURE_QUANTA.DIODE_TVS(CHIPS)':
 'C':PIN_LENGTH='Short',
 CDS_PINID='C';
NODE_NAME     R4070 1
 '@S9S_MB_2U_LIB.S9S_MB_2U(SCH_1):PAGE153_I62@PURE_QUANTA.Q_RES(CHIPS)':
 'A': CDS_PINID='A';
NODE_NAME     R4065 1
 '@S9S_MB_2U_LIB.S9S_MB_2U(SCH_1):PAGE131_I14@PURE_QUANTA.Q_RES(CHIPS)':
 'A': CDS_PINID='A';
NODE_NAME     PU201 A3
 '@S9S_MB_2U_LIB.S9S_MB_2U(SCH_1):PAGE131_I63@PURE_QUANTA.MAX15090BEWIT(CHIPS)':
 'IN_A3': CDS_PINID='IN_A3';
NODE_NAME     PU201 A5
 '@S9S_MB_2U_LIB.S9S_MB_2U(SCH_1):PAGE131_I63@PURE_QUANTA.MAX15090BEWIT(CHIPS)':
 'IN_A5': CDS_PINID='IN_A5';
NODE_NAME     PU201 B3
 '@S9S_MB_2U_LIB.S9S_MB_2U(SCH_1):PAGE131_I63@PURE_QUANTA.MAX15090BEWIT(CHIPS)':
 'IN_B3': CDS_PINID='IN_B3';
NODE_NAME     PU201 B5
 '@S9S_MB_2U_LIB.S9S_MB_2U(SCH_1):PAGE131_I63@PURE_QUANTA.MAX15090BEWIT(CHIPS)':
 'IN_B5': CDS_PINID='IN_B5';
NODE_NAME     PU201 C3
 '@S9S_MB_2U_LIB.S9S_MB_2U(SCH_1):PAGE131_I63@PURE_QUANTA.MAX15090BEWIT(CHIPS)':
 'IN_C3': CDS_PINID='IN_C3';
NODE_NAME     PU201 C5
 '@S9S_MB_2U_LIB.S9S_MB_2U(SCH_1):PAGE131_I63@PURE_QUANTA.MAX15090BEWIT(CHIPS)':
 'IN_C5': CDS_PINID='IN_C5';
NODE_NAME     PU201 D5
 '@S9S_MB_2U_LIB.S9S_MB_2U(SCH_1):PAGE131_I63@PURE_QUANTA.MAX15090BEWIT(CHIPS)':
 'IN_D5': CDS_PINID='IN_D5';
NODE_NAME     R4074 1
 '@S9S_MB_2U_LIB.S9S_MB_2U(SCH_1):PAGE324_I22@PURE_QUANTA.Q_RES(CHIPS)':
 'A': CDS_PINID='A';
NODE_NAME     PC2207 1
 '@S9S_MB_2U_LIB.S9S_MB_2U(SCH_1):PAGE324_I31@PURE_QUANTA.Q_CAP(CHIPS)':
 'A': CDS_PINID='A';
NODE_NAME     PU292 21_22
 '@S9S_MB_2U_LIB.S9S_MB_2U(SCH_1):PAGE323_I49@PURE_QUANTA.RS31312R(CHIPS)':
 'VIN_21_22': CDS_PINID='VIN_21_22';
NODE_NAME     PU292 23
 '@S9S_MB_2U_LIB.S9S_MB_2U(SCH_1):PAGE323_I49@PURE_QUANTA.RS31312R(CHIPS)':
 'VIN_23': CDS_PINID='VIN_23';
NODE_NAME     PU292 24
 '@S9S_MB_2U_LIB.S9S_MB_2U(SCH_1):PAGE323_I49@PURE_QUANTA.RS31312R(CHIPS)':
 'VIN_24': CDS_PINID='VIN_24';
NODE_NAME     PU292 25
 '@S9S_MB_2U_LIB.S9S_MB_2U(SCH_1):PAGE323_I49@PURE_QUANTA.RS31312R(CHIPS)':
 'VIN_25': CDS_PINID='VIN_25';
NODE_NAME     PU292 26
 '@S9S_MB_2U_LIB.S9S_MB_2U(SCH_1):PAGE323_I49@PURE_QUANTA.RS31312R(CHIPS)':
 'VIN_26': CDS_PINID='VIN_26';
NODE_NAME     PC2198 1
 '@S9S_MB_2U_LIB.S9S_MB_2U(SCH_1):PAGE323_I51@PURE_QUANTA.Q_CAP(CHIPS)':
 'A': CDS_PINID='A';
NODE_NAME     PD115 C
 '@S9S_MB_2U_LIB.S9S_MB_2U(SCH_1):PAGE229_I29@PURE_QUANTA.DIODE_TVS(CHIPS)':
 'C':PIN_LENGTH='SHORT',
 CDS_PINID='C';
NODE_NAME     PC2230 1
 '@S9S_MB_2U_LIB.S9S_MB_2U(SCH_1):PAGE229_I31@PURE_QUANTA.Q_CAP(CHIPS)':
 'A': CDS_PINID='A';
NODE_NAME     PR4010 1
 '@S9S_MB_2U_LIB.S9S_MB_2U(SCH_1):PAGE229_I52@PURE_QUANTA.Q_RES(CHIPS)':
 'A': CDS_PINID='A';
NODE_NAME     PR4003 1
 '@S9S_MB_2U_LIB.S9S_MB_2U(SCH_1):PAGE229_I70@PURE_QUANTA.Q_RES(CHIPS)':
 'A': CDS_PINID='A';
NODE_NAME     PC1657 1
 '@S9S_MB_2U_LIB.S9S_MB_2U(SCH_1):PAGE275_I77@PURE_QUANTA.Q_CAP(CHIPS)':
 'A': CDS_PINID='A';
NODE_NAME     PL43 1
 '@S9S_MB_2U_LIB.S9S_MB_2U(SCH_1):PAGE275_I79@PURE_QUANTA.Q_INDUCTOR(CHIPS)':
 '1': CDS_PINID='\1\';
NODE_NAME     PL44 1
 '@S9S_MB_2U_LIB.S9S_MB_2U(SCH_1):PAGE257_I80@PURE_QUANTA.Q_INDUCTOR(CHIPS)':
 '1': CDS_PINID='\1\';
NODE_NAME     PC1652 1
 '@S9S_MB_2U_LIB.S9S_MB_2U(SCH_1):PAGE253_I80@PURE_QUANTA.Q_CAP(CHIPS)':
 'A': CDS_PINID='A';
NODE_NAME     PL15 1
 '@S9S_MB_2U_LIB.S9S_MB_2U(SCH_1):PAGE253_I82@PURE_QUANTA.Q_INDUCTOR(CHIPS)':
 '1': CDS_PINID='\1\';
NODE_NAME     PC1653 1
 '@S9S_MB_2U_LIB.S9S_MB_2U(SCH_1):PAGE257_I78@PURE_QUANTA.Q_CAP(CHIPS)':
 'A': CDS_PINID='A';
NODE_NAME     PL101 1
 '@S9S_MB_2U_LIB.S9S_MB_2U(SCH_1):PAGE258_I59@PURE_QUANTA.Q_INDUCTOR(CHIPS)':
 '1': CDS_PINID='\1\';
NODE_NAME     PC1658 1
 '@S9S_MB_2U_LIB.S9S_MB_2U(SCH_1):PAGE276_I62@PURE_QUANTA.Q_CAP(CHIPS)':
 'A': CDS_PINID='A';
NODE_NAME     PL23 1
 '@S9S_MB_2U_LIB.S9S_MB_2U(SCH_1):PAGE279_I78@PURE_QUANTA.Q_INDUCTOR(CHIPS)':
 '1': CDS_PINID='\1\';
NODE_NAME     PR304 1
 '@S9S_MB_2U_LIB.S9S_MB_2U(SCH_1):PAGE270_I9@PURE_QUANTA.Q_RES(CHIPS)':
 'A': CDS_PINID='A';
NODE_NAME     PR108 1
 '@S9S_MB_2U_LIB.S9S_MB_2U(SCH_1):PAGE260_I9@PURE_QUANTA.Q_RES(CHIPS)':
 'A': CDS_PINID='A';
NODE_NAME     PR107 1
 '@S9S_MB_2U_LIB.S9S_MB_2U(SCH_1):PAGE260_I10@PURE_QUANTA.Q_RES(CHIPS)':
 'A': CDS_PINID='A';
NODE_NAME     PC1650 1
 '@S9S_MB_2U_LIB.S9S_MB_2U(SCH_1):PAGE248_I18@PURE_QUANTA.Q_CAP(CHIPS)':
 'A': CDS_PINID='A';
NODE_NAME     R1837 1
 '@S9S_MB_2U_LIB.S9S_MB_2U(SCH_1):PAGE240_I3@PURE_QUANTA.Q_RES_4P_12(CHIPS)':
 '1': CDS_PINID='\1\';
NODE_NAME     R1838 1
 '@S9S_MB_2U_LIB.S9S_MB_2U(SCH_1):PAGE240_I11@PURE_QUANTA.Q_RES_4P_12(CHIPS)':
 '1': CDS_PINID='\1\';
NODE_NAME     PU288 1
 '@S9S_MB_2U_LIB.S9S_MB_2U(SCH_1):PAGE301_I14@PURE_QUANTA.MP5991GLUZ(CHIPS)':
 'VOUT1': CDS_PINID='VOUT1';
NODE_NAME     PU288 2
 '@S9S_MB_2U_LIB.S9S_MB_2U(SCH_1):PAGE301_I14@PURE_QUANTA.MP5991GLUZ(CHIPS)':
 'VOUT2': CDS_PINID='VOUT2';
NODE_NAME     PU288 25
 '@S9S_MB_2U_LIB.S9S_MB_2U(SCH_1):PAGE301_I14@PURE_QUANTA.MP5991GLUZ(CHIPS)':
 'VOUT3': CDS_PINID='VOUT3';
NODE_NAME     PU288 26
 '@S9S_MB_2U_LIB.S9S_MB_2U(SCH_1):PAGE301_I14@PURE_QUANTA.MP5991GLUZ(CHIPS)':
 'VOUT4': CDS_PINID='VOUT4';
NODE_NAME     PU288 27
 '@S9S_MB_2U_LIB.S9S_MB_2U(SCH_1):PAGE301_I14@PURE_QUANTA.MP5991GLUZ(CHIPS)':
 'VOUT5': CDS_PINID='VOUT5';
NODE_NAME     PU288 28
 '@S9S_MB_2U_LIB.S9S_MB_2U(SCH_1):PAGE301_I14@PURE_QUANTA.MP5991GLUZ(CHIPS)':
 'VOUT6': CDS_PINID='VOUT6';
NODE_NAME     PU288 29
 '@S9S_MB_2U_LIB.S9S_MB_2U(SCH_1):PAGE301_I14@PURE_QUANTA.MP5991GLUZ(CHIPS)':
 'VOUT7': CDS_PINID='VOUT7';
NODE_NAME     PU288 30
 '@S9S_MB_2U_LIB.S9S_MB_2U(SCH_1):PAGE301_I14@PURE_QUANTA.MP5991GLUZ(CHIPS)':
 'VOUT8': CDS_PINID='VOUT8';
NODE_NAME     PU288 31
 '@S9S_MB_2U_LIB.S9S_MB_2U(SCH_1):PAGE301_I14@PURE_QUANTA.MP5991GLUZ(CHIPS)':
 'VOUT9': CDS_PINID='VOUT9';
NODE_NAME     PU288 32
 '@S9S_MB_2U_LIB.S9S_MB_2U(SCH_1):PAGE301_I14@PURE_QUANTA.MP5991GLUZ(CHIPS)':
 'VOUT10': CDS_PINID='VOUT10';
NODE_NAME     PPQ5 1
 '@S9S_MB_2U_LIB.S9S_MB_2U(SCH_1):PAGE328_I35@PURE_QUANTA.MOSFET_NCH_1D3S(CHIPS)':
 '1': CDS_PINID='\1\';
NODE_NAME     PPQ5 2
 '@S9S_MB_2U_LIB.S9S_MB_2U(SCH_1):PAGE328_I35@PURE_QUANTA.MOSFET_NCH_1D3S(CHIPS)':
 '2': CDS_PINID='\2\';
NODE_NAME     PPQ5 3
 '@S9S_MB_2U_LIB.S9S_MB_2U(SCH_1):PAGE328_I35@PURE_QUANTA.MOSFET_NCH_1D3S(CHIPS)':
 '3': CDS_PINID='\3\';
NODE_NAME     PPQ6 1
 '@S9S_MB_2U_LIB.S9S_MB_2U(SCH_1):PAGE328_I40@PURE_QUANTA.MOSFET_NCH_1D3S(CHIPS)':
 '1': CDS_PINID='\1\';
NODE_NAME     PPQ6 2
 '@S9S_MB_2U_LIB.S9S_MB_2U(SCH_1):PAGE328_I40@PURE_QUANTA.MOSFET_NCH_1D3S(CHIPS)':
 '2': CDS_PINID='\2\';
NODE_NAME     PPQ6 3
 '@S9S_MB_2U_LIB.S9S_MB_2U(SCH_1):PAGE328_I40@PURE_QUANTA.MOSFET_NCH_1D3S(CHIPS)':
 '3': CDS_PINID='\3\';
NODE_NAME     PPQ7 1
 '@S9S_MB_2U_LIB.S9S_MB_2U(SCH_1):PAGE328_I41@PURE_QUANTA.MOSFET_NCH_1D3S(CHIPS)':
 '1': CDS_PINID='\1\';
NODE_NAME     PPQ7 2
 '@S9S_MB_2U_LIB.S9S_MB_2U(SCH_1):PAGE328_I41@PURE_QUANTA.MOSFET_NCH_1D3S(CHIPS)':
 '2': CDS_PINID='\2\';
NODE_NAME     PPQ7 3
 '@S9S_MB_2U_LIB.S9S_MB_2U(SCH_1):PAGE328_I41@PURE_QUANTA.MOSFET_NCH_1D3S(CHIPS)':
 '3': CDS_PINID='\3\';
NODE_NAME     PPQ8 1
 '@S9S_MB_2U_LIB.S9S_MB_2U(SCH_1):PAGE328_I62@PURE_QUANTA.MOSFET_NCH_1D3S(CHIPS)':
 '1': CDS_PINID='\1\';
NODE_NAME     PPQ8 2
 '@S9S_MB_2U_LIB.S9S_MB_2U(SCH_1):PAGE328_I62@PURE_QUANTA.MOSFET_NCH_1D3S(CHIPS)':
 '2': CDS_PINID='\2\';
NODE_NAME     PPQ8 3
 '@S9S_MB_2U_LIB.S9S_MB_2U(SCH_1):PAGE328_I62@PURE_QUANTA.MOSFET_NCH_1D3S(CHIPS)':
 '3': CDS_PINID='\3\';
NODE_NAME     PPQ1 1
 '@S9S_MB_2U_LIB.S9S_MB_2U(SCH_1):PAGE328_I65@PURE_QUANTA.MOSFET_NCH_1D3S(CHIPS)':
 '1': CDS_PINID='\1\';
NODE_NAME     PPQ1 2
 '@S9S_MB_2U_LIB.S9S_MB_2U(SCH_1):PAGE328_I65@PURE_QUANTA.MOSFET_NCH_1D3S(CHIPS)':
 '2': CDS_PINID='\2\';
NODE_NAME     PPQ1 3
 '@S9S_MB_2U_LIB.S9S_MB_2U(SCH_1):PAGE328_I65@PURE_QUANTA.MOSFET_NCH_1D3S(CHIPS)':
 '3': CDS_PINID='\3\';
NODE_NAME     PC1750 1
 '@S9S_MB_2U_LIB.S9S_MB_2U(SCH_1):PAGE328_I68@PURE_QUANTA.Q_CAP(CHIPS)':
 'A': CDS_PINID='A';
NODE_NAME     PR2537 1
 '@S9S_MB_2U_LIB.S9S_MB_2U(SCH_1):PAGE328_I70@PURE_QUANTA.Q_RES(CHIPS)':
 'A': CDS_PINID='A';
NODE_NAME     PD17 K
 '@S9S_MB_2U_LIB.S9S_MB_2U(SCH_1):PAGE328_I72@PURE_QUANTA.SS15P3SM386A(CHIPS)':
 'CATHODE': CDS_PINID='CATHODE';
NODE_NAME     PPQ2 1
 '@S9S_MB_2U_LIB.S9S_MB_2U(SCH_1):PAGE328_I73@PURE_QUANTA.MOSFET_NCH_1D3S(CHIPS)':
 '1': CDS_PINID='\1\';
NODE_NAME     PPQ2 2
 '@S9S_MB_2U_LIB.S9S_MB_2U(SCH_1):PAGE328_I73@PURE_QUANTA.MOSFET_NCH_1D3S(CHIPS)':
 '2': CDS_PINID='\2\';
NODE_NAME     PPQ2 3
 '@S9S_MB_2U_LIB.S9S_MB_2U(SCH_1):PAGE328_I73@PURE_QUANTA.MOSFET_NCH_1D3S(CHIPS)':
 '3': CDS_PINID='\3\';
NODE_NAME     PPQ9 1
 '@S9S_MB_2U_LIB.S9S_MB_2U(SCH_1):PAGE328_I77@PURE_QUANTA.MOSFET_NCH_1D3S(CHIPS)':
 '1': CDS_PINID='\1\';
NODE_NAME     PPQ9 2
 '@S9S_MB_2U_LIB.S9S_MB_2U(SCH_1):PAGE328_I77@PURE_QUANTA.MOSFET_NCH_1D3S(CHIPS)':
 '2': CDS_PINID='\2\';
NODE_NAME     PPQ9 3
 '@S9S_MB_2U_LIB.S9S_MB_2U(SCH_1):PAGE328_I77@PURE_QUANTA.MOSFET_NCH_1D3S(CHIPS)':
 '3': CDS_PINID='\3\';
NODE_NAME     PJ42 10
 '@S9S_MB_2U_LIB.S9S_MB_2U(SCH_1):PAGE327_I34@PURE_QUANTA.SCONN21_9193031121LF(CHIPS)':
 '10': CDS_PINID='\10\';
NODE_NAME     PC1789 1
 '@S9S_MB_2U_LIB.S9S_MB_2U(SCH_1):PAGE327_I38@PURE_QUANTA.Q_CAP(CHIPS)':
 'A': CDS_PINID='A';
NODE_NAME     R2236 1
 '@S9S_MB_2U_LIB.S9S_MB_2U(SCH_1):PAGE326_I7@PURE_QUANTA.Q_RES(CHIPS)':
 'A': CDS_PINID='A';
NODE_NAME     R2221 1
 '@S9S_MB_2U_LIB.S9S_MB_2U(SCH_1):PAGE326_I20@PURE_QUANTA.Q_RES(CHIPS)':
 'A': CDS_PINID='A';
NODE_NAME     R3933 1
 '@S9S_MB_2U_LIB.S9S_MB_2U(SCH_1):PAGE303_I62@PURE_QUANTA.Q_RES(CHIPS)':
 'A': CDS_PINID='A';
NODE_NAME     R4680 1
 '@S9S_MB_2U_LIB.S9S_MB_2U(SCH_1):PAGE246_I102@PURE_QUANTA.Q_RES(CHIPS)':
 'A': CDS_PINID='A';
NODE_NAME     R4706 2
 '@S9S_MB_2U_LIB.S9S_MB_2U(SCH_1):PAGE241_I66@PURE_QUANTA.Q_RES(CHIPS)':
 'B': CDS_PINID='B';
NODE_NAME     C2383 1
 '@S9S_MB_2U_LIB.S9S_MB_2U(SCH_1):PAGE329_I11@PURE_QUANTA.Q_CAP(CHIPS)':
 'A': CDS_PINID='A';
NODE_NAME     U339 5
 '@S9S_MB_2U_LIB.S9S_MB_2U(SCH_1):PAGE329_I12@PURE_QUANTA.AP331AWG7(CHIPS)':
 'VCC': CDS_PINID='VCC';
NODE_NAME     R4774 1
 '@S9S_MB_2U_LIB.S9S_MB_2U(SCH_1):PAGE329_I17@PURE_QUANTA.Q_RES(CHIPS)':
 'A': CDS_PINID='A';
NODE_NAME     U340 5
 '@S9S_MB_2U_LIB.S9S_MB_2U(SCH_1):PAGE329_I23@PURE_QUANTA.AP331AWG7(CHIPS)':
 'VCC': CDS_PINID='VCC';
NODE_NAME     C2384 1
 '@S9S_MB_2U_LIB.S9S_MB_2U(SCH_1):PAGE329_I29@PURE_QUANTA.Q_CAP(CHIPS)':
 'A': CDS_PINID='A';
NODE_NAME     R4776 1
 '@S9S_MB_2U_LIB.S9S_MB_2U(SCH_1):PAGE329_I38@PURE_QUANTA.Q_RES(CHIPS)':
 'A': CDS_PINID='A';
NODE_NAME     U342 5
 '@S9S_MB_2U_LIB.S9S_MB_2U(SCH_1):PAGE329_I45@PURE_QUANTA.AP331AWG7(CHIPS)':
 'VCC': CDS_PINID='VCC';
NODE_NAME     C2387 1
 '@S9S_MB_2U_LIB.S9S_MB_2U(SCH_1):PAGE329_I51@PURE_QUANTA.Q_CAP(CHIPS)':
 'A': CDS_PINID='A';
NODE_NAME     R4790 1
 '@S9S_MB_2U_LIB.S9S_MB_2U(SCH_1):PAGE329_I67@PURE_QUANTA.Q_RES(CHIPS)':
 'A': CDS_PINID='A';
NODE_NAME     U344 5
 '@S9S_MB_2U_LIB.S9S_MB_2U(SCH_1):PAGE326_I66@PURE_QUANTA.AP331AWG7(CHIPS)':
 'VCC': CDS_PINID='VCC';
NODE_NAME     C2390 1
 '@S9S_MB_2U_LIB.S9S_MB_2U(SCH_1):PAGE326_I71@PURE_QUANTA.Q_CAP(CHIPS)':
 'A': CDS_PINID='A';
NODE_NAME     R4806 1
 '@S9S_MB_2U_LIB.S9S_MB_2U(SCH_1):PAGE326_I98@PURE_QUANTA.Q_RES(CHIPS)':
 'A': CDS_PINID='A';
NODE_NAME     R2219 1
 '@S9S_MB_2U_LIB.S9S_MB_2U(SCH_1):PAGE326_I100@PURE_QUANTA.Q_RES(CHIPS)':
 'A': CDS_PINID='A';
NODE_NAME     R4068 1
 '@S9S_MB_2U_LIB.S9S_MB_2U(SCH_1):PAGE153_I15@PURE_QUANTA.Q_RES(CHIPS)':
 'A': CDS_PINID='A';
NODE_NAME     PR3786 1
 '@S9S_MB_2U_LIB.S9S_MB_2U(SCH_1):PAGE153_I42@PURE_QUANTA.Q_RES(CHIPS)':
 'A': CDS_PINID='A';
NODE_NAME     PC2079 1
 '@S9S_MB_2U_LIB.S9S_MB_2U(SCH_1):PAGE153_I44@PURE_QUANTA.Q_CAP(CHIPS)':
 'A': CDS_PINID='A';
NODE_NAME     PU203 A3
 '@S9S_MB_2U_LIB.S9S_MB_2U(SCH_1):PAGE153_I51@PURE_QUANTA.MAX15090BEWIT(CHIPS)':
 'IN_A3': CDS_PINID='IN_A3';
NODE_NAME     PU203 A5
 '@S9S_MB_2U_LIB.S9S_MB_2U(SCH_1):PAGE153_I51@PURE_QUANTA.MAX15090BEWIT(CHIPS)':
 'IN_A5': CDS_PINID='IN_A5';
NODE_NAME     PU203 B3
 '@S9S_MB_2U_LIB.S9S_MB_2U(SCH_1):PAGE153_I51@PURE_QUANTA.MAX15090BEWIT(CHIPS)':
 'IN_B3': CDS_PINID='IN_B3';
NODE_NAME     PU203 B5
 '@S9S_MB_2U_LIB.S9S_MB_2U(SCH_1):PAGE153_I51@PURE_QUANTA.MAX15090BEWIT(CHIPS)':
 'IN_B5': CDS_PINID='IN_B5';
NODE_NAME     PU203 C3
 '@S9S_MB_2U_LIB.S9S_MB_2U(SCH_1):PAGE153_I51@PURE_QUANTA.MAX15090BEWIT(CHIPS)':
 'IN_C3': CDS_PINID='IN_C3';
NODE_NAME     PU203 C5
 '@S9S_MB_2U_LIB.S9S_MB_2U(SCH_1):PAGE153_I51@PURE_QUANTA.MAX15090BEWIT(CHIPS)':
 'IN_C5': CDS_PINID='IN_C5';
NODE_NAME     PU203 D5
 '@S9S_MB_2U_LIB.S9S_MB_2U(SCH_1):PAGE153_I51@PURE_QUANTA.MAX15090BEWIT(CHIPS)':
 'IN_D5': CDS_PINID='IN_D5';
NODE_NAME     PR3792 1
 '@S9S_MB_2U_LIB.S9S_MB_2U(SCH_1):PAGE153_I56@PURE_QUANTA.Q_RES(CHIPS)':
 'A': CDS_PINID='A';
NODE_NAME     PC2154 1
 '@S9S_MB_2U_LIB.S9S_MB_2U(SCH_1):PAGE236_I68@PURE_QUANTA.Q_CAP(CHIPS)':
 'A': CDS_PINID='A';
NODE_NAME     PU204 21_22
 '@S9S_MB_2U_LIB.S9S_MB_2U(SCH_1):PAGE236_I70@PURE_QUANTA.RS31312R(CHIPS)':
 'VIN_21_22': CDS_PINID='VIN_21_22';
NODE_NAME     PU204 23
 '@S9S_MB_2U_LIB.S9S_MB_2U(SCH_1):PAGE236_I70@PURE_QUANTA.RS31312R(CHIPS)':
 'VIN_23': CDS_PINID='VIN_23';
NODE_NAME     PU204 24
 '@S9S_MB_2U_LIB.S9S_MB_2U(SCH_1):PAGE236_I70@PURE_QUANTA.RS31312R(CHIPS)':
 'VIN_24': CDS_PINID='VIN_24';
NODE_NAME     PU204 25
 '@S9S_MB_2U_LIB.S9S_MB_2U(SCH_1):PAGE236_I70@PURE_QUANTA.RS31312R(CHIPS)':
 'VIN_25': CDS_PINID='VIN_25';
NODE_NAME     PU204 26
 '@S9S_MB_2U_LIB.S9S_MB_2U(SCH_1):PAGE236_I70@PURE_QUANTA.RS31312R(CHIPS)':
 'VIN_26': CDS_PINID='VIN_26';
NODE_NAME     PR3841 1
 '@S9S_MB_2U_LIB.S9S_MB_2U(SCH_1):PAGE236_I86@PURE_QUANTA.Q_RES(CHIPS)':
 'A': CDS_PINID='A';
NODE_NAME     PR3843 1
 '@S9S_MB_2U_LIB.S9S_MB_2U(SCH_1):PAGE236_I89@PURE_QUANTA.Q_RES(CHIPS)':
 'A': CDS_PINID='A';
NODE_NAME     PD107 C
 '@S9S_MB_2U_LIB.S9S_MB_2U(SCH_1):PAGE131_I44@PURE_QUANTA.DIODE_TVS(CHIPS)':
 'C':PIN_LENGTH='Short',
 CDS_PINID='C';
NODE_NAME     PC2139 1
 '@S9S_MB_2U_LIB.S9S_MB_2U(SCH_1):PAGE131_I46@PURE_QUANTA.Q_CAP(CHIPS)':
 'A': CDS_PINID='A';
NODE_NAME     PC2165 1
 '@S9S_MB_2U_LIB.S9S_MB_2U(SCH_1):PAGE237_I68@PURE_QUANTA.Q_CAP(CHIPS)':
 'A': CDS_PINID='A';
NODE_NAME     PU206 21_22
 '@S9S_MB_2U_LIB.S9S_MB_2U(SCH_1):PAGE237_I70@PURE_QUANTA.RS31312R(CHIPS)':
 'VIN_21_22': CDS_PINID='VIN_21_22';
NODE_NAME     PU206 23
 '@S9S_MB_2U_LIB.S9S_MB_2U(SCH_1):PAGE237_I70@PURE_QUANTA.RS31312R(CHIPS)':
 'VIN_23': CDS_PINID='VIN_23';
NODE_NAME     PU206 24
 '@S9S_MB_2U_LIB.S9S_MB_2U(SCH_1):PAGE237_I70@PURE_QUANTA.RS31312R(CHIPS)':
 'VIN_24': CDS_PINID='VIN_24';
NODE_NAME     PU206 25
 '@S9S_MB_2U_LIB.S9S_MB_2U(SCH_1):PAGE237_I70@PURE_QUANTA.RS31312R(CHIPS)':
 'VIN_25': CDS_PINID='VIN_25';
NODE_NAME     PU206 26
 '@S9S_MB_2U_LIB.S9S_MB_2U(SCH_1):PAGE237_I70@PURE_QUANTA.RS31312R(CHIPS)':
 'VIN_26': CDS_PINID='VIN_26';
NODE_NAME     PR3853 1
 '@S9S_MB_2U_LIB.S9S_MB_2U(SCH_1):PAGE237_I84@PURE_QUANTA.Q_RES(CHIPS)':
 'A': CDS_PINID='A';
NODE_NAME     PR3857 1
 '@S9S_MB_2U_LIB.S9S_MB_2U(SCH_1):PAGE237_I87@PURE_QUANTA.Q_RES(CHIPS)':
 'A': CDS_PINID='A';
NODE_NAME     PR3953 1
 '@S9S_MB_2U_LIB.S9S_MB_2U(SCH_1):PAGE323_I63@PURE_QUANTA.Q_RES(CHIPS)':
 'A': CDS_PINID='A';
NODE_NAME     PR3957 1
 '@S9S_MB_2U_LIB.S9S_MB_2U(SCH_1):PAGE323_I70@PURE_QUANTA.Q_RES(CHIPS)':
 'A': CDS_PINID='A';
NODE_NAME     PR3960 1
 '@S9S_MB_2U_LIB.S9S_MB_2U(SCH_1):PAGE324_I32@PURE_QUANTA.Q_RES(CHIPS)':
 'A': CDS_PINID='A';
NODE_NAME     PD114 C
 '@S9S_MB_2U_LIB.S9S_MB_2U(SCH_1):PAGE324_I84@PURE_QUANTA.DIODE_TVS(CHIPS)':
 'C':PIN_LENGTH='Short',
 CDS_PINID='C';
NODE_NAME     R3117 1
 '@S9S_MB_2U_LIB.S9S_MB_2U(SCH_1):PAGE245_I78@PURE_QUANTA.Q_RES(CHIPS)':
 'A': CDS_PINID='A';
NODE_NAME     PU9 3
 '@S9S_MB_2U_LIB.S9S_MB_2U(SCH_1):PAGE245_I95@PURE_QUANTA.IR3889MTRPBF(CHIPS)':
 'VIN': CDS_PINID='VIN';
NODE_NAME     PC1649 1
 '@S9S_MB_2U_LIB.S9S_MB_2U(SCH_1):PAGE245_I97@PURE_QUANTA.Q_CAP(CHIPS)':
 'A': CDS_PINID='A';
NODE_NAME     PL45 1
 '@S9S_MB_2U_LIB.S9S_MB_2U(SCH_1):PAGE245_I98@PURE_QUANTA.Q_INDUCTOR(CHIPS)':
 '1': CDS_PINID='\1\';
NODE_NAME     PC8 1
 '@S9S_MB_2U_LIB.S9S_MB_2U(SCH_1):PAGE245_I118@PURE_QUANTA.Q_CAP(CHIPS)':
 'A': CDS_PINID='A';
NODE_NAME     R4071 1
 '@S9S_MB_2U_LIB.S9S_MB_2U(SCH_1):PAGE229_I24@PURE_QUANTA.Q_RES(CHIPS)':
 'A': CDS_PINID='A';
NODE_NAME     PR4014 1
 '@S9S_MB_2U_LIB.S9S_MB_2U(SCH_1):PAGE229_I54@PURE_QUANTA.Q_RES(CHIPS)':
 'A': CDS_PINID='A';
NODE_NAME     PU300 A3
 '@S9S_MB_2U_LIB.S9S_MB_2U(SCH_1):PAGE229_I69@PURE_QUANTA.MAX15090BEWIT(CHIPS)':
 'IN_A3': CDS_PINID='IN_A3';
NODE_NAME     PU300 A5
 '@S9S_MB_2U_LIB.S9S_MB_2U(SCH_1):PAGE229_I69@PURE_QUANTA.MAX15090BEWIT(CHIPS)':
 'IN_A5': CDS_PINID='IN_A5';
NODE_NAME     PU300 B3
 '@S9S_MB_2U_LIB.S9S_MB_2U(SCH_1):PAGE229_I69@PURE_QUANTA.MAX15090BEWIT(CHIPS)':
 'IN_B3': CDS_PINID='IN_B3';
NODE_NAME     PU300 B5
 '@S9S_MB_2U_LIB.S9S_MB_2U(SCH_1):PAGE229_I69@PURE_QUANTA.MAX15090BEWIT(CHIPS)':
 'IN_B5': CDS_PINID='IN_B5';
NODE_NAME     PU300 C3
 '@S9S_MB_2U_LIB.S9S_MB_2U(SCH_1):PAGE229_I69@PURE_QUANTA.MAX15090BEWIT(CHIPS)':
 'IN_C3': CDS_PINID='IN_C3';
NODE_NAME     PU300 C5
 '@S9S_MB_2U_LIB.S9S_MB_2U(SCH_1):PAGE229_I69@PURE_QUANTA.MAX15090BEWIT(CHIPS)':
 'IN_C5': CDS_PINID='IN_C5';
NODE_NAME     PU300 D5
 '@S9S_MB_2U_LIB.S9S_MB_2U(SCH_1):PAGE229_I69@PURE_QUANTA.MAX15090BEWIT(CHIPS)':
 'IN_D5': CDS_PINID='IN_D5';
NODE_NAME     PU299 21_22
 '@S9S_MB_2U_LIB.S9S_MB_2U(SCH_1):PAGE229_I90@PURE_QUANTA.RS31312R(CHIPS)':
 'VIN_21_22': CDS_PINID='VIN_21_22';
NODE_NAME     PU299 23
 '@S9S_MB_2U_LIB.S9S_MB_2U(SCH_1):PAGE229_I90@PURE_QUANTA.RS31312R(CHIPS)':
 'VIN_23': CDS_PINID='VIN_23';
NODE_NAME     PU299 24
 '@S9S_MB_2U_LIB.S9S_MB_2U(SCH_1):PAGE229_I90@PURE_QUANTA.RS31312R(CHIPS)':
 'VIN_24': CDS_PINID='VIN_24';
NODE_NAME     PU299 25
 '@S9S_MB_2U_LIB.S9S_MB_2U(SCH_1):PAGE229_I90@PURE_QUANTA.RS31312R(CHIPS)':
 'VIN_25': CDS_PINID='VIN_25';
NODE_NAME     PU299 26
 '@S9S_MB_2U_LIB.S9S_MB_2U(SCH_1):PAGE229_I90@PURE_QUANTA.RS31312R(CHIPS)':
 'VIN_26': CDS_PINID='VIN_26';
NODE_NAME     PC1648 1
 '@S9S_MB_2U_LIB.S9S_MB_2U(SCH_1):PAGE244_I2@PURE_QUANTA.Q_CAP(CHIPS)':
 'A': CDS_PINID='A';
NODE_NAME     PL64 1
 '@S9S_MB_2U_LIB.S9S_MB_2U(SCH_1):PAGE244_I5@PURE_QUANTA.Q_INDUCTOR(CHIPS)':
 '1': CDS_PINID='\1\';
NODE_NAME     PL16 1
 '@S9S_MB_2U_LIB.S9S_MB_2U(SCH_1):PAGE249_I16@PURE_QUANTA.Q_INDUCTOR(CHIPS)':
 '1': CDS_PINID='\1\';
NODE_NAME     PL110 1
 '@S9S_MB_2U_LIB.S9S_MB_2U(SCH_1):PAGE248_I19@PURE_QUANTA.Q_INDUCTOR(CHIPS)':
 '1': CDS_PINID='\1\';
NODE_NAME     R1688 1
 '@S9S_MB_2U_LIB.S9S_MB_2U(SCH_1):PAGE232_I18@PURE_QUANTA.Q_RES(CHIPS)':
 'A': CDS_PINID='A';
NET_NAME
'P12V_AUX_ADC'
 '@S9S_MB_2U_LIB.S9S_MB_2U(SCH_1):P12V_AUX_ADC':
 C_SIGNAL='@s9s_mb_2u_lib.s9s_mb_2u(sch_1):p12v_aux_adc';
NODE_NAME     R1799 2
 '@S9S_MB_2U_LIB.S9S_MB_2U(SCH_1):PAGE239_I173@PURE_QUANTA.Q_RES(CHIPS)':
 'B': CDS_PINID='B';
NODE_NAME     R1800 1
 '@S9S_MB_2U_LIB.S9S_MB_2U(SCH_1):PAGE239_I174@PURE_QUANTA.Q_RES(CHIPS)':
 'A': CDS_PINID='A';
NODE_NAME     R3679 1
 '@S9S_MB_2U_LIB.S9S_MB_2U(SCH_1):PAGE239_I209@PURE_QUANTA.Q_RES(CHIPS)':
 'A': CDS_PINID='A';
NODE_NAME     R3680 1
 '@S9S_MB_2U_LIB.S9S_MB_2U(SCH_1):PAGE239_I210@PURE_QUANTA.Q_RES(CHIPS)':
 'A': CDS_PINID='A';
NET_NAME
'P12V_AUX_ADC_MAM'
 '@S9S_MB_2U_LIB.S9S_MB_2U(SCH_1):P12V_AUX_ADC_MAM':
 C_SIGNAL='@s9s_mb_2u_lib.s9s_mb_2u(sch_1):p12v_aux_adc_mam';
NODE_NAME     U193 5
 '@S9S_MB_2U_LIB.S9S_MB_2U(SCH_1):PAGE239_I57@PURE_QUANTA.MAX11617EEET(CHIPS)':
 'AIN0': CDS_PINID='AIN0';
NODE_NAME     C1344 1
 '@S9S_MB_2U_LIB.S9S_MB_2U(SCH_1):PAGE239_I205@PURE_QUANTA.Q_CAP(CHIPS)':
 'A': CDS_PINID='A';
NODE_NAME     R3679 2
 '@S9S_MB_2U_LIB.S9S_MB_2U(SCH_1):PAGE239_I209@PURE_QUANTA.Q_RES(CHIPS)':
 'B': CDS_PINID='B';
NET_NAME
'P12V_AUX_ADC_TIC'
 '@S9S_MB_2U_LIB.S9S_MB_2U(SCH_1):P12V_AUX_ADC_TIC':
 C_SIGNAL='@s9s_mb_2u_lib.s9s_mb_2u(sch_1):p12v_aux_adc_tic';
NODE_NAME     U269 16
 '@S9S_MB_2U_LIB.S9S_MB_2U(SCH_1):PAGE239_I103@PURE_QUANTA.ADC128D818CIMTXNOPB(CHIPS)':
 'IN0': CDS_PINID='IN0';
NODE_NAME     C2046 1
 '@S9S_MB_2U_LIB.S9S_MB_2U(SCH_1):PAGE239_I207@PURE_QUANTA.Q_CAP(CHIPS)':
 'A': CDS_PINID='A';
NODE_NAME     R3680 2
 '@S9S_MB_2U_LIB.S9S_MB_2U(SCH_1):PAGE239_I210@PURE_QUANTA.Q_RES(CHIPS)':
 'B': CDS_PINID='B';
NET_NAME
'P12V_AUX_BLEEDING'
 '@S9S_MB_2U_LIB.S9S_MB_2U(SCH_1):P12V_AUX_BLEEDING':
 C_SIGNAL='@s9s_mb_2u_lib.s9s_mb_2u(sch_1):p12v_aux_bleeding';
NODE_NAME     R2530 2
 '@S9S_MB_2U_LIB.S9S_MB_2U(SCH_1):PAGE234_I10@PURE_QUANTA.Q_RES(CHIPS)':
 'B': CDS_PINID='B';
NODE_NAME     Q54 D
 '@S9S_MB_2U_LIB.S9S_MB_2U(SCH_1):PAGE234_I14@PURE_QUANTA.MOSFET_NCH_GDS_ESD_PROTECTED(CHIPS)':
 'D': CDS_PINID='D';
NET_NAME
'P12V_AUX_CPU0_DIMM_ISEN_N'
 '@S9S_MB_2U_LIB.S9S_MB_2U(SCH_1):P12V_AUX_CPU0_DIMM_ISEN_N':
 C_SIGNAL='@s9s_mb_2u_lib.s9s_mb_2u(sch_1):p12v_aux_cpu0_dimm_isen_n';
NODE_NAME     PR1390 1
 '@S9S_MB_2U_LIB.S9S_MB_2U(SCH_1):PAGE264_I10@PURE_QUANTA.Q_RES(CHIPS)':
 'A': CDS_PINID='A';
NODE_NAME     R1838 4
 '@S9S_MB_2U_LIB.S9S_MB_2U(SCH_1):PAGE240_I11@PURE_QUANTA.Q_RES_4P_12(CHIPS)':
 '4': CDS_PINID='\4\';
NODE_NAME     U102 4
 '@S9S_MB_2U_LIB.S9S_MB_2U(SCH_1):PAGE240_I29@PURE_QUANTA.INA183A1IDBVR(CHIPS)':
 'IN-': CDS_PINID='\in-\';
NET_NAME
'P12V_AUX_CPU0_DIMM_ISEN_P'
 '@S9S_MB_2U_LIB.S9S_MB_2U(SCH_1):P12V_AUX_CPU0_DIMM_ISEN_P':
 C_SIGNAL='@s9s_mb_2u_lib.s9s_mb_2u(sch_1):p12v_aux_cpu0_dimm_isen_p';
NODE_NAME     PR1380 1
 '@S9S_MB_2U_LIB.S9S_MB_2U(SCH_1):PAGE264_I11@PURE_QUANTA.Q_RES(CHIPS)':
 'A': CDS_PINID='A';
NODE_NAME     R1838 3
 '@S9S_MB_2U_LIB.S9S_MB_2U(SCH_1):PAGE240_I11@PURE_QUANTA.Q_RES_4P_12(CHIPS)':
 '3': CDS_PINID='\3\';
NODE_NAME     U102 5
 '@S9S_MB_2U_LIB.S9S_MB_2U(SCH_1):PAGE240_I29@PURE_QUANTA.INA183A1IDBVR(CHIPS)':
 'IN+': CDS_PINID='\in+\';
NET_NAME
'P12V_AUX_CPU1_DIMM_ISEN_N'
 '@S9S_MB_2U_LIB.S9S_MB_2U(SCH_1):P12V_AUX_CPU1_DIMM_ISEN_N':
 C_SIGNAL='@s9s_mb_2u_lib.s9s_mb_2u(sch_1):p12v_aux_cpu1_dimm_isen_n';
NODE_NAME     U103 4
 '@S9S_MB_2U_LIB.S9S_MB_2U(SCH_1):PAGE240_I22@PURE_QUANTA.INA183A1IDBVR(CHIPS)':
 'IN-': CDS_PINID='\in-\';
NODE_NAME     PR1410 1
 '@S9S_MB_2U_LIB.S9S_MB_2U(SCH_1):PAGE282_I10@PURE_QUANTA.Q_RES(CHIPS)':
 'A': CDS_PINID='A';
NODE_NAME     R1837 4
 '@S9S_MB_2U_LIB.S9S_MB_2U(SCH_1):PAGE240_I3@PURE_QUANTA.Q_RES_4P_12(CHIPS)':
 '4': CDS_PINID='\4\';
NET_NAME
'P12V_AUX_CPU1_DIMM_ISEN_P'
 '@S9S_MB_2U_LIB.S9S_MB_2U(SCH_1):P12V_AUX_CPU1_DIMM_ISEN_P':
 C_SIGNAL='@s9s_mb_2u_lib.s9s_mb_2u(sch_1):p12v_aux_cpu1_dimm_isen_p';
NODE_NAME     U103 5
 '@S9S_MB_2U_LIB.S9S_MB_2U(SCH_1):PAGE240_I22@PURE_QUANTA.INA183A1IDBVR(CHIPS)':
 'IN+': CDS_PINID='\in+\';
NODE_NAME     PR1400 1
 '@S9S_MB_2U_LIB.S9S_MB_2U(SCH_1):PAGE282_I9@PURE_QUANTA.Q_RES(CHIPS)':
 'A': CDS_PINID='A';
NODE_NAME     R1837 3
 '@S9S_MB_2U_LIB.S9S_MB_2U(SCH_1):PAGE240_I3@PURE_QUANTA.Q_RES_4P_12(CHIPS)':
 '3': CDS_PINID='\3\';
NET_NAME
'P12V_AUX_UV_ADR_TRIGGER'
 '@S9S_MB_2U_LIB.S9S_MB_2U(SCH_1):P12V_AUX_UV_ADR_TRIGGER':
 C_SIGNAL='@s9s_mb_2u_lib.s9s_mb_2u(sch_1):p12v_aux_uv_adr_trigger';
NODE_NAME     R4775 1
 '@S9S_MB_2U_LIB.S9S_MB_2U(SCH_1):PAGE329_I2@PURE_QUANTA.Q_RES(CHIPS)':
 'A': CDS_PINID='A';
NODE_NAME     R4778 1
 '@S9S_MB_2U_LIB.S9S_MB_2U(SCH_1):PAGE329_I9@PURE_QUANTA.Q_RES(CHIPS)':
 'A': CDS_PINID='A';
NODE_NAME     U339 3
 '@S9S_MB_2U_LIB.S9S_MB_2U(SCH_1):PAGE329_I12@PURE_QUANTA.AP331AWG7(CHIPS)':
 'IN+': CDS_PINID='\in+\';
NODE_NAME     C2381 1
 '@S9S_MB_2U_LIB.S9S_MB_2U(SCH_1):PAGE329_I14@PURE_QUANTA.Q_CAP(CHIPS)':
 'A': CDS_PINID='A';
NODE_NAME     R4774 2
 '@S9S_MB_2U_LIB.S9S_MB_2U(SCH_1):PAGE329_I17@PURE_QUANTA.Q_RES(CHIPS)':
 'B': CDS_PINID='B';
NET_NAME
'P12V_AUX_UV_TRIGGER'
 '@S9S_MB_2U_LIB.S9S_MB_2U(SCH_1):P12V_AUX_UV_TRIGGER':
 C_SIGNAL='@s9s_mb_2u_lib.s9s_mb_2u(sch_1):p12v_aux_uv_trigger';
NODE_NAME     U340 3
 '@S9S_MB_2U_LIB.S9S_MB_2U(SCH_1):PAGE329_I23@PURE_QUANTA.AP331AWG7(CHIPS)':
 'IN+': CDS_PINID='\in+\';
NODE_NAME     R4779 1
 '@S9S_MB_2U_LIB.S9S_MB_2U(SCH_1):PAGE329_I31@PURE_QUANTA.Q_RES(CHIPS)':
 'A': CDS_PINID='A';
NODE_NAME     C2382 1
 '@S9S_MB_2U_LIB.S9S_MB_2U(SCH_1):PAGE329_I33@PURE_QUANTA.Q_CAP(CHIPS)':
 'A': CDS_PINID='A';
NODE_NAME     R4776 2
 '@S9S_MB_2U_LIB.S9S_MB_2U(SCH_1):PAGE329_I38@PURE_QUANTA.Q_RES(CHIPS)':
 'B': CDS_PINID='B';
NODE_NAME     R4777 1
 '@S9S_MB_2U_LIB.S9S_MB_2U(SCH_1):PAGE329_I39@PURE_QUANTA.Q_RES(CHIPS)':
 'A': CDS_PINID='A';
NET_NAME
'P12V_E1S_0'
 '@S9S_MB_2U_LIB.S9S_MB_2U(SCH_1):P12V_E1S_0':
 C_SIGNAL='@s9s_mb_2u_lib.s9s_mb_2u(sch_1):p12v_e1s_0',
 CDS_GLOBAL_NET='TRUE';
NODE_NAME     C1277 1
 '@S9S_MB_2U_LIB.S9S_MB_2U(SCH_1):PAGE297_I237@PURE_QUANTA.Q_CAP(CHIPS)':
 'A': CDS_PINID='A';
NODE_NAME     C1279 1
 '@S9S_MB_2U_LIB.S9S_MB_2U(SCH_1):PAGE297_I252@PURE_QUANTA.Q_CAP(CHIPS)':
 'A': CDS_PINID='A';
NODE_NAME     C1278 1
 '@S9S_MB_2U_LIB.S9S_MB_2U(SCH_1):PAGE297_I258@PURE_QUANTA.Q_CAP(CHIPS)':
 'A': CDS_PINID='A';
NODE_NAME     C1276 1
 '@S9S_MB_2U_LIB.S9S_MB_2U(SCH_1):PAGE297_I260@PURE_QUANTA.Q_CAP(CHIPS)':
 'A': CDS_PINID='A';
NODE_NAME     PU294 A4
 '@S9S_MB_2U_LIB.S9S_MB_2U(SCH_1):PAGE324_I62@PURE_QUANTA.MAX15090BEWIT(CHIPS)':
 'OUT_A4': CDS_PINID='OUT_A4';
NODE_NAME     PU294 B4
 '@S9S_MB_2U_LIB.S9S_MB_2U(SCH_1):PAGE324_I62@PURE_QUANTA.MAX15090BEWIT(CHIPS)':
 'OUT_B4': CDS_PINID='OUT_B4';
NODE_NAME     PU294 B6
 '@S9S_MB_2U_LIB.S9S_MB_2U(SCH_1):PAGE324_I62@PURE_QUANTA.MAX15090BEWIT(CHIPS)':
 'OUT_B6': CDS_PINID='OUT_B6';
NODE_NAME     PU294 C4
 '@S9S_MB_2U_LIB.S9S_MB_2U(SCH_1):PAGE324_I62@PURE_QUANTA.MAX15090BEWIT(CHIPS)':
 'OUT_C4': CDS_PINID='OUT_C4';
NODE_NAME     PU294 C6
 '@S9S_MB_2U_LIB.S9S_MB_2U(SCH_1):PAGE324_I62@PURE_QUANTA.MAX15090BEWIT(CHIPS)':
 'OUT_C6': CDS_PINID='OUT_C6';
NODE_NAME     PU294 D4
 '@S9S_MB_2U_LIB.S9S_MB_2U(SCH_1):PAGE324_I62@PURE_QUANTA.MAX15090BEWIT(CHIPS)':
 'OUT_D4': CDS_PINID='OUT_D4';
NODE_NAME     PU294 D6
 '@S9S_MB_2U_LIB.S9S_MB_2U(SCH_1):PAGE324_I62@PURE_QUANTA.MAX15090BEWIT(CHIPS)':
 'OUT_D6': CDS_PINID='OUT_D6';
NODE_NAME     PR4528 1
 '@S9S_MB_2U_LIB.S9S_MB_2U(SCH_1):PAGE324_I70@PURE_QUANTA.Q_RES(CHIPS)':
 'A': CDS_PINID='A';
NODE_NAME     PD112 C
 '@S9S_MB_2U_LIB.S9S_MB_2U(SCH_1):PAGE324_I71@PURE_QUANTA.SCHOTTKY_AC(CHIPS)':
 'C': CDS_PINID='C';
NODE_NAME     J90 B1
 '@S9S_MB_2U_LIB.S9S_MB_2U(SCH_1):PAGE297_I318@PURE_QUANTA.SCONN56_123276793(CHIPS)':
 'P12V_B1': CDS_PINID='P12V_B1';
NODE_NAME     J90 B2
 '@S9S_MB_2U_LIB.S9S_MB_2U(SCH_1):PAGE297_I318@PURE_QUANTA.SCONN56_123276793(CHIPS)':
 'P12V_B2': CDS_PINID='P12V_B2';
NODE_NAME     J90 B3
 '@S9S_MB_2U_LIB.S9S_MB_2U(SCH_1):PAGE297_I318@PURE_QUANTA.SCONN56_123276793(CHIPS)':
 'P12V_B3': CDS_PINID='P12V_B3';
NODE_NAME     J90 B4
 '@S9S_MB_2U_LIB.S9S_MB_2U(SCH_1):PAGE297_I318@PURE_QUANTA.SCONN56_123276793(CHIPS)':
 'P12V_B4': CDS_PINID='P12V_B4';
NODE_NAME     J90 B5
 '@S9S_MB_2U_LIB.S9S_MB_2U(SCH_1):PAGE297_I318@PURE_QUANTA.SCONN56_123276793(CHIPS)':
 'P12V_B5': CDS_PINID='P12V_B5';
NODE_NAME     J90 B6
 '@S9S_MB_2U_LIB.S9S_MB_2U(SCH_1):PAGE297_I318@PURE_QUANTA.SCONN56_123276793(CHIPS)':
 'P12V_B6': CDS_PINID='P12V_B6';
NODE_NAME     PC2214 1
 '@S9S_MB_2U_LIB.S9S_MB_2U(SCH_1):PAGE324_I69@PURE_QUANTA.Q_CAP(CHIPS)':
 'A': CDS_PINID='A';
NODE_NAME     PC2217 1
 '@S9S_MB_2U_LIB.S9S_MB_2U(SCH_1):PAGE324_I75@PURE_QUANTA.Q_CAP(CHIPS)':
 'A': CDS_PINID='A';
NODE_NAME     PC2219 1
 '@S9S_MB_2U_LIB.S9S_MB_2U(SCH_1):PAGE324_I78@PURE_QUANTA.Q_CAP(CHIPS)':
 'A': CDS_PINID='A';
NODE_NAME     PU292 13
 '@S9S_MB_2U_LIB.S9S_MB_2U(SCH_1):PAGE323_I49@PURE_QUANTA.RS31312R(CHIPS)':
 'VOUT_13': CDS_PINID='VOUT_13';
NODE_NAME     PU292 14
 '@S9S_MB_2U_LIB.S9S_MB_2U(SCH_1):PAGE323_I49@PURE_QUANTA.RS31312R(CHIPS)':
 'VOUT_14': CDS_PINID='VOUT_14';
NODE_NAME     PU292 15
 '@S9S_MB_2U_LIB.S9S_MB_2U(SCH_1):PAGE323_I49@PURE_QUANTA.RS31312R(CHIPS)':
 'VOUT_15': CDS_PINID='VOUT_15';
NODE_NAME     PU292 16
 '@S9S_MB_2U_LIB.S9S_MB_2U(SCH_1):PAGE323_I49@PURE_QUANTA.RS31312R(CHIPS)':
 'VOUT_16': CDS_PINID='VOUT_16';
NODE_NAME     PU292 17
 '@S9S_MB_2U_LIB.S9S_MB_2U(SCH_1):PAGE323_I49@PURE_QUANTA.RS31312R(CHIPS)':
 'VOUT_17': CDS_PINID='VOUT_17';
NODE_NAME     PU292 18
 '@S9S_MB_2U_LIB.S9S_MB_2U(SCH_1):PAGE323_I49@PURE_QUANTA.RS31312R(CHIPS)':
 'VOUT_18': CDS_PINID='VOUT_18';
NODE_NAME     PU292 19
 '@S9S_MB_2U_LIB.S9S_MB_2U(SCH_1):PAGE323_I49@PURE_QUANTA.RS31312R(CHIPS)':
 'VOUT_19': CDS_PINID='VOUT_19';
NODE_NAME     PU292 20
 '@S9S_MB_2U_LIB.S9S_MB_2U(SCH_1):PAGE323_I49@PURE_QUANTA.RS31312R(CHIPS)':
 'VOUT_20': CDS_PINID='VOUT_20';
NODE_NAME     PR3950 1
 '@S9S_MB_2U_LIB.S9S_MB_2U(SCH_1):PAGE323_I55@PURE_QUANTA.Q_RES(CHIPS)':
 'A': CDS_PINID='A';
NODE_NAME     PR3952 1
 '@S9S_MB_2U_LIB.S9S_MB_2U(SCH_1):PAGE323_I62@PURE_QUANTA.Q_RES(CHIPS)':
 'A': CDS_PINID='A';
NODE_NAME     PC2206 1
 '@S9S_MB_2U_LIB.S9S_MB_2U(SCH_1):PAGE323_I73@PURE_QUANTA.Q_CAP(CHIPS)':
 'A': CDS_PINID='A';
NODE_NAME     PC2280 1
 '@S9S_MB_2U_LIB.S9S_MB_2U(SCH_1):PAGE324_I79@PURE_QUANTA.Q_CAP(CHIPS)':
 'A': CDS_PINID='A';
NET_NAME
'P12V_E1S_0_EN_G'
 '@S9S_MB_2U_LIB.S9S_MB_2U(SCH_1):P12V_E1S_0_EN_G':
 C_SIGNAL='@s9s_mb_2u_lib.s9s_mb_2u(sch_1):p12v_e1s_0_en_g';
NODE_NAME     R4074 2
 '@S9S_MB_2U_LIB.S9S_MB_2U(SCH_1):PAGE324_I22@PURE_QUANTA.Q_RES(CHIPS)':
 'B': CDS_PINID='B';
NODE_NAME     Q127 6
 '@S9S_MB_2U_LIB.S9S_MB_2U(SCH_1):PAGE324_I10@PURE_QUANTA.MOSFET_NCH_DUAL(CHIPS)':
 'D1': CDS_PINID='D1';
NODE_NAME     Q127 5
 '@S9S_MB_2U_LIB.S9S_MB_2U(SCH_1):PAGE324_I24@PURE_QUANTA.MOSFET_NCH_DUAL(CHIPS)':
 'G2': CDS_PINID='G2';
NET_NAME
'P12V_E1S_0_ISENSE_MAM'
 '@S9S_MB_2U_LIB.S9S_MB_2U(SCH_1):P12V_E1S_0_ISENSE_MAM':
 C_SIGNAL='@s9s_mb_2u_lib.s9s_mb_2u(sch_1):p12v_e1s_0_isense_mam';
NODE_NAME     U193 12
 '@S9S_MB_2U_LIB.S9S_MB_2U(SCH_1):PAGE239_I57@PURE_QUANTA.MAX11617EEET(CHIPS)':
 'AIN7': CDS_PINID='AIN7';
NODE_NAME     R3939 2
 '@S9S_MB_2U_LIB.S9S_MB_2U(SCH_1):PAGE239_I330@PURE_QUANTA.Q_RES(CHIPS)':
 'B': CDS_PINID='B';
NODE_NAME     C2195 1
 '@S9S_MB_2U_LIB.S9S_MB_2U(SCH_1):PAGE239_I333@PURE_QUANTA.Q_CAP(CHIPS)':
 'A': CDS_PINID='A';
NODE_NAME     R3940 2
 '@S9S_MB_2U_LIB.S9S_MB_2U(SCH_1):PAGE239_I337@PURE_QUANTA.Q_RES(CHIPS)':
 'B': CDS_PINID='B';
NET_NAME
'P12V_E1S_0_ISENSE_MAM_MAM'
 '@S9S_MB_2U_LIB.S9S_MB_2U(SCH_1):P12V_E1S_0_ISENSE_MAM_MAM':
 C_SIGNAL='@s9s_mb_2u_lib.s9s_mb_2u(sch_1):p12v_e1s_0_isense_mam_mam';
NODE_NAME     R3974 2
 '@S9S_MB_2U_LIB.S9S_MB_2U(SCH_1):PAGE324_I67@PURE_QUANTA.Q_RES(CHIPS)':
 'B': CDS_PINID='B';
NODE_NAME     R3939 1
 '@S9S_MB_2U_LIB.S9S_MB_2U(SCH_1):PAGE239_I330@PURE_QUANTA.Q_RES(CHIPS)':
 'A': CDS_PINID='A';
NET_NAME
'P12V_E1S_0_ISENSE_MAM_TIC'
 '@S9S_MB_2U_LIB.S9S_MB_2U(SCH_1):P12V_E1S_0_ISENSE_MAM_TIC':
 C_SIGNAL='@s9s_mb_2u_lib.s9s_mb_2u(sch_1):p12v_e1s_0_isense_mam_tic';
NODE_NAME     R3941 1
 '@S9S_MB_2U_LIB.S9S_MB_2U(SCH_1):PAGE239_I338@PURE_QUANTA.Q_RES(CHIPS)':
 'A': CDS_PINID='A';
NODE_NAME     R3975 2
 '@S9S_MB_2U_LIB.S9S_MB_2U(SCH_1):PAGE324_I65@PURE_QUANTA.Q_RES(CHIPS)':
 'B': CDS_PINID='B';
NET_NAME
'P12V_E1S_0_ISENSE_MPS_MAM'
 '@S9S_MB_2U_LIB.S9S_MB_2U(SCH_1):P12V_E1S_0_ISENSE_MPS_MAM':
 C_SIGNAL='@s9s_mb_2u_lib.s9s_mb_2u(sch_1):p12v_e1s_0_isense_mps_mam';
NODE_NAME     R3940 1
 '@S9S_MB_2U_LIB.S9S_MB_2U(SCH_1):PAGE239_I337@PURE_QUANTA.Q_RES(CHIPS)':
 'A': CDS_PINID='A';
NODE_NAME     R3955 2
 '@S9S_MB_2U_LIB.S9S_MB_2U(SCH_1):PAGE323_I67@PURE_QUANTA.Q_RES(CHIPS)':
 'B': CDS_PINID='B';
NET_NAME
'P12V_E1S_0_ISENSE_MPS_TIC'
 '@S9S_MB_2U_LIB.S9S_MB_2U(SCH_1):P12V_E1S_0_ISENSE_MPS_TIC':
 C_SIGNAL='@s9s_mb_2u_lib.s9s_mb_2u(sch_1):p12v_e1s_0_isense_mps_tic';
NODE_NAME     R3942 1
 '@S9S_MB_2U_LIB.S9S_MB_2U(SCH_1):PAGE239_I339@PURE_QUANTA.Q_RES(CHIPS)':
 'A': CDS_PINID='A';
NODE_NAME     R3956 2
 '@S9S_MB_2U_LIB.S9S_MB_2U(SCH_1):PAGE323_I66@PURE_QUANTA.Q_RES(CHIPS)':
 'B': CDS_PINID='B';
NET_NAME
'P12V_E1S_0_ISENSE_TIC'
 '@S9S_MB_2U_LIB.S9S_MB_2U(SCH_1):P12V_E1S_0_ISENSE_TIC':
 C_SIGNAL='@s9s_mb_2u_lib.s9s_mb_2u(sch_1):p12v_e1s_0_isense_tic';
NODE_NAME     U269 9
 '@S9S_MB_2U_LIB.S9S_MB_2U(SCH_1):PAGE239_I103@PURE_QUANTA.ADC128D818CIMTXNOPB(CHIPS)':
 'IN7': CDS_PINID='IN7';
NODE_NAME     C2194 1
 '@S9S_MB_2U_LIB.S9S_MB_2U(SCH_1):PAGE239_I336@PURE_QUANTA.Q_CAP(CHIPS)':
 'A': CDS_PINID='A';
NODE_NAME     R3941 2
 '@S9S_MB_2U_LIB.S9S_MB_2U(SCH_1):PAGE239_I338@PURE_QUANTA.Q_RES(CHIPS)':
 'B': CDS_PINID='B';
NODE_NAME     R3942 2
 '@S9S_MB_2U_LIB.S9S_MB_2U(SCH_1):PAGE239_I339@PURE_QUANTA.Q_RES(CHIPS)':
 'B': CDS_PINID='B';
NET_NAME
'P12V_E1S_AVIN_PD_0'
 '@S9S_MB_2U_LIB.S9S_MB_2U(SCH_1):P12V_E1S_AVIN_PD_0':
 C_SIGNAL='@s9s_mb_2u_lib.s9s_mb_2u(sch_1):p12v_e1s_avin_pd_0';
NODE_NAME     PU292 12
 '@S9S_MB_2U_LIB.S9S_MB_2U(SCH_1):PAGE323_I49@PURE_QUANTA.RS31312R(CHIPS)':
 'AVIN': CDS_PINID='AVIN';
NODE_NAME     PR3950 2
 '@S9S_MB_2U_LIB.S9S_MB_2U(SCH_1):PAGE323_I55@PURE_QUANTA.Q_RES(CHIPS)':
 'B': CDS_PINID='B';
NODE_NAME     PC2205 1
 '@S9S_MB_2U_LIB.S9S_MB_2U(SCH_1):PAGE323_I69@PURE_QUANTA.Q_CAP(CHIPS)':
 'A': CDS_PINID='A';
NODE_NAME     PR3957 2
 '@S9S_MB_2U_LIB.S9S_MB_2U(SCH_1):PAGE323_I70@PURE_QUANTA.Q_RES(CHIPS)':
 'B': CDS_PINID='B';
NET_NAME
'P12V_E1S_CB_0'
 '@S9S_MB_2U_LIB.S9S_MB_2U(SCH_1):P12V_E1S_CB_0':
 C_SIGNAL='@s9s_mb_2u_lib.s9s_mb_2u(sch_1):p12v_e1s_cb_0';
NODE_NAME     PU294 B1
 '@S9S_MB_2U_LIB.S9S_MB_2U(SCH_1):PAGE324_I62@PURE_QUANTA.MAX15090BEWIT(CHIPS)':
 'CB': CDS_PINID='CB';
NODE_NAME     PR3968 1
 '@S9S_MB_2U_LIB.S9S_MB_2U(SCH_1):PAGE324_I59@PURE_QUANTA.Q_RES(CHIPS)':
 'A': CDS_PINID='A';
NET_NAME
'P12V_E1S_EN_0_R'
 '@S9S_MB_2U_LIB.S9S_MB_2U(SCH_1):P12V_E1S_EN_0_R':
 C_SIGNAL='@s9s_mb_2u_lib.s9s_mb_2u(sch_1):p12v_e1s_en_0_r';
NODE_NAME     R4064 2
 '@S9S_MB_2U_LIB.S9S_MB_2U(SCH_1):PAGE324_I21@PURE_QUANTA.Q_RES(CHIPS)':
 'B': CDS_PINID='B';
NODE_NAME     R4073 1
 '@S9S_MB_2U_LIB.S9S_MB_2U(SCH_1):PAGE324_I9@PURE_QUANTA.Q_RES(CHIPS)':
 'A': CDS_PINID='A';
NODE_NAME     Q127 2
 '@S9S_MB_2U_LIB.S9S_MB_2U(SCH_1):PAGE324_I10@PURE_QUANTA.MOSFET_NCH_DUAL(CHIPS)':
 'G1': CDS_PINID='G1';
NET_NAME
'P12V_E1S_EN_0_R2'
 '@S9S_MB_2U_LIB.S9S_MB_2U(SCH_1):P12V_E1S_EN_0_R2':
 C_SIGNAL='@s9s_mb_2u_lib.s9s_mb_2u(sch_1):p12v_e1s_en_0_r2';
NODE_NAME     R3943 2
 '@S9S_MB_2U_LIB.S9S_MB_2U(SCH_1):PAGE323_I45@PURE_QUANTA.Q_RES(CHIPS)':
 'B': CDS_PINID='B';
NODE_NAME     PU292 1
 '@S9S_MB_2U_LIB.S9S_MB_2U(SCH_1):PAGE323_I49@PURE_QUANTA.RS31312R(CHIPS)':
 'EN': CDS_PINID='EN';
NET_NAME
'P12V_E1S_FAULT_0'
 '@S9S_MB_2U_LIB.S9S_MB_2U(SCH_1):P12V_E1S_FAULT_0':
 C_SIGNAL='@s9s_mb_2u_lib.s9s_mb_2u(sch_1):p12v_e1s_fault_0';
NODE_NAME     PU294 C7
 '@S9S_MB_2U_LIB.S9S_MB_2U(SCH_1):PAGE324_I62@PURE_QUANTA.MAX15090BEWIT(CHIPS)':
 'FAULT#': CDS_PINID='\fault#\';
NODE_NAME     R3976 2
 '@S9S_MB_2U_LIB.S9S_MB_2U(SCH_1):PAGE324_I73@PURE_QUANTA.Q_RES(CHIPS)':
 'B': CDS_PINID='B';
NET_NAME
'P12V_E1S_FLTB_0'
 '@S9S_MB_2U_LIB.S9S_MB_2U(SCH_1):P12V_E1S_FLTB_0':
 C_SIGNAL='@s9s_mb_2u_lib.s9s_mb_2u(sch_1):p12v_e1s_fltb_0';
NODE_NAME     PU292 9
 '@S9S_MB_2U_LIB.S9S_MB_2U(SCH_1):PAGE323_I49@PURE_QUANTA.RS31312R(CHIPS)':
 'FLTB': CDS_PINID='FLTB';
NODE_NAME     PR3951 1
 '@S9S_MB_2U_LIB.S9S_MB_2U(SCH_1):PAGE323_I54@PURE_QUANTA.Q_RES(CHIPS)':
 'A': CDS_PINID='A';
NET_NAME
'P12V_E1S_GATE_0'
 '@S9S_MB_2U_LIB.S9S_MB_2U(SCH_1):P12V_E1S_GATE_0':
 C_SIGNAL='@s9s_mb_2u_lib.s9s_mb_2u(sch_1):p12v_e1s_gate_0';
NODE_NAME     PU294 A6
 '@S9S_MB_2U_LIB.S9S_MB_2U(SCH_1):PAGE324_I62@PURE_QUANTA.MAX15090BEWIT(CHIPS)':
 'GATE': CDS_PINID='GATE';
NODE_NAME     PR4528 2
 '@S9S_MB_2U_LIB.S9S_MB_2U(SCH_1):PAGE324_I70@PURE_QUANTA.Q_RES(CHIPS)':
 'B': CDS_PINID='B';
NODE_NAME     PC2215 1
 '@S9S_MB_2U_LIB.S9S_MB_2U(SCH_1):PAGE324_I66@PURE_QUANTA.Q_CAP(CHIPS)':
 'A': CDS_PINID='A';
NODE_NAME     PC2214 2
 '@S9S_MB_2U_LIB.S9S_MB_2U(SCH_1):PAGE324_I69@PURE_QUANTA.Q_CAP(CHIPS)':
 'B': CDS_PINID='B';
NET_NAME
'P12V_E1S_IMON_0'
 '@S9S_MB_2U_LIB.S9S_MB_2U(SCH_1):P12V_E1S_IMON_0':
 C_SIGNAL='@s9s_mb_2u_lib.s9s_mb_2u(sch_1):p12v_e1s_imon_0';
NODE_NAME     PU292 8
 '@S9S_MB_2U_LIB.S9S_MB_2U(SCH_1):PAGE323_I49@PURE_QUANTA.RS31312R(CHIPS)':
 'IMON': CDS_PINID='IMON';
NODE_NAME     PC2202 1
 '@S9S_MB_2U_LIB.S9S_MB_2U(SCH_1):PAGE323_I56@PURE_QUANTA.Q_CAP(CHIPS)':
 'A': CDS_PINID='A';
NODE_NAME     PR3949 1
 '@S9S_MB_2U_LIB.S9S_MB_2U(SCH_1):PAGE323_I53@PURE_QUANTA.Q_RES(CHIPS)':
 'A': CDS_PINID='A';
NODE_NAME     R3956 1
 '@S9S_MB_2U_LIB.S9S_MB_2U(SCH_1):PAGE323_I66@PURE_QUANTA.Q_RES(CHIPS)':
 'A': CDS_PINID='A';
NODE_NAME     R3955 1
 '@S9S_MB_2U_LIB.S9S_MB_2U(SCH_1):PAGE323_I67@PURE_QUANTA.Q_RES(CHIPS)':
 'A': CDS_PINID='A';
NET_NAME
'P12V_E1S_ISET_0'
 '@S9S_MB_2U_LIB.S9S_MB_2U(SCH_1):P12V_E1S_ISET_0':
 C_SIGNAL='@s9s_mb_2u_lib.s9s_mb_2u(sch_1):p12v_e1s_iset_0';
NODE_NAME     PR3944 1
 '@S9S_MB_2U_LIB.S9S_MB_2U(SCH_1):PAGE323_I40@PURE_QUANTA.Q_RES(CHIPS)':
 'A': CDS_PINID='A';
NODE_NAME     PU292 5
 '@S9S_MB_2U_LIB.S9S_MB_2U(SCH_1):PAGE323_I49@PURE_QUANTA.RS31312R(CHIPS)':
 'ISET': CDS_PINID='ISET';
NODE_NAME     PR4541 1
 '@S9S_MB_2U_LIB.S9S_MB_2U(SCH_1):PAGE323_I43@PURE_QUANTA.Q_RES(CHIPS)':
 'A': CDS_PINID='A';
NET_NAME
'P12V_E1S_ISET_0_R'
 '@S9S_MB_2U_LIB.S9S_MB_2U(SCH_1):P12V_E1S_ISET_0_R':
 C_SIGNAL='@s9s_mb_2u_lib.s9s_mb_2u(sch_1):p12v_e1s_iset_0_r';
NODE_NAME     PC2341 1
 '@S9S_MB_2U_LIB.S9S_MB_2U(SCH_1):PAGE323_I42@PURE_QUANTA.Q_CAP(CHIPS)':
 'A': CDS_PINID='A';
NODE_NAME     PR4541 2
 '@S9S_MB_2U_LIB.S9S_MB_2U(SCH_1):PAGE323_I43@PURE_QUANTA.Q_RES(CHIPS)':
 'B': CDS_PINID='B';
NET_NAME
'P12V_E1S_OV_0'
 '@S9S_MB_2U_LIB.S9S_MB_2U(SCH_1):P12V_E1S_OV_0':
 C_SIGNAL='@s9s_mb_2u_lib.s9s_mb_2u(sch_1):p12v_e1s_ov_0';
NODE_NAME     PU294 D3
 '@S9S_MB_2U_LIB.S9S_MB_2U(SCH_1):PAGE324_I62@PURE_QUANTA.MAX15090BEWIT(CHIPS)':
 'OV': CDS_PINID='OV';
NODE_NAME     PR3962 1
 '@S9S_MB_2U_LIB.S9S_MB_2U(SCH_1):PAGE324_I28@PURE_QUANTA.Q_RES(CHIPS)':
 'A': CDS_PINID='A';
NODE_NAME     PR3961 2
 '@S9S_MB_2U_LIB.S9S_MB_2U(SCH_1):PAGE324_I85@PURE_QUANTA.Q_RES(CHIPS)':
 'B': CDS_PINID='B';
NET_NAME
'P12V_E1S_OV_FB_0'
 '@S9S_MB_2U_LIB.S9S_MB_2U(SCH_1):P12V_E1S_OV_FB_0':
 C_SIGNAL='@s9s_mb_2u_lib.s9s_mb_2u(sch_1):p12v_e1s_ov_fb_0';
NODE_NAME     PU292 11
 '@S9S_MB_2U_LIB.S9S_MB_2U(SCH_1):PAGE323_I49@PURE_QUANTA.RS31312R(CHIPS)':
 'OV': CDS_PINID='OV';
NODE_NAME     PR3954 1
 '@S9S_MB_2U_LIB.S9S_MB_2U(SCH_1):PAGE323_I58@PURE_QUANTA.Q_RES(CHIPS)':
 'A': CDS_PINID='A';
NODE_NAME     PR3952 2
 '@S9S_MB_2U_LIB.S9S_MB_2U(SCH_1):PAGE323_I62@PURE_QUANTA.Q_RES(CHIPS)':
 'B': CDS_PINID='B';
NODE_NAME     PR3953 2
 '@S9S_MB_2U_LIB.S9S_MB_2U(SCH_1):PAGE323_I63@PURE_QUANTA.Q_RES(CHIPS)':
 'B': CDS_PINID='B';
NET_NAME
'P12V_E1S_PWRGD_0'
 '@S9S_MB_2U_LIB.S9S_MB_2U(SCH_1):P12V_E1S_PWRGD_0':
 C_SIGNAL='@s9s_mb_2u_lib.s9s_mb_2u(sch_1):p12v_e1s_pwrgd_0';
NODE_NAME     PU294 D7
 '@S9S_MB_2U_LIB.S9S_MB_2U(SCH_1):PAGE324_I62@PURE_QUANTA.MAX15090BEWIT(CHIPS)':
 'PG': CDS_PINID='PG';
NODE_NAME     R3972 1
 '@S9S_MB_2U_LIB.S9S_MB_2U(SCH_1):PAGE324_I68@PURE_QUANTA.Q_RES(CHIPS)':
 'A': CDS_PINID='A';
NET_NAME
'P12V_E1S_REG_0'
 '@S9S_MB_2U_LIB.S9S_MB_2U(SCH_1):P12V_E1S_REG_0':
 C_SIGNAL='@s9s_mb_2u_lib.s9s_mb_2u(sch_1):p12v_e1s_reg_0';
NODE_NAME     PU294 D1
 '@S9S_MB_2U_LIB.S9S_MB_2U(SCH_1):PAGE324_I62@PURE_QUANTA.MAX15090BEWIT(CHIPS)':
 'REG': CDS_PINID='REG';
NODE_NAME     PC2211 2
 '@S9S_MB_2U_LIB.S9S_MB_2U(SCH_1):PAGE324_I57@PURE_QUANTA.Q_CAP(CHIPS)':
 'B': CDS_PINID='B';
NET_NAME
'P12V_E1S_SENSE_0'
 '@S9S_MB_2U_LIB.S9S_MB_2U(SCH_1):P12V_E1S_SENSE_0':
 C_SIGNAL='@s9s_mb_2u_lib.s9s_mb_2u(sch_1):p12v_e1s_sense_0';
NODE_NAME     PU294 A1
 '@S9S_MB_2U_LIB.S9S_MB_2U(SCH_1):PAGE324_I62@PURE_QUANTA.MAX15090BEWIT(CHIPS)':
 'ISENSE': CDS_PINID='ISENSE';
NODE_NAME     R3974 1
 '@S9S_MB_2U_LIB.S9S_MB_2U(SCH_1):PAGE324_I67@PURE_QUANTA.Q_RES(CHIPS)':
 'A': CDS_PINID='A';
NODE_NAME     R3975 1
 '@S9S_MB_2U_LIB.S9S_MB_2U(SCH_1):PAGE324_I65@PURE_QUANTA.Q_RES(CHIPS)':
 'A': CDS_PINID='A';
NODE_NAME     PR3970 1
 '@S9S_MB_2U_LIB.S9S_MB_2U(SCH_1):PAGE324_I64@PURE_QUANTA.Q_RES(CHIPS)':
 'A': CDS_PINID='A';
NET_NAME
'P12V_E1S_SS_0'
 '@S9S_MB_2U_LIB.S9S_MB_2U(SCH_1):P12V_E1S_SS_0':
 C_SIGNAL='@s9s_mb_2u_lib.s9s_mb_2u(sch_1):p12v_e1s_ss_0';
NODE_NAME     PC2281 1
 '@S9S_MB_2U_LIB.S9S_MB_2U(SCH_1):PAGE323_I47@PURE_QUANTA.Q_CAP(CHIPS)':
 'A': CDS_PINID='A';
NODE_NAME     PU292 6
 '@S9S_MB_2U_LIB.S9S_MB_2U(SCH_1):PAGE323_I49@PURE_QUANTA.RS31312R(CHIPS)':
 'SS': CDS_PINID='SS';
NET_NAME
'P12V_E1S_TIMER_0'
 '@S9S_MB_2U_LIB.S9S_MB_2U(SCH_1):P12V_E1S_TIMER_0':
 C_SIGNAL='@s9s_mb_2u_lib.s9s_mb_2u(sch_1):p12v_e1s_timer_0';
NODE_NAME     PC2196 1
 '@S9S_MB_2U_LIB.S9S_MB_2U(SCH_1):PAGE323_I37@PURE_QUANTA.Q_CAP(CHIPS)':
 'A': CDS_PINID='A';
NODE_NAME     PU292 4
 '@S9S_MB_2U_LIB.S9S_MB_2U(SCH_1):PAGE323_I49@PURE_QUANTA.RS31312R(CHIPS)':
 'TIMER': CDS_PINID='TIMER';
NET_NAME
'P12V_E1S_UV_0'
 '@S9S_MB_2U_LIB.S9S_MB_2U(SCH_1):P12V_E1S_UV_0':
 C_SIGNAL='@s9s_mb_2u_lib.s9s_mb_2u(sch_1):p12v_e1s_uv_0';
NODE_NAME     PU294 D2
 '@S9S_MB_2U_LIB.S9S_MB_2U(SCH_1):PAGE324_I62@PURE_QUANTA.MAX15090BEWIT(CHIPS)':
 'UV': CDS_PINID='UV';
NODE_NAME     R3958 2
 '@S9S_MB_2U_LIB.S9S_MB_2U(SCH_1):PAGE324_I26@PURE_QUANTA.Q_RES(CHIPS)':
 'B': CDS_PINID='B';
NODE_NAME     PR3960 2
 '@S9S_MB_2U_LIB.S9S_MB_2U(SCH_1):PAGE324_I32@PURE_QUANTA.Q_RES(CHIPS)':
 'B': CDS_PINID='B';
NODE_NAME     PR3961 1
 '@S9S_MB_2U_LIB.S9S_MB_2U(SCH_1):PAGE324_I85@PURE_QUANTA.Q_RES(CHIPS)':
 'A': CDS_PINID='A';
NET_NAME
'P12V_E1S_UV_0_R'
 '@S9S_MB_2U_LIB.S9S_MB_2U(SCH_1):P12V_E1S_UV_0_R':
 C_SIGNAL='@s9s_mb_2u_lib.s9s_mb_2u(sch_1):p12v_e1s_uv_0_r';
NODE_NAME     Q127 3
 '@S9S_MB_2U_LIB.S9S_MB_2U(SCH_1):PAGE324_I24@PURE_QUANTA.MOSFET_NCH_DUAL(CHIPS)':
 'D2': CDS_PINID='D2';
NODE_NAME     R3958 1
 '@S9S_MB_2U_LIB.S9S_MB_2U(SCH_1):PAGE324_I26@PURE_QUANTA.Q_RES(CHIPS)':
 'A': CDS_PINID='A';
NET_NAME
'P12V_E1S_VCC_0'
 '@S9S_MB_2U_LIB.S9S_MB_2U(SCH_1):P12V_E1S_VCC_0':
 C_SIGNAL='@s9s_mb_2u_lib.s9s_mb_2u(sch_1):p12v_e1s_vcc_0';
NODE_NAME     PR3966 2
 '@S9S_MB_2U_LIB.S9S_MB_2U(SCH_1):PAGE324_I61@PURE_QUANTA.Q_RES(CHIPS)':
 'B': CDS_PINID='B';
NODE_NAME     PU294 A2
 '@S9S_MB_2U_LIB.S9S_MB_2U(SCH_1):PAGE324_I62@PURE_QUANTA.MAX15090BEWIT(CHIPS)':
 'VCC': CDS_PINID='VCC';
NODE_NAME     PC2209 1
 '@S9S_MB_2U_LIB.S9S_MB_2U(SCH_1):PAGE324_I60@PURE_QUANTA.Q_CAP(CHIPS)':
 'A': CDS_PINID='A';
NET_NAME
'P12V_HSC_ADC_N'
 '@S9S_MB_2U_LIB.S9S_MB_2U(SCH_1):P12V_HSC_ADC_N':
 C_SIGNAL='@s9s_mb_2u_lib.s9s_mb_2u(sch_1):p12v_hsc_adc_n';
NODE_NAME     PJ42 6
 '@S9S_MB_2U_LIB.S9S_MB_2U(SCH_1):PAGE327_I34@PURE_QUANTA.SCONN21_9193031121LF(CHIPS)':
 '6': CDS_PINID='\6\';
NODE_NAME     PR2517 1
 '@S9S_MB_2U_LIB.S9S_MB_2U(SCH_1):PAGE328_I90@PURE_QUANTA.Q_RES(CHIPS)':
 'A': CDS_PINID='A';
NODE_NAME     PR2518 1
 '@S9S_MB_2U_LIB.S9S_MB_2U(SCH_1):PAGE328_I91@PURE_QUANTA.Q_RES(CHIPS)':
 'A': CDS_PINID='A';
NODE_NAME     PR2519 1
 '@S9S_MB_2U_LIB.S9S_MB_2U(SCH_1):PAGE328_I92@PURE_QUANTA.Q_RES(CHIPS)':
 'A': CDS_PINID='A';
NODE_NAME     PR2515 1
 '@S9S_MB_2U_LIB.S9S_MB_2U(SCH_1):PAGE328_I93@PURE_QUANTA.Q_RES(CHIPS)':
 'A': CDS_PINID='A';
NODE_NAME     PR2516 1
 '@S9S_MB_2U_LIB.S9S_MB_2U(SCH_1):PAGE328_I94@PURE_QUANTA.Q_RES(CHIPS)':
 'A': CDS_PINID='A';
NET_NAME
'P12V_HSC_ADC_P'
 '@S9S_MB_2U_LIB.S9S_MB_2U(SCH_1):P12V_HSC_ADC_P':
 C_SIGNAL='@s9s_mb_2u_lib.s9s_mb_2u(sch_1):p12v_hsc_adc_p';
NODE_NAME     PJ42 7
 '@S9S_MB_2U_LIB.S9S_MB_2U(SCH_1):PAGE327_I34@PURE_QUANTA.SCONN21_9193031121LF(CHIPS)':
 '7': CDS_PINID='\7\';
NODE_NAME     PR2513 1
 '@S9S_MB_2U_LIB.S9S_MB_2U(SCH_1):PAGE328_I95@PURE_QUANTA.Q_RES(CHIPS)':
 'A': CDS_PINID='A';
NODE_NAME     PR2512 1
 '@S9S_MB_2U_LIB.S9S_MB_2U(SCH_1):PAGE328_I96@PURE_QUANTA.Q_RES(CHIPS)':
 'A': CDS_PINID='A';
NODE_NAME     PR2514 1
 '@S9S_MB_2U_LIB.S9S_MB_2U(SCH_1):PAGE328_I97@PURE_QUANTA.Q_RES(CHIPS)':
 'A': CDS_PINID='A';
NODE_NAME     PR2510 1
 '@S9S_MB_2U_LIB.S9S_MB_2U(SCH_1):PAGE328_I98@PURE_QUANTA.Q_RES(CHIPS)':
 'A': CDS_PINID='A';
NODE_NAME     PR2511 1
 '@S9S_MB_2U_LIB.S9S_MB_2U(SCH_1):PAGE328_I99@PURE_QUANTA.Q_RES(CHIPS)':
 'A': CDS_PINID='A';
NET_NAME
'P12V_HSC_GATE1'
 '@S9S_MB_2U_LIB.S9S_MB_2U(SCH_1):P12V_HSC_GATE1':
 C_SIGNAL='@s9s_mb_2u_lib.s9s_mb_2u(sch_1):p12v_hsc_gate1';
NODE_NAME     PR2538 2
 '@S9S_MB_2U_LIB.S9S_MB_2U(SCH_1):PAGE328_I76@PURE_QUANTA.Q_RES(CHIPS)':
 'B': CDS_PINID='B';
NODE_NAME     PJ42 8
 '@S9S_MB_2U_LIB.S9S_MB_2U(SCH_1):PAGE327_I34@PURE_QUANTA.SCONN21_9193031121LF(CHIPS)':
 '8': CDS_PINID='\8\';
NET_NAME
'P12V_HSC_GATE2'
 '@S9S_MB_2U_LIB.S9S_MB_2U(SCH_1):P12V_HSC_GATE2':
 C_SIGNAL='@s9s_mb_2u_lib.s9s_mb_2u(sch_1):p12v_hsc_gate2';
NODE_NAME     PR2528 2
 '@S9S_MB_2U_LIB.S9S_MB_2U(SCH_1):PAGE328_I16@PURE_QUANTA.Q_RES(CHIPS)':
 'B': CDS_PINID='B';
NODE_NAME     PR2529 2
 '@S9S_MB_2U_LIB.S9S_MB_2U(SCH_1):PAGE328_I38@PURE_QUANTA.Q_RES(CHIPS)':
 'B': CDS_PINID='B';
NODE_NAME     PR2530 2
 '@S9S_MB_2U_LIB.S9S_MB_2U(SCH_1):PAGE328_I39@PURE_QUANTA.Q_RES(CHIPS)':
 'B': CDS_PINID='B';
NODE_NAME     PR2531 2
 '@S9S_MB_2U_LIB.S9S_MB_2U(SCH_1):PAGE328_I59@PURE_QUANTA.Q_RES(CHIPS)':
 'B': CDS_PINID='B';
NODE_NAME     PR2535 2
 '@S9S_MB_2U_LIB.S9S_MB_2U(SCH_1):PAGE328_I60@PURE_QUANTA.Q_RES(CHIPS)':
 'B': CDS_PINID='B';
NODE_NAME     PR2536 2
 '@S9S_MB_2U_LIB.S9S_MB_2U(SCH_1):PAGE328_I61@PURE_QUANTA.Q_RES(CHIPS)':
 'B': CDS_PINID='B';
NODE_NAME     PC1750 2
 '@S9S_MB_2U_LIB.S9S_MB_2U(SCH_1):PAGE328_I68@PURE_QUANTA.Q_CAP(CHIPS)':
 'B': CDS_PINID='B';
NODE_NAME     PC1751 2
 '@S9S_MB_2U_LIB.S9S_MB_2U(SCH_1):PAGE328_I69@PURE_QUANTA.Q_CAP(CHIPS)':
 'B': CDS_PINID='B';
NODE_NAME     PJ42 9
 '@S9S_MB_2U_LIB.S9S_MB_2U(SCH_1):PAGE327_I34@PURE_QUANTA.SCONN21_9193031121LF(CHIPS)':
 '9': CDS_PINID='\9\';
NET_NAME
'P12V_HSC_GATE_G1'
 '@S9S_MB_2U_LIB.S9S_MB_2U(SCH_1):P12V_HSC_GATE_G1':
 C_SIGNAL='@s9s_mb_2u_lib.s9s_mb_2u(sch_1):p12v_hsc_gate_g1';
NODE_NAME     PR2528 1
 '@S9S_MB_2U_LIB.S9S_MB_2U(SCH_1):PAGE328_I16@PURE_QUANTA.Q_RES(CHIPS)':
 'A': CDS_PINID='A';
NODE_NAME     PPQ5 4
 '@S9S_MB_2U_LIB.S9S_MB_2U(SCH_1):PAGE328_I35@PURE_QUANTA.MOSFET_NCH_1D3S(CHIPS)':
 '4': CDS_PINID='\4\';
NET_NAME
'P12V_HSC_GATE_G2'
 '@S9S_MB_2U_LIB.S9S_MB_2U(SCH_1):P12V_HSC_GATE_G2':
 C_SIGNAL='@s9s_mb_2u_lib.s9s_mb_2u(sch_1):p12v_hsc_gate_g2';
NODE_NAME     PR2529 1
 '@S9S_MB_2U_LIB.S9S_MB_2U(SCH_1):PAGE328_I38@PURE_QUANTA.Q_RES(CHIPS)':
 'A': CDS_PINID='A';
NODE_NAME     PPQ6 4
 '@S9S_MB_2U_LIB.S9S_MB_2U(SCH_1):PAGE328_I40@PURE_QUANTA.MOSFET_NCH_1D3S(CHIPS)':
 '4': CDS_PINID='\4\';
NET_NAME
'P12V_HSC_GATE_G3'
 '@S9S_MB_2U_LIB.S9S_MB_2U(SCH_1):P12V_HSC_GATE_G3':
 C_SIGNAL='@s9s_mb_2u_lib.s9s_mb_2u(sch_1):p12v_hsc_gate_g3';
NODE_NAME     PR2530 1
 '@S9S_MB_2U_LIB.S9S_MB_2U(SCH_1):PAGE328_I39@PURE_QUANTA.Q_RES(CHIPS)':
 'A': CDS_PINID='A';
NODE_NAME     PPQ7 4
 '@S9S_MB_2U_LIB.S9S_MB_2U(SCH_1):PAGE328_I41@PURE_QUANTA.MOSFET_NCH_1D3S(CHIPS)':
 '4': CDS_PINID='\4\';
NET_NAME
'P12V_HSC_GATE_G4'
 '@S9S_MB_2U_LIB.S9S_MB_2U(SCH_1):P12V_HSC_GATE_G4':
 C_SIGNAL='@s9s_mb_2u_lib.s9s_mb_2u(sch_1):p12v_hsc_gate_g4';
NODE_NAME     PR2531 1
 '@S9S_MB_2U_LIB.S9S_MB_2U(SCH_1):PAGE328_I59@PURE_QUANTA.Q_RES(CHIPS)':
 'A': CDS_PINID='A';
NODE_NAME     PPQ8 4
 '@S9S_MB_2U_LIB.S9S_MB_2U(SCH_1):PAGE328_I62@PURE_QUANTA.MOSFET_NCH_1D3S(CHIPS)':
 '4': CDS_PINID='\4\';
NET_NAME
'P12V_HSC_GATE_G5'
 '@S9S_MB_2U_LIB.S9S_MB_2U(SCH_1):P12V_HSC_GATE_G5':
 C_SIGNAL='@s9s_mb_2u_lib.s9s_mb_2u(sch_1):p12v_hsc_gate_g5';
NODE_NAME     PR2535 1
 '@S9S_MB_2U_LIB.S9S_MB_2U(SCH_1):PAGE328_I60@PURE_QUANTA.Q_RES(CHIPS)':
 'A': CDS_PINID='A';
NODE_NAME     PPQ1 4
 '@S9S_MB_2U_LIB.S9S_MB_2U(SCH_1):PAGE328_I65@PURE_QUANTA.MOSFET_NCH_1D3S(CHIPS)':
 '4': CDS_PINID='\4\';
NET_NAME
'P12V_HSC_GATE_G6'
 '@S9S_MB_2U_LIB.S9S_MB_2U(SCH_1):P12V_HSC_GATE_G6':
 C_SIGNAL='@s9s_mb_2u_lib.s9s_mb_2u(sch_1):p12v_hsc_gate_g6';
NODE_NAME     PR2536 1
 '@S9S_MB_2U_LIB.S9S_MB_2U(SCH_1):PAGE328_I61@PURE_QUANTA.Q_RES(CHIPS)':
 'A': CDS_PINID='A';
NODE_NAME     PPQ2 4
 '@S9S_MB_2U_LIB.S9S_MB_2U(SCH_1):PAGE328_I73@PURE_QUANTA.MOSFET_NCH_1D3S(CHIPS)':
 '4': CDS_PINID='\4\';
NET_NAME
'P12V_HSC_GATE_RC'
 '@S9S_MB_2U_LIB.S9S_MB_2U(SCH_1):P12V_HSC_GATE_RC':
 C_SIGNAL='@s9s_mb_2u_lib.s9s_mb_2u(sch_1):p12v_hsc_gate_rc';
NODE_NAME     PC1751 1
 '@S9S_MB_2U_LIB.S9S_MB_2U(SCH_1):PAGE328_I69@PURE_QUANTA.Q_CAP(CHIPS)':
 'A': CDS_PINID='A';
NODE_NAME     PR2537 2
 '@S9S_MB_2U_LIB.S9S_MB_2U(SCH_1):PAGE328_I70@PURE_QUANTA.Q_RES(CHIPS)':
 'B': CDS_PINID='B';
NET_NAME
'P12V_HSC_SENSE1_N'
 '@S9S_MB_2U_LIB.S9S_MB_2U(SCH_1):P12V_HSC_SENSE1_N':
 C_SIGNAL='@s9s_mb_2u_lib.s9s_mb_2u(sch_1):p12v_hsc_sense1_n';
NODE_NAME     PJ42 3
 '@S9S_MB_2U_LIB.S9S_MB_2U(SCH_1):PAGE327_I34@PURE_QUANTA.SCONN21_9193031121LF(CHIPS)':
 '3': CDS_PINID='\3\';
NODE_NAME     PR2519 2
 '@S9S_MB_2U_LIB.S9S_MB_2U(SCH_1):PAGE328_I92@PURE_QUANTA.Q_RES(CHIPS)':
 'B': CDS_PINID='B';
NODE_NAME     PR3 4
 '@S9S_MB_2U_LIB.S9S_MB_2U(SCH_1):PAGE328_I126@PURE_QUANTA.Q_RES_4P_12(CHIPS)':
 '4': CDS_PINID='\4\';
NET_NAME
'P12V_HSC_SENSE1_P'
 '@S9S_MB_2U_LIB.S9S_MB_2U(SCH_1):P12V_HSC_SENSE1_P':
 C_SIGNAL='@s9s_mb_2u_lib.s9s_mb_2u(sch_1):p12v_hsc_sense1_p';
NODE_NAME     PJ42 2
 '@S9S_MB_2U_LIB.S9S_MB_2U(SCH_1):PAGE327_I34@PURE_QUANTA.SCONN21_9193031121LF(CHIPS)':
 '2': CDS_PINID='\2\';
NODE_NAME     PR2514 2
 '@S9S_MB_2U_LIB.S9S_MB_2U(SCH_1):PAGE328_I97@PURE_QUANTA.Q_RES(CHIPS)':
 'B': CDS_PINID='B';
NODE_NAME     PR3 3
 '@S9S_MB_2U_LIB.S9S_MB_2U(SCH_1):PAGE328_I126@PURE_QUANTA.Q_RES_4P_12(CHIPS)':
 '3': CDS_PINID='\3\';
NET_NAME
'P12V_HSC_SENSE2_N'
 '@S9S_MB_2U_LIB.S9S_MB_2U(SCH_1):P12V_HSC_SENSE2_N':
 C_SIGNAL='@s9s_mb_2u_lib.s9s_mb_2u(sch_1):p12v_hsc_sense2_n';
NODE_NAME     PJ42 5
 '@S9S_MB_2U_LIB.S9S_MB_2U(SCH_1):PAGE327_I34@PURE_QUANTA.SCONN21_9193031121LF(CHIPS)':
 '5': CDS_PINID='\5\';
NODE_NAME     PR2527 1
 '@S9S_MB_2U_LIB.S9S_MB_2U(SCH_1):PAGE328_I117@PURE_QUANTA.Q_RES(CHIPS)':
 'A': CDS_PINID='A';
NODE_NAME     PR2526 1
 '@S9S_MB_2U_LIB.S9S_MB_2U(SCH_1):PAGE328_I118@PURE_QUANTA.Q_RES(CHIPS)':
 'A': CDS_PINID='A';
NODE_NAME     PR2524 1
 '@S9S_MB_2U_LIB.S9S_MB_2U(SCH_1):PAGE328_I119@PURE_QUANTA.Q_RES(CHIPS)':
 'A': CDS_PINID='A';
NODE_NAME     PR2525 1
 '@S9S_MB_2U_LIB.S9S_MB_2U(SCH_1):PAGE328_I120@PURE_QUANTA.Q_RES(CHIPS)':
 'A': CDS_PINID='A';
NET_NAME
'P12V_HSC_SENSE2_P'
 '@S9S_MB_2U_LIB.S9S_MB_2U(SCH_1):P12V_HSC_SENSE2_P':
 C_SIGNAL='@s9s_mb_2u_lib.s9s_mb_2u(sch_1):p12v_hsc_sense2_p';
NODE_NAME     PJ42 4
 '@S9S_MB_2U_LIB.S9S_MB_2U(SCH_1):PAGE327_I34@PURE_QUANTA.SCONN21_9193031121LF(CHIPS)':
 '4': CDS_PINID='\4\';
NODE_NAME     PR2522 1
 '@S9S_MB_2U_LIB.S9S_MB_2U(SCH_1):PAGE328_I86@PURE_QUANTA.Q_RES(CHIPS)':
 'A': CDS_PINID='A';
NODE_NAME     PR2523 1
 '@S9S_MB_2U_LIB.S9S_MB_2U(SCH_1):PAGE328_I87@PURE_QUANTA.Q_RES(CHIPS)':
 'A': CDS_PINID='A';
NODE_NAME     PR2521 1
 '@S9S_MB_2U_LIB.S9S_MB_2U(SCH_1):PAGE328_I88@PURE_QUANTA.Q_RES(CHIPS)':
 'A': CDS_PINID='A';
NODE_NAME     PR2520 1
 '@S9S_MB_2U_LIB.S9S_MB_2U(SCH_1):PAGE328_I89@PURE_QUANTA.Q_RES(CHIPS)':
 'A': CDS_PINID='A';
NET_NAME
'P12V_HSC_SENSE2_R1_N'
 '@S9S_MB_2U_LIB.S9S_MB_2U(SCH_1):P12V_HSC_SENSE2_R1_N':
 C_SIGNAL='@s9s_mb_2u_lib.s9s_mb_2u(sch_1):p12v_hsc_sense2_r1_n';
NODE_NAME     PR4 2B
 '@S9S_MB_2U_LIB.S9S_MB_2U(SCH_1):PAGE328_I79@PURE_QUANTA.Q_SP_RES4P(CHIPS)':
 '2B': CDS_PINID='\2b\';
NODE_NAME     PR2515 2
 '@S9S_MB_2U_LIB.S9S_MB_2U(SCH_1):PAGE328_I93@PURE_QUANTA.Q_RES(CHIPS)':
 'B': CDS_PINID='B';
NODE_NAME     PR2524 2
 '@S9S_MB_2U_LIB.S9S_MB_2U(SCH_1):PAGE328_I119@PURE_QUANTA.Q_RES(CHIPS)':
 'B': CDS_PINID='B';
NET_NAME
'P12V_HSC_SENSE2_R1_P'
 '@S9S_MB_2U_LIB.S9S_MB_2U(SCH_1):P12V_HSC_SENSE2_R1_P':
 C_SIGNAL='@s9s_mb_2u_lib.s9s_mb_2u(sch_1):p12v_hsc_sense2_r1_p';
NODE_NAME     PR4 1B
 '@S9S_MB_2U_LIB.S9S_MB_2U(SCH_1):PAGE328_I79@PURE_QUANTA.Q_SP_RES4P(CHIPS)':
 '1B': CDS_PINID='\1b\';
NODE_NAME     PR2520 2
 '@S9S_MB_2U_LIB.S9S_MB_2U(SCH_1):PAGE328_I89@PURE_QUANTA.Q_RES(CHIPS)':
 'B': CDS_PINID='B';
NODE_NAME     PR2510 2
 '@S9S_MB_2U_LIB.S9S_MB_2U(SCH_1):PAGE328_I98@PURE_QUANTA.Q_RES(CHIPS)':
 'B': CDS_PINID='B';
NET_NAME
'P12V_HSC_SENSE2_R2_N'
 '@S9S_MB_2U_LIB.S9S_MB_2U(SCH_1):P12V_HSC_SENSE2_R2_N':
 C_SIGNAL='@s9s_mb_2u_lib.s9s_mb_2u(sch_1):p12v_hsc_sense2_r2_n';
NODE_NAME     PR2532 2B
 '@S9S_MB_2U_LIB.S9S_MB_2U(SCH_1):PAGE328_I78@PURE_QUANTA.Q_SP_RES4P(CHIPS)':
 '2B': CDS_PINID='\2b\';
NODE_NAME     PR2516 2
 '@S9S_MB_2U_LIB.S9S_MB_2U(SCH_1):PAGE328_I94@PURE_QUANTA.Q_RES(CHIPS)':
 'B': CDS_PINID='B';
NODE_NAME     PR2525 2
 '@S9S_MB_2U_LIB.S9S_MB_2U(SCH_1):PAGE328_I120@PURE_QUANTA.Q_RES(CHIPS)':
 'B': CDS_PINID='B';
NET_NAME
'P12V_HSC_SENSE2_R2_P'
 '@S9S_MB_2U_LIB.S9S_MB_2U(SCH_1):P12V_HSC_SENSE2_R2_P':
 C_SIGNAL='@s9s_mb_2u_lib.s9s_mb_2u(sch_1):p12v_hsc_sense2_r2_p';
NODE_NAME     PR2532 1B
 '@S9S_MB_2U_LIB.S9S_MB_2U(SCH_1):PAGE328_I78@PURE_QUANTA.Q_SP_RES4P(CHIPS)':
 '1B': CDS_PINID='\1b\';
NODE_NAME     PR2521 2
 '@S9S_MB_2U_LIB.S9S_MB_2U(SCH_1):PAGE328_I88@PURE_QUANTA.Q_RES(CHIPS)':
 'B': CDS_PINID='B';
NODE_NAME     PR2511 2
 '@S9S_MB_2U_LIB.S9S_MB_2U(SCH_1):PAGE328_I99@PURE_QUANTA.Q_RES(CHIPS)':
 'B': CDS_PINID='B';
NET_NAME
'P12V_HSC_SENSE2_R3_N'
 '@S9S_MB_2U_LIB.S9S_MB_2U(SCH_1):P12V_HSC_SENSE2_R3_N':
 C_SIGNAL='@s9s_mb_2u_lib.s9s_mb_2u(sch_1):p12v_hsc_sense2_r3_n';
NODE_NAME     PR2533 2B
 '@S9S_MB_2U_LIB.S9S_MB_2U(SCH_1):PAGE328_I64@PURE_QUANTA.Q_SP_RES4P(CHIPS)':
 '2B': CDS_PINID='\2b\';
NODE_NAME     PR2517 2
 '@S9S_MB_2U_LIB.S9S_MB_2U(SCH_1):PAGE328_I90@PURE_QUANTA.Q_RES(CHIPS)':
 'B': CDS_PINID='B';
NODE_NAME     PR2526 2
 '@S9S_MB_2U_LIB.S9S_MB_2U(SCH_1):PAGE328_I118@PURE_QUANTA.Q_RES(CHIPS)':
 'B': CDS_PINID='B';
NET_NAME
'P12V_HSC_SENSE2_R3_P'
 '@S9S_MB_2U_LIB.S9S_MB_2U(SCH_1):P12V_HSC_SENSE2_R3_P':
 C_SIGNAL='@s9s_mb_2u_lib.s9s_mb_2u(sch_1):p12v_hsc_sense2_r3_p';
NODE_NAME     PR2533 1B
 '@S9S_MB_2U_LIB.S9S_MB_2U(SCH_1):PAGE328_I64@PURE_QUANTA.Q_SP_RES4P(CHIPS)':
 '1B': CDS_PINID='\1b\';
NODE_NAME     PR2522 2
 '@S9S_MB_2U_LIB.S9S_MB_2U(SCH_1):PAGE328_I86@PURE_QUANTA.Q_RES(CHIPS)':
 'B': CDS_PINID='B';
NODE_NAME     PR2512 2
 '@S9S_MB_2U_LIB.S9S_MB_2U(SCH_1):PAGE328_I96@PURE_QUANTA.Q_RES(CHIPS)':
 'B': CDS_PINID='B';
NET_NAME
'P12V_HSC_SENSE2_R4_N'
 '@S9S_MB_2U_LIB.S9S_MB_2U(SCH_1):P12V_HSC_SENSE2_R4_N':
 C_SIGNAL='@s9s_mb_2u_lib.s9s_mb_2u(sch_1):p12v_hsc_sense2_r4_n';
NODE_NAME     PR2534 2B
 '@S9S_MB_2U_LIB.S9S_MB_2U(SCH_1):PAGE328_I63@PURE_QUANTA.Q_SP_RES4P(CHIPS)':
 '2B': CDS_PINID='\2b\';
NODE_NAME     PR2518 2
 '@S9S_MB_2U_LIB.S9S_MB_2U(SCH_1):PAGE328_I91@PURE_QUANTA.Q_RES(CHIPS)':
 'B': CDS_PINID='B';
NODE_NAME     PR2527 2
 '@S9S_MB_2U_LIB.S9S_MB_2U(SCH_1):PAGE328_I117@PURE_QUANTA.Q_RES(CHIPS)':
 'B': CDS_PINID='B';
NET_NAME
'P12V_HSC_SENSE2_R4_P'
 '@S9S_MB_2U_LIB.S9S_MB_2U(SCH_1):P12V_HSC_SENSE2_R4_P':
 C_SIGNAL='@s9s_mb_2u_lib.s9s_mb_2u(sch_1):p12v_hsc_sense2_r4_p';
NODE_NAME     PR2534 1B
 '@S9S_MB_2U_LIB.S9S_MB_2U(SCH_1):PAGE328_I63@PURE_QUANTA.Q_SP_RES4P(CHIPS)':
 '1B': CDS_PINID='\1b\';
NODE_NAME     PR2523 2
 '@S9S_MB_2U_LIB.S9S_MB_2U(SCH_1):PAGE328_I87@PURE_QUANTA.Q_RES(CHIPS)':
 'B': CDS_PINID='B';
NODE_NAME     PR2513 2
 '@S9S_MB_2U_LIB.S9S_MB_2U(SCH_1):PAGE328_I95@PURE_QUANTA.Q_RES(CHIPS)':
 'B': CDS_PINID='B';
NET_NAME
'P12V_HSC_TEMP_ALERT_N'
 '@S9S_MB_2U_LIB.S9S_MB_2U(SCH_1):P12V_HSC_TEMP_ALERT_N':
 C_SIGNAL='@s9s_mb_2u_lib.s9s_mb_2u(sch_1):p12v_hsc_temp_alert_n';
NODE_NAME     U345 6
 '@S9S_MB_2U_LIB.S9S_MB_2U(SCH_1):PAGE327_I10@PURE_QUANTA.NCT7718W(CHIPS)':
 'ALERT#': CDS_PINID='\alert#\';
NODE_NAME     R4684 1
 '@S9S_MB_2U_LIB.S9S_MB_2U(SCH_1):PAGE327_I14@PURE_QUANTA.Q_RES(CHIPS)':
 'A': CDS_PINID='A';
NET_NAME
'P12V_HSC_TEMP_ALERT_R_N'
 '@S9S_MB_2U_LIB.S9S_MB_2U(SCH_1):P12V_HSC_TEMP_ALERT_R_N':
 C_SIGNAL='@s9s_mb_2u_lib.s9s_mb_2u(sch_1):p12v_hsc_temp_alert_r_n';
NODE_NAME     R4684 2
 '@S9S_MB_2U_LIB.S9S_MB_2U(SCH_1):PAGE327_I14@PURE_QUANTA.Q_RES(CHIPS)':
 'B': CDS_PINID='B';
NODE_NAME     R4685 2
 '@S9S_MB_2U_LIB.S9S_MB_2U(SCH_1):PAGE327_I23@PURE_QUANTA.Q_RES(CHIPS)':
 'B': CDS_PINID='B';
NODE_NAME     U249 A19
 '@S9S_MB_2U_LIB.S9S_MB_2U(SCH_1):PAGE314_I188@PURE_QUANTA.LCMXO3LF9400C5BG484C(CHIPS)':
 'PT42A': CDS_PINID='PT42A';
NET_NAME
'P12V_HSC_TEMP_D+'
 '@S9S_MB_2U_LIB.S9S_MB_2U(SCH_1):P12V_HSC_TEMP_D+':
 C_SIGNAL='@s9s_mb_2u_lib.s9s_mb_2u(sch_1):\p12v_hsc_temp_d+\';
NODE_NAME     R4892 2
 '@S9S_MB_2U_LIB.S9S_MB_2U(SCH_1):PAGE327_I5@PURE_QUANTA.Q_RES(CHIPS)':
 'B': CDS_PINID='B';
NODE_NAME     C2459 1
 '@S9S_MB_2U_LIB.S9S_MB_2U(SCH_1):PAGE327_I6@PURE_QUANTA.Q_CAP(CHIPS)':
 'A': CDS_PINID='A';
NODE_NAME     U345 2
 '@S9S_MB_2U_LIB.S9S_MB_2U(SCH_1):PAGE327_I10@PURE_QUANTA.NCT7718W(CHIPS)':
 'D+': CDS_PINID='\d+\';
NET_NAME
'P12V_HSC_TEMP_D-'
 '@S9S_MB_2U_LIB.S9S_MB_2U(SCH_1):P12V_HSC_TEMP_D-':
 C_SIGNAL='@s9s_mb_2u_lib.s9s_mb_2u(sch_1):\p12v_hsc_temp_d-\';
NODE_NAME     R4893 2
 '@S9S_MB_2U_LIB.S9S_MB_2U(SCH_1):PAGE327_I4@PURE_QUANTA.Q_RES(CHIPS)':
 'B': CDS_PINID='B';
NODE_NAME     C2459 2
 '@S9S_MB_2U_LIB.S9S_MB_2U(SCH_1):PAGE327_I6@PURE_QUANTA.Q_CAP(CHIPS)':
 'B': CDS_PINID='B';
NODE_NAME     U345 3
 '@S9S_MB_2U_LIB.S9S_MB_2U(SCH_1):PAGE327_I10@PURE_QUANTA.NCT7718W(CHIPS)':
 'D-': CDS_PINID='\d-\';
NET_NAME
'P12V_HSC_TEMP_E'
 '@S9S_MB_2U_LIB.S9S_MB_2U(SCH_1):P12V_HSC_TEMP_E':
 C_SIGNAL='@s9s_mb_2u_lib.s9s_mb_2u(sch_1):p12v_hsc_temp_e';
NODE_NAME     R4893 1
 '@S9S_MB_2U_LIB.S9S_MB_2U(SCH_1):PAGE327_I4@PURE_QUANTA.Q_RES(CHIPS)':
 'A': CDS_PINID='A';
NODE_NAME     U365 E
 '@S9S_MB_2U_LIB.S9S_MB_2U(SCH_1):PAGE327_I49@PURE_QUANTA.MMBT3904(CHIPS)':
 '2': CDS_PINID='\2\';
NET_NAME
'P12V_HSC_TEMP_R'
 '@S9S_MB_2U_LIB.S9S_MB_2U(SCH_1):P12V_HSC_TEMP_R':
 C_SIGNAL='@s9s_mb_2u_lib.s9s_mb_2u(sch_1):p12v_hsc_temp_r';
NODE_NAME     R4892 1
 '@S9S_MB_2U_LIB.S9S_MB_2U(SCH_1):PAGE327_I5@PURE_QUANTA.Q_RES(CHIPS)':
 'A': CDS_PINID='A';
NODE_NAME     U365 B
 '@S9S_MB_2U_LIB.S9S_MB_2U(SCH_1):PAGE327_I49@PURE_QUANTA.MMBT3904(CHIPS)':
 '1': CDS_PINID='\1\';
NODE_NAME     U365 C
 '@S9S_MB_2U_LIB.S9S_MB_2U(SCH_1):PAGE327_I49@PURE_QUANTA.MMBT3904(CHIPS)':
 '3': CDS_PINID='\3\';
NET_NAME
'P12V_HSC_TEMP_SCL'
 '@S9S_MB_2U_LIB.S9S_MB_2U(SCH_1):P12V_HSC_TEMP_SCL':
 C_SIGNAL='@s9s_mb_2u_lib.s9s_mb_2u(sch_1):p12v_hsc_temp_scl';
NODE_NAME     U345 8
 '@S9S_MB_2U_LIB.S9S_MB_2U(SCH_1):PAGE327_I10@PURE_QUANTA.NCT7718W(CHIPS)':
 'SCL': CDS_PINID='SCL';
NODE_NAME     R4894 1
 '@S9S_MB_2U_LIB.S9S_MB_2U(SCH_1):PAGE327_I15@PURE_QUANTA.Q_RES(CHIPS)':
 'A': CDS_PINID='A';
NET_NAME
'P12V_HSC_TEMP_SDA'
 '@S9S_MB_2U_LIB.S9S_MB_2U(SCH_1):P12V_HSC_TEMP_SDA':
 C_SIGNAL='@s9s_mb_2u_lib.s9s_mb_2u(sch_1):p12v_hsc_temp_sda';
NODE_NAME     U345 7
 '@S9S_MB_2U_LIB.S9S_MB_2U(SCH_1):PAGE327_I10@PURE_QUANTA.NCT7718W(CHIPS)':
 'SDA': CDS_PINID='SDA';
NODE_NAME     R4895 1
 '@S9S_MB_2U_LIB.S9S_MB_2U(SCH_1):PAGE327_I16@PURE_QUANTA.Q_RES(CHIPS)':
 'A': CDS_PINID='A';
NET_NAME
'P12V_HSC_T_CRIT_N'
 '@S9S_MB_2U_LIB.S9S_MB_2U(SCH_1):P12V_HSC_T_CRIT_N':
 C_SIGNAL='@s9s_mb_2u_lib.s9s_mb_2u(sch_1):p12v_hsc_t_crit_n';
NODE_NAME     U345 4
 '@S9S_MB_2U_LIB.S9S_MB_2U(SCH_1):PAGE327_I10@PURE_QUANTA.NCT7718W(CHIPS)':
 'T_CRIT#': CDS_PINID='\t_crit#\';
NODE_NAME     R4896 1
 '@S9S_MB_2U_LIB.S9S_MB_2U(SCH_1):PAGE327_I11@PURE_QUANTA.Q_RES(CHIPS)':
 'A': CDS_PINID='A';
NET_NAME
'P12V_HSC_T_CRIT_R_N'
 '@S9S_MB_2U_LIB.S9S_MB_2U(SCH_1):P12V_HSC_T_CRIT_R_N':
 C_SIGNAL='@s9s_mb_2u_lib.s9s_mb_2u(sch_1):p12v_hsc_t_crit_r_n';
NODE_NAME     R4896 2
 '@S9S_MB_2U_LIB.S9S_MB_2U(SCH_1):PAGE327_I11@PURE_QUANTA.Q_RES(CHIPS)':
 'B': CDS_PINID='B';
NODE_NAME     R4686 2
 '@S9S_MB_2U_LIB.S9S_MB_2U(SCH_1):PAGE327_I17@PURE_QUANTA.Q_RES(CHIPS)':
 'B': CDS_PINID='B';
NODE_NAME     U249 B20
 '@S9S_MB_2U_LIB.S9S_MB_2U(SCH_1):PAGE314_I188@PURE_QUANTA.LCMXO3LF9400C5BG484C(CHIPS)':
 'PT42B': CDS_PINID='PT42B';
NET_NAME
'P12V_MAIN_R'
 '@S9S_MB_2U_LIB.S9S_MB_2U(SCH_1):P12V_MAIN_R':
 C_SIGNAL='@s9s_mb_2u_lib.s9s_mb_2u(sch_1):p12v_main_r',
 CDS_GLOBAL_NET='TRUE';
NODE_NAME     PPQ5 5
 '@S9S_MB_2U_LIB.S9S_MB_2U(SCH_1):PAGE328_I35@PURE_QUANTA.MOSFET_NCH_1D3S(CHIPS)':
 '5': CDS_PINID='\5\';
NODE_NAME     PPQ6 5
 '@S9S_MB_2U_LIB.S9S_MB_2U(SCH_1):PAGE328_I40@PURE_QUANTA.MOSFET_NCH_1D3S(CHIPS)':
 '5': CDS_PINID='\5\';
NODE_NAME     PPQ7 5
 '@S9S_MB_2U_LIB.S9S_MB_2U(SCH_1):PAGE328_I41@PURE_QUANTA.MOSFET_NCH_1D3S(CHIPS)':
 '5': CDS_PINID='\5\';
NODE_NAME     PPQ8 5
 '@S9S_MB_2U_LIB.S9S_MB_2U(SCH_1):PAGE328_I62@PURE_QUANTA.MOSFET_NCH_1D3S(CHIPS)':
 '5': CDS_PINID='\5\';
NODE_NAME     PR2534 2A
 '@S9S_MB_2U_LIB.S9S_MB_2U(SCH_1):PAGE328_I63@PURE_QUANTA.Q_SP_RES4P(CHIPS)':
 '2A': CDS_PINID='\2a\';
NODE_NAME     PR2533 2A
 '@S9S_MB_2U_LIB.S9S_MB_2U(SCH_1):PAGE328_I64@PURE_QUANTA.Q_SP_RES4P(CHIPS)':
 '2A': CDS_PINID='\2a\';
NODE_NAME     PPQ1 5
 '@S9S_MB_2U_LIB.S9S_MB_2U(SCH_1):PAGE328_I65@PURE_QUANTA.MOSFET_NCH_1D3S(CHIPS)':
 '5': CDS_PINID='\5\';
NODE_NAME     PPQ2 5
 '@S9S_MB_2U_LIB.S9S_MB_2U(SCH_1):PAGE328_I73@PURE_QUANTA.MOSFET_NCH_1D3S(CHIPS)':
 '5': CDS_PINID='\5\';
NODE_NAME     PR2532 2A
 '@S9S_MB_2U_LIB.S9S_MB_2U(SCH_1):PAGE328_I78@PURE_QUANTA.Q_SP_RES4P(CHIPS)':
 '2A': CDS_PINID='\2a\';
NODE_NAME     PR4 2A
 '@S9S_MB_2U_LIB.S9S_MB_2U(SCH_1):PAGE328_I79@PURE_QUANTA.Q_SP_RES4P(CHIPS)':
 '2A': CDS_PINID='\2a\';
NET_NAME
'P12V_MAIN_R_0'
 '@S9S_MB_2U_LIB.S9S_MB_2U(SCH_1):P12V_MAIN_R_0':
 C_SIGNAL='@s9s_mb_2u_lib.s9s_mb_2u(sch_1):p12v_main_r_0',
 CDS_GLOBAL_NET='TRUE';
NODE_NAME     PPQ9 5
 '@S9S_MB_2U_LIB.S9S_MB_2U(SCH_1):PAGE328_I77@PURE_QUANTA.MOSFET_NCH_1D3S(CHIPS)':
 '5': CDS_PINID='\5\';
NODE_NAME     PR3 2
 '@S9S_MB_2U_LIB.S9S_MB_2U(SCH_1):PAGE328_I126@PURE_QUANTA.Q_RES_4P_12(CHIPS)':
 '2': CDS_PINID='\2\';
NET_NAME
'P12V_OCP_1_EN_G'
 '@S9S_MB_2U_LIB.S9S_MB_2U(SCH_1):P12V_OCP_1_EN_G':
 C_SIGNAL='@s9s_mb_2u_lib.s9s_mb_2u(sch_1):p12v_ocp_1_en_g';
NODE_NAME     Q123 5
 '@S9S_MB_2U_LIB.S9S_MB_2U(SCH_1):PAGE153_I17@PURE_QUANTA.MOSFET_NCH_DUAL(CHIPS)':
 'G2': CDS_PINID='G2';
NODE_NAME     Q123 6
 '@S9S_MB_2U_LIB.S9S_MB_2U(SCH_1):PAGE153_I9@PURE_QUANTA.MOSFET_NCH_DUAL(CHIPS)':
 'D1': CDS_PINID='D1';
NODE_NAME     R4068 2
 '@S9S_MB_2U_LIB.S9S_MB_2U(SCH_1):PAGE153_I15@PURE_QUANTA.Q_RES(CHIPS)':
 'B': CDS_PINID='B';
NET_NAME
'P12V_OCP_2_EN_G'
 '@S9S_MB_2U_LIB.S9S_MB_2U(SCH_1):P12V_OCP_2_EN_G':
 C_SIGNAL='@s9s_mb_2u_lib.s9s_mb_2u(sch_1):p12v_ocp_2_en_g';
NODE_NAME     R4065 2
 '@S9S_MB_2U_LIB.S9S_MB_2U(SCH_1):PAGE131_I14@PURE_QUANTA.Q_RES(CHIPS)':
 'B': CDS_PINID='B';
NODE_NAME     Q118 5
 '@S9S_MB_2U_LIB.S9S_MB_2U(SCH_1):PAGE131_I16@PURE_QUANTA.MOSFET_NCH_DUAL(CHIPS)':
 'G2': CDS_PINID='G2';
NODE_NAME     Q118 6
 '@S9S_MB_2U_LIB.S9S_MB_2U(SCH_1):PAGE131_I7@PURE_QUANTA.MOSFET_NCH_DUAL(CHIPS)':
 'D1': CDS_PINID='D1';
NET_NAME
'P12V_OCP_AVIN_PD_1'
 '@S9S_MB_2U_LIB.S9S_MB_2U(SCH_1):P12V_OCP_AVIN_PD_1':
 C_SIGNAL='@s9s_mb_2u_lib.s9s_mb_2u(sch_1):p12v_ocp_avin_pd_1';
NODE_NAME     PU204 12
 '@S9S_MB_2U_LIB.S9S_MB_2U(SCH_1):PAGE236_I70@PURE_QUANTA.RS31312R(CHIPS)':
 'AVIN': CDS_PINID='AVIN';
NODE_NAME     PR3838 2
 '@S9S_MB_2U_LIB.S9S_MB_2U(SCH_1):PAGE236_I77@PURE_QUANTA.Q_RES(CHIPS)':
 'B': CDS_PINID='B';
NODE_NAME     PC2158 1
 '@S9S_MB_2U_LIB.S9S_MB_2U(SCH_1):PAGE236_I88@PURE_QUANTA.Q_CAP(CHIPS)':
 'A': CDS_PINID='A';
NODE_NAME     PR3843 2
 '@S9S_MB_2U_LIB.S9S_MB_2U(SCH_1):PAGE236_I89@PURE_QUANTA.Q_RES(CHIPS)':
 'B': CDS_PINID='B';
NET_NAME
'P12V_OCP_AVIN_PD_2'
 '@S9S_MB_2U_LIB.S9S_MB_2U(SCH_1):P12V_OCP_AVIN_PD_2':
 C_SIGNAL='@s9s_mb_2u_lib.s9s_mb_2u(sch_1):p12v_ocp_avin_pd_2';
NODE_NAME     PU206 12
 '@S9S_MB_2U_LIB.S9S_MB_2U(SCH_1):PAGE237_I70@PURE_QUANTA.RS31312R(CHIPS)':
 'AVIN': CDS_PINID='AVIN';
NODE_NAME     PR3850 2
 '@S9S_MB_2U_LIB.S9S_MB_2U(SCH_1):PAGE237_I77@PURE_QUANTA.Q_RES(CHIPS)':
 'B': CDS_PINID='B';
NODE_NAME     PR3857 2
 '@S9S_MB_2U_LIB.S9S_MB_2U(SCH_1):PAGE237_I87@PURE_QUANTA.Q_RES(CHIPS)':
 'B': CDS_PINID='B';
NODE_NAME     PC1320 1
 '@S9S_MB_2U_LIB.S9S_MB_2U(SCH_1):PAGE237_I95@PURE_QUANTA.Q_CAP(CHIPS)':
 'A': CDS_PINID='A';
NET_NAME
'P12V_OCP_CB_1'
 '@S9S_MB_2U_LIB.S9S_MB_2U(SCH_1):P12V_OCP_CB_1':
 C_SIGNAL='@s9s_mb_2u_lib.s9s_mb_2u(sch_1):p12v_ocp_cb_1';
NODE_NAME     PR5484 1
 '@S9S_MB_2U_LIB.S9S_MB_2U(SCH_1):PAGE153_I49@PURE_QUANTA.Q_RES(CHIPS)':
 'A': CDS_PINID='A';
NODE_NAME     PU203 B1
 '@S9S_MB_2U_LIB.S9S_MB_2U(SCH_1):PAGE153_I51@PURE_QUANTA.MAX15090BEWIT(CHIPS)':
 'CB': CDS_PINID='CB';
NET_NAME
'P12V_OCP_CB_2'
 '@S9S_MB_2U_LIB.S9S_MB_2U(SCH_1):P12V_OCP_CB_2':
 C_SIGNAL='@s9s_mb_2u_lib.s9s_mb_2u(sch_1):p12v_ocp_cb_2';
NODE_NAME     PR3821 1
 '@S9S_MB_2U_LIB.S9S_MB_2U(SCH_1):PAGE131_I59@PURE_QUANTA.Q_RES(CHIPS)':
 'A': CDS_PINID='A';
NODE_NAME     PU201 B1
 '@S9S_MB_2U_LIB.S9S_MB_2U(SCH_1):PAGE131_I63@PURE_QUANTA.MAX15090BEWIT(CHIPS)':
 'CB': CDS_PINID='CB';
NET_NAME
'P12V_OCP_EN_1_R'
 '@S9S_MB_2U_LIB.S9S_MB_2U(SCH_1):P12V_OCP_EN_1_R':
 C_SIGNAL='@s9s_mb_2u_lib.s9s_mb_2u(sch_1):p12v_ocp_en_1_r';
NODE_NAME     R4061 2
 '@S9S_MB_2U_LIB.S9S_MB_2U(SCH_1):PAGE153_I4@PURE_QUANTA.Q_RES(CHIPS)':
 'B': CDS_PINID='B';
NODE_NAME     Q123 2
 '@S9S_MB_2U_LIB.S9S_MB_2U(SCH_1):PAGE153_I9@PURE_QUANTA.MOSFET_NCH_DUAL(CHIPS)':
 'G1': CDS_PINID='G1';
NET_NAME
'P12V_OCP_EN_1_R2'
 '@S9S_MB_2U_LIB.S9S_MB_2U(SCH_1):P12V_OCP_EN_1_R2':
 C_SIGNAL='@s9s_mb_2u_lib.s9s_mb_2u(sch_1):p12v_ocp_en_1_r2';
NODE_NAME     R3834 2
 '@S9S_MB_2U_LIB.S9S_MB_2U(SCH_1):PAGE236_I65@PURE_QUANTA.Q_RES(CHIPS)':
 'B': CDS_PINID='B';
NODE_NAME     PU204 1
 '@S9S_MB_2U_LIB.S9S_MB_2U(SCH_1):PAGE236_I70@PURE_QUANTA.RS31312R(CHIPS)':
 'EN': CDS_PINID='EN';
NET_NAME
'P12V_OCP_EN_2_R'
 '@S9S_MB_2U_LIB.S9S_MB_2U(SCH_1):P12V_OCP_EN_2_R':
 C_SIGNAL='@s9s_mb_2u_lib.s9s_mb_2u(sch_1):p12v_ocp_en_2_r';
NODE_NAME     R4059 2
 '@S9S_MB_2U_LIB.S9S_MB_2U(SCH_1):PAGE131_I6@PURE_QUANTA.Q_RES(CHIPS)':
 'B': CDS_PINID='B';
NODE_NAME     Q118 2
 '@S9S_MB_2U_LIB.S9S_MB_2U(SCH_1):PAGE131_I7@PURE_QUANTA.MOSFET_NCH_DUAL(CHIPS)':
 'G1': CDS_PINID='G1';
NET_NAME
'P12V_OCP_FAULT_1'
 '@S9S_MB_2U_LIB.S9S_MB_2U(SCH_1):P12V_OCP_FAULT_1':
 C_SIGNAL='@s9s_mb_2u_lib.s9s_mb_2u(sch_1):p12v_ocp_fault_1';
NODE_NAME     R3799 2
 '@S9S_MB_2U_LIB.S9S_MB_2U(SCH_1):PAGE153_I90@PURE_QUANTA.Q_RES(CHIPS)':
 'B': CDS_PINID='B';
NODE_NAME     PU203 C7
 '@S9S_MB_2U_LIB.S9S_MB_2U(SCH_1):PAGE153_I51@PURE_QUANTA.MAX15090BEWIT(CHIPS)':
 'FAULT#': CDS_PINID='\fault#\';
NET_NAME
'P12V_OCP_FAULT_2'
 '@S9S_MB_2U_LIB.S9S_MB_2U(SCH_1):P12V_OCP_FAULT_2':
 C_SIGNAL='@s9s_mb_2u_lib.s9s_mb_2u(sch_1):p12v_ocp_fault_2';
NODE_NAME     R3816 2
 '@S9S_MB_2U_LIB.S9S_MB_2U(SCH_1):PAGE131_I80@PURE_QUANTA.Q_RES(CHIPS)':
 'B': CDS_PINID='B';
NODE_NAME     PU201 C7
 '@S9S_MB_2U_LIB.S9S_MB_2U(SCH_1):PAGE131_I63@PURE_QUANTA.MAX15090BEWIT(CHIPS)':
 'FAULT#': CDS_PINID='\fault#\';
NET_NAME
'P12V_OCP_FLTB_1'
 '@S9S_MB_2U_LIB.S9S_MB_2U(SCH_1):P12V_OCP_FLTB_1':
 C_SIGNAL='@s9s_mb_2u_lib.s9s_mb_2u(sch_1):p12v_ocp_fltb_1';
NODE_NAME     PU204 9
 '@S9S_MB_2U_LIB.S9S_MB_2U(SCH_1):PAGE236_I70@PURE_QUANTA.RS31312R(CHIPS)':
 'FLTB': CDS_PINID='FLTB';
NODE_NAME     PR3839 1
 '@S9S_MB_2U_LIB.S9S_MB_2U(SCH_1):PAGE236_I75@PURE_QUANTA.Q_RES(CHIPS)':
 'A': CDS_PINID='A';
NET_NAME
'P12V_OCP_FLTB_2'
 '@S9S_MB_2U_LIB.S9S_MB_2U(SCH_1):P12V_OCP_FLTB_2':
 C_SIGNAL='@s9s_mb_2u_lib.s9s_mb_2u(sch_1):p12v_ocp_fltb_2';
NODE_NAME     PU206 9
 '@S9S_MB_2U_LIB.S9S_MB_2U(SCH_1):PAGE237_I70@PURE_QUANTA.RS31312R(CHIPS)':
 'FLTB': CDS_PINID='FLTB';
NODE_NAME     PR3851 1
 '@S9S_MB_2U_LIB.S9S_MB_2U(SCH_1):PAGE237_I74@PURE_QUANTA.Q_RES(CHIPS)':
 'A': CDS_PINID='A';
NET_NAME
'P12V_OCP_GATE_1'
 '@S9S_MB_2U_LIB.S9S_MB_2U(SCH_1):P12V_OCP_GATE_1':
 C_SIGNAL='@s9s_mb_2u_lib.s9s_mb_2u(sch_1):p12v_ocp_gate_1';
NODE_NAME     PC2088 2
 '@S9S_MB_2U_LIB.S9S_MB_2U(SCH_1):PAGE153_I81@PURE_QUANTA.Q_CAP(CHIPS)':
 'B': CDS_PINID='B';
NODE_NAME     PU203 A6
 '@S9S_MB_2U_LIB.S9S_MB_2U(SCH_1):PAGE153_I51@PURE_QUANTA.MAX15090BEWIT(CHIPS)':
 'GATE': CDS_PINID='GATE';
NODE_NAME     PC4056 1
 '@S9S_MB_2U_LIB.S9S_MB_2U(SCH_1):PAGE153_I83@PURE_QUANTA.Q_CAP(CHIPS)':
 'A': CDS_PINID='A';
NODE_NAME     PR4524 2
 '@S9S_MB_2U_LIB.S9S_MB_2U(SCH_1):PAGE153_I84@PURE_QUANTA.Q_RES(CHIPS)':
 'B': CDS_PINID='B';
NET_NAME
'P12V_OCP_GATE_2'
 '@S9S_MB_2U_LIB.S9S_MB_2U(SCH_1):P12V_OCP_GATE_2':
 C_SIGNAL='@s9s_mb_2u_lib.s9s_mb_2u(sch_1):p12v_ocp_gate_2';
NODE_NAME     PU201 A6
 '@S9S_MB_2U_LIB.S9S_MB_2U(SCH_1):PAGE131_I63@PURE_QUANTA.MAX15090BEWIT(CHIPS)':
 'GATE': CDS_PINID='GATE';
NODE_NAME     C2148 2
 '@S9S_MB_2U_LIB.S9S_MB_2U(SCH_1):PAGE131_I73@PURE_QUANTA.Q_CAP(CHIPS)':
 'B': CDS_PINID='B';
NODE_NAME     PC2150 1
 '@S9S_MB_2U_LIB.S9S_MB_2U(SCH_1):PAGE131_I76@PURE_QUANTA.Q_CAP(CHIPS)':
 'A': CDS_PINID='A';
NODE_NAME     PR4522 2
 '@S9S_MB_2U_LIB.S9S_MB_2U(SCH_1):PAGE131_I77@PURE_QUANTA.Q_RES(CHIPS)':
 'B': CDS_PINID='B';
NET_NAME
'P12V_OCP_IMON_1'
 '@S9S_MB_2U_LIB.S9S_MB_2U(SCH_1):P12V_OCP_IMON_1':
 C_SIGNAL='@s9s_mb_2u_lib.s9s_mb_2u(sch_1):p12v_ocp_imon_1';
NODE_NAME     PU204 8
 '@S9S_MB_2U_LIB.S9S_MB_2U(SCH_1):PAGE236_I70@PURE_QUANTA.RS31312R(CHIPS)':
 'IMON': CDS_PINID='IMON';
NODE_NAME     PR3837 1
 '@S9S_MB_2U_LIB.S9S_MB_2U(SCH_1):PAGE236_I72@PURE_QUANTA.Q_RES(CHIPS)':
 'A': CDS_PINID='A';
NODE_NAME     PC2156 1
 '@S9S_MB_2U_LIB.S9S_MB_2U(SCH_1):PAGE236_I74@PURE_QUANTA.Q_CAP(CHIPS)':
 'A': CDS_PINID='A';
NODE_NAME     R3872 1
 '@S9S_MB_2U_LIB.S9S_MB_2U(SCH_1):PAGE236_I81@PURE_QUANTA.Q_RES(CHIPS)':
 'A': CDS_PINID='A';
NODE_NAME     R3871 1
 '@S9S_MB_2U_LIB.S9S_MB_2U(SCH_1):PAGE236_I82@PURE_QUANTA.Q_RES(CHIPS)':
 'A': CDS_PINID='A';
NET_NAME
'P12V_OCP_IMON_2'
 '@S9S_MB_2U_LIB.S9S_MB_2U(SCH_1):P12V_OCP_IMON_2':
 C_SIGNAL='@s9s_mb_2u_lib.s9s_mb_2u(sch_1):p12v_ocp_imon_2';
NODE_NAME     PU206 8
 '@S9S_MB_2U_LIB.S9S_MB_2U(SCH_1):PAGE237_I70@PURE_QUANTA.RS31312R(CHIPS)':
 'IMON': CDS_PINID='IMON';
NODE_NAME     PR3849 1
 '@S9S_MB_2U_LIB.S9S_MB_2U(SCH_1):PAGE237_I72@PURE_QUANTA.Q_RES(CHIPS)':
 'A': CDS_PINID='A';
NODE_NAME     PC2167 1
 '@S9S_MB_2U_LIB.S9S_MB_2U(SCH_1):PAGE237_I73@PURE_QUANTA.Q_CAP(CHIPS)':
 'A': CDS_PINID='A';
NODE_NAME     R3874 1
 '@S9S_MB_2U_LIB.S9S_MB_2U(SCH_1):PAGE237_I80@PURE_QUANTA.Q_RES(CHIPS)':
 'A': CDS_PINID='A';
NODE_NAME     R3873 1
 '@S9S_MB_2U_LIB.S9S_MB_2U(SCH_1):PAGE237_I81@PURE_QUANTA.Q_RES(CHIPS)':
 'A': CDS_PINID='A';
NET_NAME
'P12V_OCP_ISET_1'
 '@S9S_MB_2U_LIB.S9S_MB_2U(SCH_1):P12V_OCP_ISET_1':
 C_SIGNAL='@s9s_mb_2u_lib.s9s_mb_2u(sch_1):p12v_ocp_iset_1';
NODE_NAME     PR3835 1
 '@S9S_MB_2U_LIB.S9S_MB_2U(SCH_1):PAGE236_I62@PURE_QUANTA.Q_RES(CHIPS)':
 'A': CDS_PINID='A';
NODE_NAME     PU204 5
 '@S9S_MB_2U_LIB.S9S_MB_2U(SCH_1):PAGE236_I70@PURE_QUANTA.RS31312R(CHIPS)':
 'ISET': CDS_PINID='ISET';
NET_NAME
'P12V_OCP_ISET_2'
 '@S9S_MB_2U_LIB.S9S_MB_2U(SCH_1):P12V_OCP_ISET_2':
 C_SIGNAL='@s9s_mb_2u_lib.s9s_mb_2u(sch_1):p12v_ocp_iset_2';
NODE_NAME     PR3847 1
 '@S9S_MB_2U_LIB.S9S_MB_2U(SCH_1):PAGE237_I61@PURE_QUANTA.Q_RES(CHIPS)':
 'A': CDS_PINID='A';
NODE_NAME     PU206 5
 '@S9S_MB_2U_LIB.S9S_MB_2U(SCH_1):PAGE237_I70@PURE_QUANTA.RS31312R(CHIPS)':
 'ISET': CDS_PINID='ISET';
NET_NAME
'P12V_OCP_OV_1'
 '@S9S_MB_2U_LIB.S9S_MB_2U(SCH_1):P12V_OCP_OV_1':
 C_SIGNAL='@s9s_mb_2u_lib.s9s_mb_2u(sch_1):p12v_ocp_ov_1';
NODE_NAME     PR3787 2
 '@S9S_MB_2U_LIB.S9S_MB_2U(SCH_1):PAGE153_I41@PURE_QUANTA.Q_RES(CHIPS)':
 'B': CDS_PINID='B';
NODE_NAME     PR3788 1
 '@S9S_MB_2U_LIB.S9S_MB_2U(SCH_1):PAGE153_I33@PURE_QUANTA.Q_RES(CHIPS)':
 'A': CDS_PINID='A';
NODE_NAME     PU203 D3
 '@S9S_MB_2U_LIB.S9S_MB_2U(SCH_1):PAGE153_I51@PURE_QUANTA.MAX15090BEWIT(CHIPS)':
 'OV': CDS_PINID='OV';
NET_NAME
'P12V_OCP_OV_2'
 '@S9S_MB_2U_LIB.S9S_MB_2U(SCH_1):P12V_OCP_OV_2':
 C_SIGNAL='@s9s_mb_2u_lib.s9s_mb_2u(sch_1):p12v_ocp_ov_2';
NODE_NAME     PR3806 2
 '@S9S_MB_2U_LIB.S9S_MB_2U(SCH_1):PAGE131_I32@PURE_QUANTA.Q_RES(CHIPS)':
 'B': CDS_PINID='B';
NODE_NAME     PU201 D3
 '@S9S_MB_2U_LIB.S9S_MB_2U(SCH_1):PAGE131_I63@PURE_QUANTA.MAX15090BEWIT(CHIPS)':
 'OV': CDS_PINID='OV';
NODE_NAME     PR3828 1
 '@S9S_MB_2U_LIB.S9S_MB_2U(SCH_1):PAGE131_I29@PURE_QUANTA.Q_RES(CHIPS)':
 'A': CDS_PINID='A';
NET_NAME
'P12V_OCP_OV_FB_1'
 '@S9S_MB_2U_LIB.S9S_MB_2U(SCH_1):P12V_OCP_OV_FB_1':
 C_SIGNAL='@s9s_mb_2u_lib.s9s_mb_2u(sch_1):p12v_ocp_ov_fb_1';
NODE_NAME     PU204 11
 '@S9S_MB_2U_LIB.S9S_MB_2U(SCH_1):PAGE236_I70@PURE_QUANTA.RS31312R(CHIPS)':
 'OV': CDS_PINID='OV';
NODE_NAME     PR3842 1
 '@S9S_MB_2U_LIB.S9S_MB_2U(SCH_1):PAGE236_I83@PURE_QUANTA.Q_RES(CHIPS)':
 'A': CDS_PINID='A';
NODE_NAME     PR3840 2
 '@S9S_MB_2U_LIB.S9S_MB_2U(SCH_1):PAGE236_I85@PURE_QUANTA.Q_RES(CHIPS)':
 'B': CDS_PINID='B';
NODE_NAME     PR3841 2
 '@S9S_MB_2U_LIB.S9S_MB_2U(SCH_1):PAGE236_I86@PURE_QUANTA.Q_RES(CHIPS)':
 'B': CDS_PINID='B';
NET_NAME
'P12V_OCP_OV_FB_2'
 '@S9S_MB_2U_LIB.S9S_MB_2U(SCH_1):P12V_OCP_OV_FB_2':
 C_SIGNAL='@s9s_mb_2u_lib.s9s_mb_2u(sch_1):p12v_ocp_ov_fb_2';
NODE_NAME     PU206 11
 '@S9S_MB_2U_LIB.S9S_MB_2U(SCH_1):PAGE237_I70@PURE_QUANTA.RS31312R(CHIPS)':
 'OV': CDS_PINID='OV';
NODE_NAME     PR3854 1
 '@S9S_MB_2U_LIB.S9S_MB_2U(SCH_1):PAGE237_I83@PURE_QUANTA.Q_RES(CHIPS)':
 'A': CDS_PINID='A';
NODE_NAME     PR3853 2
 '@S9S_MB_2U_LIB.S9S_MB_2U(SCH_1):PAGE237_I84@PURE_QUANTA.Q_RES(CHIPS)':
 'B': CDS_PINID='B';
NODE_NAME     PR3852 2
 '@S9S_MB_2U_LIB.S9S_MB_2U(SCH_1):PAGE237_I85@PURE_QUANTA.Q_RES(CHIPS)':
 'B': CDS_PINID='B';
NET_NAME
'P12V_OCP_PWRGD_1'
 '@S9S_MB_2U_LIB.S9S_MB_2U(SCH_1):P12V_OCP_PWRGD_1':
 C_SIGNAL='@s9s_mb_2u_lib.s9s_mb_2u(sch_1):p12v_ocp_pwrgd_1';
NODE_NAME     R3144 1
 '@S9S_MB_2U_LIB.S9S_MB_2U(SCH_1):PAGE153_I82@PURE_QUANTA.Q_RES(CHIPS)':
 'A': CDS_PINID='A';
NODE_NAME     PU203 D7
 '@S9S_MB_2U_LIB.S9S_MB_2U(SCH_1):PAGE153_I51@PURE_QUANTA.MAX15090BEWIT(CHIPS)':
 'PG': CDS_PINID='PG';
NET_NAME
'P12V_OCP_PWRGD_2'
 '@S9S_MB_2U_LIB.S9S_MB_2U(SCH_1):P12V_OCP_PWRGD_2':
 C_SIGNAL='@s9s_mb_2u_lib.s9s_mb_2u(sch_1):p12v_ocp_pwrgd_2';
NODE_NAME     R3831 1
 '@S9S_MB_2U_LIB.S9S_MB_2U(SCH_1):PAGE131_I78@PURE_QUANTA.Q_RES(CHIPS)':
 'A': CDS_PINID='A';
NODE_NAME     PU201 D7
 '@S9S_MB_2U_LIB.S9S_MB_2U(SCH_1):PAGE131_I63@PURE_QUANTA.MAX15090BEWIT(CHIPS)':
 'PG': CDS_PINID='PG';
NET_NAME
'P12V_OCP_REG_1'
 '@S9S_MB_2U_LIB.S9S_MB_2U(SCH_1):P12V_OCP_REG_1':
 C_SIGNAL='@s9s_mb_2u_lib.s9s_mb_2u(sch_1):p12v_ocp_reg_1';
NODE_NAME     PC2087 2
 '@S9S_MB_2U_LIB.S9S_MB_2U(SCH_1):PAGE153_I54@PURE_QUANTA.Q_CAP(CHIPS)':
 'B': CDS_PINID='B';
NODE_NAME     PU203 D1
 '@S9S_MB_2U_LIB.S9S_MB_2U(SCH_1):PAGE153_I51@PURE_QUANTA.MAX15090BEWIT(CHIPS)':
 'REG': CDS_PINID='REG';
NET_NAME
'P12V_OCP_REG_2'
 '@S9S_MB_2U_LIB.S9S_MB_2U(SCH_1):P12V_OCP_REG_2':
 C_SIGNAL='@s9s_mb_2u_lib.s9s_mb_2u(sch_1):p12v_ocp_reg_2';
NODE_NAME     PU201 D1
 '@S9S_MB_2U_LIB.S9S_MB_2U(SCH_1):PAGE131_I63@PURE_QUANTA.MAX15090BEWIT(CHIPS)':
 'REG': CDS_PINID='REG';
NODE_NAME     PC2146 2
 '@S9S_MB_2U_LIB.S9S_MB_2U(SCH_1):PAGE131_I62@PURE_QUANTA.Q_CAP(CHIPS)':
 'B': CDS_PINID='B';
NET_NAME
'P12V_OCP_SENSE_1'
 '@S9S_MB_2U_LIB.S9S_MB_2U(SCH_1):P12V_OCP_SENSE_1':
 C_SIGNAL='@s9s_mb_2u_lib.s9s_mb_2u(sch_1):p12v_ocp_sense_1';
NODE_NAME     PR3781 1
 '@S9S_MB_2U_LIB.S9S_MB_2U(SCH_1):PAGE153_I80@PURE_QUANTA.Q_RES(CHIPS)':
 'A': CDS_PINID='A';
NODE_NAME     R3869 1
 '@S9S_MB_2U_LIB.S9S_MB_2U(SCH_1):PAGE153_I87@PURE_QUANTA.Q_RES(CHIPS)':
 'A': CDS_PINID='A';
NODE_NAME     R3870 1
 '@S9S_MB_2U_LIB.S9S_MB_2U(SCH_1):PAGE153_I88@PURE_QUANTA.Q_RES(CHIPS)':
 'A': CDS_PINID='A';
NODE_NAME     PU203 A1
 '@S9S_MB_2U_LIB.S9S_MB_2U(SCH_1):PAGE153_I51@PURE_QUANTA.MAX15090BEWIT(CHIPS)':
 'ISENSE': CDS_PINID='ISENSE';
NET_NAME
'P12V_OCP_SENSE_2'
 '@S9S_MB_2U_LIB.S9S_MB_2U(SCH_1):P12V_OCP_SENSE_2':
 C_SIGNAL='@s9s_mb_2u_lib.s9s_mb_2u(sch_1):p12v_ocp_sense_2';
NODE_NAME     R3868 1
 '@S9S_MB_2U_LIB.S9S_MB_2U(SCH_1):PAGE131_I74@PURE_QUANTA.Q_RES(CHIPS)':
 'A': CDS_PINID='A';
NODE_NAME     PU201 A1
 '@S9S_MB_2U_LIB.S9S_MB_2U(SCH_1):PAGE131_I63@PURE_QUANTA.MAX15090BEWIT(CHIPS)':
 'ISENSE': CDS_PINID='ISENSE';
NODE_NAME     PR3823 1
 '@S9S_MB_2U_LIB.S9S_MB_2U(SCH_1):PAGE131_I72@PURE_QUANTA.Q_RES(CHIPS)':
 'A': CDS_PINID='A';
NODE_NAME     R3867 1
 '@S9S_MB_2U_LIB.S9S_MB_2U(SCH_1):PAGE131_I75@PURE_QUANTA.Q_RES(CHIPS)':
 'A': CDS_PINID='A';
NET_NAME
'P12V_OCP_SFF'
 '@S9S_MB_2U_LIB.S9S_MB_2U(SCH_1):P12V_OCP_SFF':
 C_SIGNAL='@s9s_mb_2u_lib.s9s_mb_2u(sch_1):p12v_ocp_sff',
 CDS_GLOBAL_NET='TRUE';
NODE_NAME     C1213 1
 '@S9S_MB_2U_LIB.S9S_MB_2U(SCH_1):PAGE150_I89@PURE_QUANTA.Q_CAP(CHIPS)':
 'A': CDS_PINID='A';
NODE_NAME     C1232 1
 '@S9S_MB_2U_LIB.S9S_MB_2U(SCH_1):PAGE150_I90@PURE_QUANTA.Q_CAP(CHIPS)':
 'A': CDS_PINID='A';
NODE_NAME     C1233 1
 '@S9S_MB_2U_LIB.S9S_MB_2U(SCH_1):PAGE150_I91@PURE_QUANTA.Q_CAP(CHIPS)':
 'A': CDS_PINID='A';
NODE_NAME     C1234 1
 '@S9S_MB_2U_LIB.S9S_MB_2U(SCH_1):PAGE150_I110@PURE_QUANTA.Q_CAP(CHIPS)':
 'A': CDS_PINID='A';
NODE_NAME     C1235 1
 '@S9S_MB_2U_LIB.S9S_MB_2U(SCH_1):PAGE150_I111@PURE_QUANTA.Q_CAP(CHIPS)':
 'A': CDS_PINID='A';
NODE_NAME     C1236 1
 '@S9S_MB_2U_LIB.S9S_MB_2U(SCH_1):PAGE150_I113@PURE_QUANTA.Q_CAP(CHIPS)':
 'A': CDS_PINID='A';
NODE_NAME     J37 B1
 '@S9S_MB_2U_LIB.S9S_MB_2U(SCH_1):PAGE150_I199@PURE_QUANTA.SCONN168_ME1016810202011(CHIPS)':
 '+12V_EDGE_B1': CDS_PINID='\+12v_edge_b1\';
NODE_NAME     J37 B2
 '@S9S_MB_2U_LIB.S9S_MB_2U(SCH_1):PAGE150_I199@PURE_QUANTA.SCONN168_ME1016810202011(CHIPS)':
 '+12V_EDGE_B2': CDS_PINID='\+12v_edge_b2\';
NODE_NAME     J37 B3
 '@S9S_MB_2U_LIB.S9S_MB_2U(SCH_1):PAGE150_I199@PURE_QUANTA.SCONN168_ME1016810202011(CHIPS)':
 '+12V_EDGE_B3': CDS_PINID='\+12v_edge_b3\';
NODE_NAME     J37 B4
 '@S9S_MB_2U_LIB.S9S_MB_2U(SCH_1):PAGE150_I199@PURE_QUANTA.SCONN168_ME1016810202011(CHIPS)':
 '+12V_EDGE_B4': CDS_PINID='\+12v_edge_b4\';
NODE_NAME     J37 B5
 '@S9S_MB_2U_LIB.S9S_MB_2U(SCH_1):PAGE150_I199@PURE_QUANTA.SCONN168_ME1016810202011(CHIPS)':
 '+12V_EDGE_B5': CDS_PINID='\+12v_edge_b5\';
NODE_NAME     J37 B6
 '@S9S_MB_2U_LIB.S9S_MB_2U(SCH_1):PAGE150_I199@PURE_QUANTA.SCONN168_ME1016810202011(CHIPS)':
 '+12V_EDGE_B6': CDS_PINID='\+12v_edge_b6\';
NODE_NAME     PC2088 1
 '@S9S_MB_2U_LIB.S9S_MB_2U(SCH_1):PAGE153_I81@PURE_QUANTA.Q_CAP(CHIPS)':
 'A': CDS_PINID='A';
NODE_NAME     PC2092 1
 '@S9S_MB_2U_LIB.S9S_MB_2U(SCH_1):PAGE153_I93@PURE_QUANTA.Q_CAP(CHIPS)':
 'A': CDS_PINID='A';
NODE_NAME     PC2082 1
 '@S9S_MB_2U_LIB.S9S_MB_2U(SCH_1):PAGE153_I96@PURE_QUANTA.Q_CAP(CHIPS)':
 'A': CDS_PINID='A';
NODE_NAME     PU203 A4
 '@S9S_MB_2U_LIB.S9S_MB_2U(SCH_1):PAGE153_I51@PURE_QUANTA.MAX15090BEWIT(CHIPS)':
 'OUT_A4': CDS_PINID='OUT_A4';
NODE_NAME     PU203 B4
 '@S9S_MB_2U_LIB.S9S_MB_2U(SCH_1):PAGE153_I51@PURE_QUANTA.MAX15090BEWIT(CHIPS)':
 'OUT_B4': CDS_PINID='OUT_B4';
NODE_NAME     PU203 B6
 '@S9S_MB_2U_LIB.S9S_MB_2U(SCH_1):PAGE153_I51@PURE_QUANTA.MAX15090BEWIT(CHIPS)':
 'OUT_B6': CDS_PINID='OUT_B6';
NODE_NAME     PU203 C4
 '@S9S_MB_2U_LIB.S9S_MB_2U(SCH_1):PAGE153_I51@PURE_QUANTA.MAX15090BEWIT(CHIPS)':
 'OUT_C4': CDS_PINID='OUT_C4';
NODE_NAME     PU203 C6
 '@S9S_MB_2U_LIB.S9S_MB_2U(SCH_1):PAGE153_I51@PURE_QUANTA.MAX15090BEWIT(CHIPS)':
 'OUT_C6': CDS_PINID='OUT_C6';
NODE_NAME     PU203 D4
 '@S9S_MB_2U_LIB.S9S_MB_2U(SCH_1):PAGE153_I51@PURE_QUANTA.MAX15090BEWIT(CHIPS)':
 'OUT_D4': CDS_PINID='OUT_D4';
NODE_NAME     PU203 D6
 '@S9S_MB_2U_LIB.S9S_MB_2U(SCH_1):PAGE153_I51@PURE_QUANTA.MAX15090BEWIT(CHIPS)':
 'OUT_D6': CDS_PINID='OUT_D6';
NODE_NAME     PR4524 1
 '@S9S_MB_2U_LIB.S9S_MB_2U(SCH_1):PAGE153_I84@PURE_QUANTA.Q_RES(CHIPS)':
 'A': CDS_PINID='A';
NODE_NAME     PD102 C
 '@S9S_MB_2U_LIB.S9S_MB_2U(SCH_1):PAGE153_I86@PURE_QUANTA.SCHOTTKY_AC(CHIPS)':
 'C': CDS_PINID='C';
NODE_NAME     PC2080 1
 '@S9S_MB_2U_LIB.S9S_MB_2U(SCH_1):PAGE153_I94@PURE_QUANTA.Q_CAP(CHIPS)':
 'A': CDS_PINID='A';
NODE_NAME     PU204 13
 '@S9S_MB_2U_LIB.S9S_MB_2U(SCH_1):PAGE236_I70@PURE_QUANTA.RS31312R(CHIPS)':
 'VOUT_13': CDS_PINID='VOUT_13';
NODE_NAME     PU204 14
 '@S9S_MB_2U_LIB.S9S_MB_2U(SCH_1):PAGE236_I70@PURE_QUANTA.RS31312R(CHIPS)':
 'VOUT_14': CDS_PINID='VOUT_14';
NODE_NAME     PU204 15
 '@S9S_MB_2U_LIB.S9S_MB_2U(SCH_1):PAGE236_I70@PURE_QUANTA.RS31312R(CHIPS)':
 'VOUT_15': CDS_PINID='VOUT_15';
NODE_NAME     PU204 16
 '@S9S_MB_2U_LIB.S9S_MB_2U(SCH_1):PAGE236_I70@PURE_QUANTA.RS31312R(CHIPS)':
 'VOUT_16': CDS_PINID='VOUT_16';
NODE_NAME     PU204 17
 '@S9S_MB_2U_LIB.S9S_MB_2U(SCH_1):PAGE236_I70@PURE_QUANTA.RS31312R(CHIPS)':
 'VOUT_17': CDS_PINID='VOUT_17';
NODE_NAME     PU204 18
 '@S9S_MB_2U_LIB.S9S_MB_2U(SCH_1):PAGE236_I70@PURE_QUANTA.RS31312R(CHIPS)':
 'VOUT_18': CDS_PINID='VOUT_18';
NODE_NAME     PU204 19
 '@S9S_MB_2U_LIB.S9S_MB_2U(SCH_1):PAGE236_I70@PURE_QUANTA.RS31312R(CHIPS)':
 'VOUT_19': CDS_PINID='VOUT_19';
NODE_NAME     PU204 20
 '@S9S_MB_2U_LIB.S9S_MB_2U(SCH_1):PAGE236_I70@PURE_QUANTA.RS31312R(CHIPS)':
 'VOUT_20': CDS_PINID='VOUT_20';
NODE_NAME     PR3838 1
 '@S9S_MB_2U_LIB.S9S_MB_2U(SCH_1):PAGE236_I77@PURE_QUANTA.Q_RES(CHIPS)':
 'A': CDS_PINID='A';
NODE_NAME     PR3840 1
 '@S9S_MB_2U_LIB.S9S_MB_2U(SCH_1):PAGE236_I85@PURE_QUANTA.Q_RES(CHIPS)':
 'A': CDS_PINID='A';
NODE_NAME     PC2160 1
 '@S9S_MB_2U_LIB.S9S_MB_2U(SCH_1):PAGE236_I91@PURE_QUANTA.Q_CAP(CHIPS)':
 'A': CDS_PINID='A';
NET_NAME
'P12V_OCP_SFF_ISENSE_MAM'
 '@S9S_MB_2U_LIB.S9S_MB_2U(SCH_1):P12V_OCP_SFF_ISENSE_MAM':
 C_SIGNAL='@s9s_mb_2u_lib.s9s_mb_2u(sch_1):p12v_ocp_sff_isense_mam';
NODE_NAME     U193 6
 '@S9S_MB_2U_LIB.S9S_MB_2U(SCH_1):PAGE239_I57@PURE_QUANTA.MAX11617EEET(CHIPS)':
 'AIN1': CDS_PINID='AIN1';
NODE_NAME     C2176 1
 '@S9S_MB_2U_LIB.S9S_MB_2U(SCH_1):PAGE239_I304@PURE_QUANTA.Q_CAP(CHIPS)':
 'A': CDS_PINID='A';
NODE_NAME     R3863 2
 '@S9S_MB_2U_LIB.S9S_MB_2U(SCH_1):PAGE239_I313@PURE_QUANTA.Q_RES(CHIPS)':
 'B': CDS_PINID='B';
NODE_NAME     R3864 2
 '@S9S_MB_2U_LIB.S9S_MB_2U(SCH_1):PAGE239_I314@PURE_QUANTA.Q_RES(CHIPS)':
 'B': CDS_PINID='B';
NET_NAME
'P12V_OCP_SFF_ISENSE_MAM_MAM'
 '@S9S_MB_2U_LIB.S9S_MB_2U(SCH_1):P12V_OCP_SFF_ISENSE_MAM_MAM':
 C_SIGNAL='@s9s_mb_2u_lib.s9s_mb_2u(sch_1):p12v_ocp_sff_isense_mam_mam';
NODE_NAME     R3863 1
 '@S9S_MB_2U_LIB.S9S_MB_2U(SCH_1):PAGE239_I313@PURE_QUANTA.Q_RES(CHIPS)':
 'A': CDS_PINID='A';
NODE_NAME     R3869 2
 '@S9S_MB_2U_LIB.S9S_MB_2U(SCH_1):PAGE153_I87@PURE_QUANTA.Q_RES(CHIPS)':
 'B': CDS_PINID='B';
NET_NAME
'P12V_OCP_SFF_ISENSE_MAM_TIC'
 '@S9S_MB_2U_LIB.S9S_MB_2U(SCH_1):P12V_OCP_SFF_ISENSE_MAM_TIC':
 C_SIGNAL='@s9s_mb_2u_lib.s9s_mb_2u(sch_1):p12v_ocp_sff_isense_mam_tic';
NODE_NAME     R3865 1
 '@S9S_MB_2U_LIB.S9S_MB_2U(SCH_1):PAGE239_I315@PURE_QUANTA.Q_RES(CHIPS)':
 'A': CDS_PINID='A';
NODE_NAME     R3870 2
 '@S9S_MB_2U_LIB.S9S_MB_2U(SCH_1):PAGE153_I88@PURE_QUANTA.Q_RES(CHIPS)':
 'B': CDS_PINID='B';
NET_NAME
'P12V_OCP_SFF_ISENSE_MPS_MAM'
 '@S9S_MB_2U_LIB.S9S_MB_2U(SCH_1):P12V_OCP_SFF_ISENSE_MPS_MAM':
 C_SIGNAL='@s9s_mb_2u_lib.s9s_mb_2u(sch_1):p12v_ocp_sff_isense_mps_mam';
NODE_NAME     R3864 1
 '@S9S_MB_2U_LIB.S9S_MB_2U(SCH_1):PAGE239_I314@PURE_QUANTA.Q_RES(CHIPS)':
 'A': CDS_PINID='A';
NODE_NAME     R3871 2
 '@S9S_MB_2U_LIB.S9S_MB_2U(SCH_1):PAGE236_I82@PURE_QUANTA.Q_RES(CHIPS)':
 'B': CDS_PINID='B';
NET_NAME
'P12V_OCP_SFF_ISENSE_MPS_TIC'
 '@S9S_MB_2U_LIB.S9S_MB_2U(SCH_1):P12V_OCP_SFF_ISENSE_MPS_TIC':
 C_SIGNAL='@s9s_mb_2u_lib.s9s_mb_2u(sch_1):p12v_ocp_sff_isense_mps_tic';
NODE_NAME     R3866 1
 '@S9S_MB_2U_LIB.S9S_MB_2U(SCH_1):PAGE239_I316@PURE_QUANTA.Q_RES(CHIPS)':
 'A': CDS_PINID='A';
NODE_NAME     R3872 2
 '@S9S_MB_2U_LIB.S9S_MB_2U(SCH_1):PAGE236_I81@PURE_QUANTA.Q_RES(CHIPS)':
 'B': CDS_PINID='B';
NET_NAME
'P12V_OCP_SFF_ISENSE_TIC'
 '@S9S_MB_2U_LIB.S9S_MB_2U(SCH_1):P12V_OCP_SFF_ISENSE_TIC':
 C_SIGNAL='@s9s_mb_2u_lib.s9s_mb_2u(sch_1):p12v_ocp_sff_isense_tic';
NODE_NAME     U269 15
 '@S9S_MB_2U_LIB.S9S_MB_2U(SCH_1):PAGE239_I103@PURE_QUANTA.ADC128D818CIMTXNOPB(CHIPS)':
 'IN1': CDS_PINID='IN1';
NODE_NAME     C2178 1
 '@S9S_MB_2U_LIB.S9S_MB_2U(SCH_1):PAGE239_I305@PURE_QUANTA.Q_CAP(CHIPS)':
 'A': CDS_PINID='A';
NODE_NAME     R3865 2
 '@S9S_MB_2U_LIB.S9S_MB_2U(SCH_1):PAGE239_I315@PURE_QUANTA.Q_RES(CHIPS)':
 'B': CDS_PINID='B';
NODE_NAME     R3866 2
 '@S9S_MB_2U_LIB.S9S_MB_2U(SCH_1):PAGE239_I316@PURE_QUANTA.Q_RES(CHIPS)':
 'B': CDS_PINID='B';
NET_NAME
'P12V_OCP_SS_1'
 '@S9S_MB_2U_LIB.S9S_MB_2U(SCH_1):P12V_OCP_SS_1':
 C_SIGNAL='@s9s_mb_2u_lib.s9s_mb_2u(sch_1):p12v_ocp_ss_1';
NODE_NAME     PC2155 1
 '@S9S_MB_2U_LIB.S9S_MB_2U(SCH_1):PAGE236_I63@PURE_QUANTA.Q_CAP(CHIPS)':
 'A': CDS_PINID='A';
NODE_NAME     PU204 6
 '@S9S_MB_2U_LIB.S9S_MB_2U(SCH_1):PAGE236_I70@PURE_QUANTA.RS31312R(CHIPS)':
 'SS': CDS_PINID='SS';
NET_NAME
'P12V_OCP_SS_2'
 '@S9S_MB_2U_LIB.S9S_MB_2U(SCH_1):P12V_OCP_SS_2':
 C_SIGNAL='@s9s_mb_2u_lib.s9s_mb_2u(sch_1):p12v_ocp_ss_2';
NODE_NAME     PC2166 1
 '@S9S_MB_2U_LIB.S9S_MB_2U(SCH_1):PAGE237_I65@PURE_QUANTA.Q_CAP(CHIPS)':
 'A': CDS_PINID='A';
NODE_NAME     PU206 6
 '@S9S_MB_2U_LIB.S9S_MB_2U(SCH_1):PAGE237_I70@PURE_QUANTA.RS31312R(CHIPS)':
 'SS': CDS_PINID='SS';
NET_NAME
'P12V_OCP_TIMER_1'
 '@S9S_MB_2U_LIB.S9S_MB_2U(SCH_1):P12V_OCP_TIMER_1':
 C_SIGNAL='@s9s_mb_2u_lib.s9s_mb_2u(sch_1):p12v_ocp_timer_1';
NODE_NAME     PC2153 1
 '@S9S_MB_2U_LIB.S9S_MB_2U(SCH_1):PAGE236_I60@PURE_QUANTA.Q_CAP(CHIPS)':
 'A': CDS_PINID='A';
NODE_NAME     PU204 4
 '@S9S_MB_2U_LIB.S9S_MB_2U(SCH_1):PAGE236_I70@PURE_QUANTA.RS31312R(CHIPS)':
 'TIMER': CDS_PINID='TIMER';
NET_NAME
'P12V_OCP_TIMER_2'
 '@S9S_MB_2U_LIB.S9S_MB_2U(SCH_1):P12V_OCP_TIMER_2':
 C_SIGNAL='@s9s_mb_2u_lib.s9s_mb_2u(sch_1):p12v_ocp_timer_2';
NODE_NAME     PC2164 1
 '@S9S_MB_2U_LIB.S9S_MB_2U(SCH_1):PAGE237_I62@PURE_QUANTA.Q_CAP(CHIPS)':
 'A': CDS_PINID='A';
NODE_NAME     PU206 4
 '@S9S_MB_2U_LIB.S9S_MB_2U(SCH_1):PAGE237_I70@PURE_QUANTA.RS31312R(CHIPS)':
 'TIMER': CDS_PINID='TIMER';
NET_NAME
'P12V_OCP_UV_1'
 '@S9S_MB_2U_LIB.S9S_MB_2U(SCH_1):P12V_OCP_UV_1':
 C_SIGNAL='@s9s_mb_2u_lib.s9s_mb_2u(sch_1):p12v_ocp_uv_1';
NODE_NAME     PR3787 1
 '@S9S_MB_2U_LIB.S9S_MB_2U(SCH_1):PAGE153_I41@PURE_QUANTA.Q_RES(CHIPS)':
 'A': CDS_PINID='A';
NODE_NAME     R3784 2
 '@S9S_MB_2U_LIB.S9S_MB_2U(SCH_1):PAGE153_I39@PURE_QUANTA.Q_RES(CHIPS)':
 'B': CDS_PINID='B';
NODE_NAME     PR3786 2
 '@S9S_MB_2U_LIB.S9S_MB_2U(SCH_1):PAGE153_I42@PURE_QUANTA.Q_RES(CHIPS)':
 'B': CDS_PINID='B';
NODE_NAME     PU203 D2
 '@S9S_MB_2U_LIB.S9S_MB_2U(SCH_1):PAGE153_I51@PURE_QUANTA.MAX15090BEWIT(CHIPS)':
 'UV': CDS_PINID='UV';
NET_NAME
'P12V_OCP_UV_1_R'
 '@S9S_MB_2U_LIB.S9S_MB_2U(SCH_1):P12V_OCP_UV_1_R':
 C_SIGNAL='@s9s_mb_2u_lib.s9s_mb_2u(sch_1):p12v_ocp_uv_1_r';
NODE_NAME     Q123 3
 '@S9S_MB_2U_LIB.S9S_MB_2U(SCH_1):PAGE153_I17@PURE_QUANTA.MOSFET_NCH_DUAL(CHIPS)':
 'D2': CDS_PINID='D2';
NODE_NAME     R3784 1
 '@S9S_MB_2U_LIB.S9S_MB_2U(SCH_1):PAGE153_I39@PURE_QUANTA.Q_RES(CHIPS)':
 'A': CDS_PINID='A';
NET_NAME
'P12V_OCP_UV_2'
 '@S9S_MB_2U_LIB.S9S_MB_2U(SCH_1):P12V_OCP_UV_2':
 C_SIGNAL='@s9s_mb_2u_lib.s9s_mb_2u(sch_1):p12v_ocp_uv_2';
NODE_NAME     PR3805 2
 '@S9S_MB_2U_LIB.S9S_MB_2U(SCH_1):PAGE131_I33@PURE_QUANTA.Q_RES(CHIPS)':
 'B': CDS_PINID='B';
NODE_NAME     PR3806 1
 '@S9S_MB_2U_LIB.S9S_MB_2U(SCH_1):PAGE131_I32@PURE_QUANTA.Q_RES(CHIPS)':
 'A': CDS_PINID='A';
NODE_NAME     PU201 D2
 '@S9S_MB_2U_LIB.S9S_MB_2U(SCH_1):PAGE131_I63@PURE_QUANTA.MAX15090BEWIT(CHIPS)':
 'UV': CDS_PINID='UV';
NODE_NAME     R3827 2
 '@S9S_MB_2U_LIB.S9S_MB_2U(SCH_1):PAGE131_I30@PURE_QUANTA.Q_RES(CHIPS)':
 'B': CDS_PINID='B';
NET_NAME
'P12V_OCP_UV_2_R'
 '@S9S_MB_2U_LIB.S9S_MB_2U(SCH_1):P12V_OCP_UV_2_R':
 C_SIGNAL='@s9s_mb_2u_lib.s9s_mb_2u(sch_1):p12v_ocp_uv_2_r';
NODE_NAME     Q118 3
 '@S9S_MB_2U_LIB.S9S_MB_2U(SCH_1):PAGE131_I16@PURE_QUANTA.MOSFET_NCH_DUAL(CHIPS)':
 'D2': CDS_PINID='D2';
NODE_NAME     R3827 1
 '@S9S_MB_2U_LIB.S9S_MB_2U(SCH_1):PAGE131_I30@PURE_QUANTA.Q_RES(CHIPS)':
 'A': CDS_PINID='A';
NET_NAME
'P12V_OCP_V3_2'
 '@S9S_MB_2U_LIB.S9S_MB_2U(SCH_1):P12V_OCP_V3_2':
 C_SIGNAL='@s9s_mb_2u_lib.s9s_mb_2u(sch_1):p12v_ocp_v3_2',
 CDS_GLOBAL_NET='TRUE';
NODE_NAME     C1829 1
 '@S9S_MB_2U_LIB.S9S_MB_2U(SCH_1):PAGE146_I166@PURE_QUANTA.Q_CAP(CHIPS)':
 'A': CDS_PINID='A';
NODE_NAME     C1830 1
 '@S9S_MB_2U_LIB.S9S_MB_2U(SCH_1):PAGE146_I167@PURE_QUANTA.Q_CAP(CHIPS)':
 'A': CDS_PINID='A';
NODE_NAME     C1831 1
 '@S9S_MB_2U_LIB.S9S_MB_2U(SCH_1):PAGE146_I168@PURE_QUANTA.Q_CAP(CHIPS)':
 'A': CDS_PINID='A';
NODE_NAME     C1833 1
 '@S9S_MB_2U_LIB.S9S_MB_2U(SCH_1):PAGE146_I169@PURE_QUANTA.Q_CAP(CHIPS)':
 'A': CDS_PINID='A';
NODE_NAME     C1834 1
 '@S9S_MB_2U_LIB.S9S_MB_2U(SCH_1):PAGE146_I171@PURE_QUANTA.Q_CAP(CHIPS)':
 'A': CDS_PINID='A';
NODE_NAME     C1832 1
 '@S9S_MB_2U_LIB.S9S_MB_2U(SCH_1):PAGE146_I179@PURE_QUANTA.Q_CAP(CHIPS)':
 'A': CDS_PINID='A';
NODE_NAME     C1839 1
 '@S9S_MB_2U_LIB.S9S_MB_2U(SCH_1):PAGE146_I180@PURE_QUANTA.Q_CAP(CHIPS)':
 'A': CDS_PINID='A';
NODE_NAME     J35 B1
 '@S9S_MB_2U_LIB.S9S_MB_2U(SCH_1):PAGE146_I303@PURE_QUANTA.SCONN168_ME1016810202011(CHIPS)':
 '+12V_EDGE_B1': CDS_PINID='\+12v_edge_b1\';
NODE_NAME     J35 B2
 '@S9S_MB_2U_LIB.S9S_MB_2U(SCH_1):PAGE146_I303@PURE_QUANTA.SCONN168_ME1016810202011(CHIPS)':
 '+12V_EDGE_B2': CDS_PINID='\+12v_edge_b2\';
NODE_NAME     J35 B3
 '@S9S_MB_2U_LIB.S9S_MB_2U(SCH_1):PAGE146_I303@PURE_QUANTA.SCONN168_ME1016810202011(CHIPS)':
 '+12V_EDGE_B3': CDS_PINID='\+12v_edge_b3\';
NODE_NAME     J35 B4
 '@S9S_MB_2U_LIB.S9S_MB_2U(SCH_1):PAGE146_I303@PURE_QUANTA.SCONN168_ME1016810202011(CHIPS)':
 '+12V_EDGE_B4': CDS_PINID='\+12v_edge_b4\';
NODE_NAME     J35 B5
 '@S9S_MB_2U_LIB.S9S_MB_2U(SCH_1):PAGE146_I303@PURE_QUANTA.SCONN168_ME1016810202011(CHIPS)':
 '+12V_EDGE_B5': CDS_PINID='\+12v_edge_b5\';
NODE_NAME     J35 B6
 '@S9S_MB_2U_LIB.S9S_MB_2U(SCH_1):PAGE146_I303@PURE_QUANTA.SCONN168_ME1016810202011(CHIPS)':
 '+12V_EDGE_B6': CDS_PINID='\+12v_edge_b6\';
NODE_NAME     PU201 A4
 '@S9S_MB_2U_LIB.S9S_MB_2U(SCH_1):PAGE131_I63@PURE_QUANTA.MAX15090BEWIT(CHIPS)':
 'OUT_A4': CDS_PINID='OUT_A4';
NODE_NAME     PU201 B4
 '@S9S_MB_2U_LIB.S9S_MB_2U(SCH_1):PAGE131_I63@PURE_QUANTA.MAX15090BEWIT(CHIPS)':
 'OUT_B4': CDS_PINID='OUT_B4';
NODE_NAME     PU201 B6
 '@S9S_MB_2U_LIB.S9S_MB_2U(SCH_1):PAGE131_I63@PURE_QUANTA.MAX15090BEWIT(CHIPS)':
 'OUT_B6': CDS_PINID='OUT_B6';
NODE_NAME     PU201 C4
 '@S9S_MB_2U_LIB.S9S_MB_2U(SCH_1):PAGE131_I63@PURE_QUANTA.MAX15090BEWIT(CHIPS)':
 'OUT_C4': CDS_PINID='OUT_C4';
NODE_NAME     PU201 C6
 '@S9S_MB_2U_LIB.S9S_MB_2U(SCH_1):PAGE131_I63@PURE_QUANTA.MAX15090BEWIT(CHIPS)':
 'OUT_C6': CDS_PINID='OUT_C6';
NODE_NAME     PU201 D4
 '@S9S_MB_2U_LIB.S9S_MB_2U(SCH_1):PAGE131_I63@PURE_QUANTA.MAX15090BEWIT(CHIPS)':
 'OUT_D4': CDS_PINID='OUT_D4';
NODE_NAME     PU201 D6
 '@S9S_MB_2U_LIB.S9S_MB_2U(SCH_1):PAGE131_I63@PURE_QUANTA.MAX15090BEWIT(CHIPS)':
 'OUT_D6': CDS_PINID='OUT_D6';
NODE_NAME     C2148 1
 '@S9S_MB_2U_LIB.S9S_MB_2U(SCH_1):PAGE131_I73@PURE_QUANTA.Q_CAP(CHIPS)':
 'A': CDS_PINID='A';
NODE_NAME     PD108 C
 '@S9S_MB_2U_LIB.S9S_MB_2U(SCH_1):PAGE131_I93@PURE_QUANTA.SCHOTTKY_AC(CHIPS)':
 'C': CDS_PINID='C';
NODE_NAME     PC2141 1
 '@S9S_MB_2U_LIB.S9S_MB_2U(SCH_1):PAGE131_I100@PURE_QUANTA.Q_CAP(CHIPS)':
 'A': CDS_PINID='A';
NODE_NAME     PC2143 1
 '@S9S_MB_2U_LIB.S9S_MB_2U(SCH_1):PAGE131_I102@PURE_QUANTA.Q_CAP(CHIPS)':
 'A': CDS_PINID='A';
NODE_NAME     PR4522 1
 '@S9S_MB_2U_LIB.S9S_MB_2U(SCH_1):PAGE131_I77@PURE_QUANTA.Q_RES(CHIPS)':
 'A': CDS_PINID='A';
NODE_NAME     PC2152 1
 '@S9S_MB_2U_LIB.S9S_MB_2U(SCH_1):PAGE131_I98@PURE_QUANTA.Q_CAP(CHIPS)':
 'A': CDS_PINID='A';
NODE_NAME     PU206 13
 '@S9S_MB_2U_LIB.S9S_MB_2U(SCH_1):PAGE237_I70@PURE_QUANTA.RS31312R(CHIPS)':
 'VOUT_13': CDS_PINID='VOUT_13';
NODE_NAME     PU206 14
 '@S9S_MB_2U_LIB.S9S_MB_2U(SCH_1):PAGE237_I70@PURE_QUANTA.RS31312R(CHIPS)':
 'VOUT_14': CDS_PINID='VOUT_14';
NODE_NAME     PU206 15
 '@S9S_MB_2U_LIB.S9S_MB_2U(SCH_1):PAGE237_I70@PURE_QUANTA.RS31312R(CHIPS)':
 'VOUT_15': CDS_PINID='VOUT_15';
NODE_NAME     PU206 16
 '@S9S_MB_2U_LIB.S9S_MB_2U(SCH_1):PAGE237_I70@PURE_QUANTA.RS31312R(CHIPS)':
 'VOUT_16': CDS_PINID='VOUT_16';
NODE_NAME     PU206 17
 '@S9S_MB_2U_LIB.S9S_MB_2U(SCH_1):PAGE237_I70@PURE_QUANTA.RS31312R(CHIPS)':
 'VOUT_17': CDS_PINID='VOUT_17';
NODE_NAME     PU206 18
 '@S9S_MB_2U_LIB.S9S_MB_2U(SCH_1):PAGE237_I70@PURE_QUANTA.RS31312R(CHIPS)':
 'VOUT_18': CDS_PINID='VOUT_18';
NODE_NAME     PU206 19
 '@S9S_MB_2U_LIB.S9S_MB_2U(SCH_1):PAGE237_I70@PURE_QUANTA.RS31312R(CHIPS)':
 'VOUT_19': CDS_PINID='VOUT_19';
NODE_NAME     PU206 20
 '@S9S_MB_2U_LIB.S9S_MB_2U(SCH_1):PAGE237_I70@PURE_QUANTA.RS31312R(CHIPS)':
 'VOUT_20': CDS_PINID='VOUT_20';
NODE_NAME     PR3850 1
 '@S9S_MB_2U_LIB.S9S_MB_2U(SCH_1):PAGE237_I77@PURE_QUANTA.Q_RES(CHIPS)':
 'A': CDS_PINID='A';
NODE_NAME     PR3852 1
 '@S9S_MB_2U_LIB.S9S_MB_2U(SCH_1):PAGE237_I85@PURE_QUANTA.Q_RES(CHIPS)':
 'A': CDS_PINID='A';
NODE_NAME     PC2174 1
 '@S9S_MB_2U_LIB.S9S_MB_2U(SCH_1):PAGE237_I91@PURE_QUANTA.Q_CAP(CHIPS)':
 'A': CDS_PINID='A';
NET_NAME
'P12V_OCP_V3_2_EN_2_R3'
 '@S9S_MB_2U_LIB.S9S_MB_2U(SCH_1):P12V_OCP_V3_2_EN_2_R3':
 C_SIGNAL='@s9s_mb_2u_lib.s9s_mb_2u(sch_1):p12v_ocp_v3_2_en_2_r3';
NODE_NAME     R3630 2
 '@S9S_MB_2U_LIB.S9S_MB_2U(SCH_1):PAGE237_I66@PURE_QUANTA.Q_RES(CHIPS)':
 'B': CDS_PINID='B';
NODE_NAME     PU206 1
 '@S9S_MB_2U_LIB.S9S_MB_2U(SCH_1):PAGE237_I70@PURE_QUANTA.RS31312R(CHIPS)':
 'EN': CDS_PINID='EN';
NET_NAME
'P12V_OCP_V3_2_ISENSE_MAM'
 '@S9S_MB_2U_LIB.S9S_MB_2U(SCH_1):P12V_OCP_V3_2_ISENSE_MAM':
 C_SIGNAL='@s9s_mb_2u_lib.s9s_mb_2u(sch_1):p12v_ocp_v3_2_isense_mam';
NODE_NAME     U193 7
 '@S9S_MB_2U_LIB.S9S_MB_2U(SCH_1):PAGE239_I57@PURE_QUANTA.MAX11617EEET(CHIPS)':
 'AIN2': CDS_PINID='AIN2';
NODE_NAME     C2175 1
 '@S9S_MB_2U_LIB.S9S_MB_2U(SCH_1):PAGE239_I309@PURE_QUANTA.Q_CAP(CHIPS)':
 'A': CDS_PINID='A';
NODE_NAME     R3859 2
 '@S9S_MB_2U_LIB.S9S_MB_2U(SCH_1):PAGE239_I321@PURE_QUANTA.Q_RES(CHIPS)':
 'B': CDS_PINID='B';
NODE_NAME     R3860 2
 '@S9S_MB_2U_LIB.S9S_MB_2U(SCH_1):PAGE239_I322@PURE_QUANTA.Q_RES(CHIPS)':
 'B': CDS_PINID='B';
NET_NAME
'P12V_OCP_V3_2_ISENSE_MAM_MAM'
 '@S9S_MB_2U_LIB.S9S_MB_2U(SCH_1):P12V_OCP_V3_2_ISENSE_MAM_MAM':
 C_SIGNAL='@s9s_mb_2u_lib.s9s_mb_2u(sch_1):p12v_ocp_v3_2_isense_mam_mam';
NODE_NAME     R3859 1
 '@S9S_MB_2U_LIB.S9S_MB_2U(SCH_1):PAGE239_I321@PURE_QUANTA.Q_RES(CHIPS)':
 'A': CDS_PINID='A';
NODE_NAME     R3867 2
 '@S9S_MB_2U_LIB.S9S_MB_2U(SCH_1):PAGE131_I75@PURE_QUANTA.Q_RES(CHIPS)':
 'B': CDS_PINID='B';
NET_NAME
'P12V_OCP_V3_2_ISENSE_MAM_TIC'
 '@S9S_MB_2U_LIB.S9S_MB_2U(SCH_1):P12V_OCP_V3_2_ISENSE_MAM_TIC':
 C_SIGNAL='@s9s_mb_2u_lib.s9s_mb_2u(sch_1):p12v_ocp_v3_2_isense_mam_tic';
NODE_NAME     R3861 1
 '@S9S_MB_2U_LIB.S9S_MB_2U(SCH_1):PAGE239_I323@PURE_QUANTA.Q_RES(CHIPS)':
 'A': CDS_PINID='A';
NODE_NAME     R3868 2
 '@S9S_MB_2U_LIB.S9S_MB_2U(SCH_1):PAGE131_I74@PURE_QUANTA.Q_RES(CHIPS)':
 'B': CDS_PINID='B';
NET_NAME
'P12V_OCP_V3_2_ISENSE_MPS_MAM'
 '@S9S_MB_2U_LIB.S9S_MB_2U(SCH_1):P12V_OCP_V3_2_ISENSE_MPS_MAM':
 C_SIGNAL='@s9s_mb_2u_lib.s9s_mb_2u(sch_1):p12v_ocp_v3_2_isense_mps_mam';
NODE_NAME     R3860 1
 '@S9S_MB_2U_LIB.S9S_MB_2U(SCH_1):PAGE239_I322@PURE_QUANTA.Q_RES(CHIPS)':
 'A': CDS_PINID='A';
NODE_NAME     R3873 2
 '@S9S_MB_2U_LIB.S9S_MB_2U(SCH_1):PAGE237_I81@PURE_QUANTA.Q_RES(CHIPS)':
 'B': CDS_PINID='B';
NET_NAME
'P12V_OCP_V3_2_ISENSE_MPS_TIC'
 '@S9S_MB_2U_LIB.S9S_MB_2U(SCH_1):P12V_OCP_V3_2_ISENSE_MPS_TIC':
 C_SIGNAL='@s9s_mb_2u_lib.s9s_mb_2u(sch_1):p12v_ocp_v3_2_isense_mps_tic';
NODE_NAME     R3862 1
 '@S9S_MB_2U_LIB.S9S_MB_2U(SCH_1):PAGE239_I324@PURE_QUANTA.Q_RES(CHIPS)':
 'A': CDS_PINID='A';
NODE_NAME     R3874 2
 '@S9S_MB_2U_LIB.S9S_MB_2U(SCH_1):PAGE237_I80@PURE_QUANTA.Q_RES(CHIPS)':
 'B': CDS_PINID='B';
NET_NAME
'P12V_OCP_V3_2_ISENSE_TIC'
 '@S9S_MB_2U_LIB.S9S_MB_2U(SCH_1):P12V_OCP_V3_2_ISENSE_TIC':
 C_SIGNAL='@s9s_mb_2u_lib.s9s_mb_2u(sch_1):p12v_ocp_v3_2_isense_tic';
NODE_NAME     U269 14
 '@S9S_MB_2U_LIB.S9S_MB_2U(SCH_1):PAGE239_I103@PURE_QUANTA.ADC128D818CIMTXNOPB(CHIPS)':
 'IN2': CDS_PINID='IN2';
NODE_NAME     C2177 1
 '@S9S_MB_2U_LIB.S9S_MB_2U(SCH_1):PAGE239_I311@PURE_QUANTA.Q_CAP(CHIPS)':
 'A': CDS_PINID='A';
NODE_NAME     R3861 2
 '@S9S_MB_2U_LIB.S9S_MB_2U(SCH_1):PAGE239_I323@PURE_QUANTA.Q_RES(CHIPS)':
 'B': CDS_PINID='B';
NODE_NAME     R3862 2
 '@S9S_MB_2U_LIB.S9S_MB_2U(SCH_1):PAGE239_I324@PURE_QUANTA.Q_RES(CHIPS)':
 'B': CDS_PINID='B';
NET_NAME
'P12V_OCP_VCC_1'
 '@S9S_MB_2U_LIB.S9S_MB_2U(SCH_1):P12V_OCP_VCC_1':
 C_SIGNAL='@s9s_mb_2u_lib.s9s_mb_2u(sch_1):p12v_ocp_vcc_1';
NODE_NAME     PC2085 1
 '@S9S_MB_2U_LIB.S9S_MB_2U(SCH_1):PAGE153_I55@PURE_QUANTA.Q_CAP(CHIPS)':
 'A': CDS_PINID='A';
NODE_NAME     PU203 A2
 '@S9S_MB_2U_LIB.S9S_MB_2U(SCH_1):PAGE153_I51@PURE_QUANTA.MAX15090BEWIT(CHIPS)':
 'VCC': CDS_PINID='VCC';
NODE_NAME     PR3792 2
 '@S9S_MB_2U_LIB.S9S_MB_2U(SCH_1):PAGE153_I56@PURE_QUANTA.Q_RES(CHIPS)':
 'B': CDS_PINID='B';
NET_NAME
'P12V_OCP_VCC_2'
 '@S9S_MB_2U_LIB.S9S_MB_2U(SCH_1):P12V_OCP_VCC_2':
 C_SIGNAL='@s9s_mb_2u_lib.s9s_mb_2u(sch_1):p12v_ocp_vcc_2';
NODE_NAME     PR3830 2
 '@S9S_MB_2U_LIB.S9S_MB_2U(SCH_1):PAGE131_I85@PURE_QUANTA.Q_RES(CHIPS)':
 'B': CDS_PINID='B';
NODE_NAME     PU201 A2
 '@S9S_MB_2U_LIB.S9S_MB_2U(SCH_1):PAGE131_I63@PURE_QUANTA.MAX15090BEWIT(CHIPS)':
 'VCC': CDS_PINID='VCC';
NODE_NAME     PC2098 1
 '@S9S_MB_2U_LIB.S9S_MB_2U(SCH_1):PAGE131_I61@PURE_QUANTA.Q_CAP(CHIPS)':
 'A': CDS_PINID='A';
NET_NAME
'P12V_PSU'
 '@S9S_MB_2U_LIB.S9S_MB_2U(SCH_1):P12V_PSU':
 C_SIGNAL='@s9s_mb_2u_lib.s9s_mb_2u(sch_1):p12v_psu',
 CDS_GLOBAL_NET='TRUE';
NODE_NAME     PU297 9
 '@S9S_MB_2U_LIB.S9S_MB_2U(SCH_1):PAGE325_I17@PURE_QUANTA.MP5991GLUZ(CHIPS)':
 'VIN1': CDS_PINID='VIN1';
NODE_NAME     PU297 10
 '@S9S_MB_2U_LIB.S9S_MB_2U(SCH_1):PAGE325_I17@PURE_QUANTA.MP5991GLUZ(CHIPS)':
 'VIN2': CDS_PINID='VIN2';
NODE_NAME     PU297 11
 '@S9S_MB_2U_LIB.S9S_MB_2U(SCH_1):PAGE325_I17@PURE_QUANTA.MP5991GLUZ(CHIPS)':
 'VIN3': CDS_PINID='VIN3';
NODE_NAME     PU297 12
 '@S9S_MB_2U_LIB.S9S_MB_2U(SCH_1):PAGE325_I17@PURE_QUANTA.MP5991GLUZ(CHIPS)':
 'VIN4': CDS_PINID='VIN4';
NODE_NAME     PU297 13
 '@S9S_MB_2U_LIB.S9S_MB_2U(SCH_1):PAGE325_I17@PURE_QUANTA.MP5991GLUZ(CHIPS)':
 'VIN5': CDS_PINID='VIN5';
NODE_NAME     PU297 14
 '@S9S_MB_2U_LIB.S9S_MB_2U(SCH_1):PAGE325_I17@PURE_QUANTA.MP5991GLUZ(CHIPS)':
 'VIN6': CDS_PINID='VIN6';
NODE_NAME     PU297 15
 '@S9S_MB_2U_LIB.S9S_MB_2U(SCH_1):PAGE325_I17@PURE_QUANTA.MP5991GLUZ(CHIPS)':
 'VIN7': CDS_PINID='VIN7';
NODE_NAME     PU297 16
 '@S9S_MB_2U_LIB.S9S_MB_2U(SCH_1):PAGE325_I17@PURE_QUANTA.MP5991GLUZ(CHIPS)':
 'VIN8': CDS_PINID='VIN8';
NODE_NAME     PU297 33
 '@S9S_MB_2U_LIB.S9S_MB_2U(SCH_1):PAGE325_I17@PURE_QUANTA.MP5991GLUZ(CHIPS)':
 'VIN9': CDS_PINID='VIN9';
NODE_NAME     PR3926 1
 '@S9S_MB_2U_LIB.S9S_MB_2U(SCH_1):PAGE303_I52@PURE_QUANTA.Q_RES(CHIPS)':
 'A': CDS_PINID='A';
NODE_NAME     PU289 1
 '@S9S_MB_2U_LIB.S9S_MB_2U(SCH_1):PAGE303_I56@PURE_QUANTA.MP5990GMA1111Z(CHIPS)':
 'VIN1': CDS_PINID='VIN1';
NODE_NAME     PU289 2
 '@S9S_MB_2U_LIB.S9S_MB_2U(SCH_1):PAGE303_I56@PURE_QUANTA.MP5990GMA1111Z(CHIPS)':
 'VIN2': CDS_PINID='VIN2';
NODE_NAME     PU289 3
 '@S9S_MB_2U_LIB.S9S_MB_2U(SCH_1):PAGE303_I56@PURE_QUANTA.MP5990GMA1111Z(CHIPS)':
 'VIN3': CDS_PINID='VIN3';
NODE_NAME     PU289 4
 '@S9S_MB_2U_LIB.S9S_MB_2U(SCH_1):PAGE303_I56@PURE_QUANTA.MP5990GMA1111Z(CHIPS)':
 'VIN4': CDS_PINID='VIN4';
NODE_NAME     PU289 5
 '@S9S_MB_2U_LIB.S9S_MB_2U(SCH_1):PAGE303_I56@PURE_QUANTA.MP5990GMA1111Z(CHIPS)':
 'VIN5': CDS_PINID='VIN5';
NODE_NAME     PU289 6
 '@S9S_MB_2U_LIB.S9S_MB_2U(SCH_1):PAGE303_I56@PURE_QUANTA.MP5990GMA1111Z(CHIPS)':
 'VIN6': CDS_PINID='VIN6';
NODE_NAME     PU289 7
 '@S9S_MB_2U_LIB.S9S_MB_2U(SCH_1):PAGE303_I56@PURE_QUANTA.MP5990GMA1111Z(CHIPS)':
 'VIN7': CDS_PINID='VIN7';
NODE_NAME     PU289 8
 '@S9S_MB_2U_LIB.S9S_MB_2U(SCH_1):PAGE303_I56@PURE_QUANTA.MP5990GMA1111Z(CHIPS)':
 'VIN8': CDS_PINID='VIN8';
NODE_NAME     PU289 42
 '@S9S_MB_2U_LIB.S9S_MB_2U(SCH_1):PAGE303_I56@PURE_QUANTA.MP5990GMA1111Z(CHIPS)':
 'VIN9': CDS_PINID='VIN9';
NODE_NAME     PU289 43
 '@S9S_MB_2U_LIB.S9S_MB_2U(SCH_1):PAGE303_I56@PURE_QUANTA.MP5990GMA1111Z(CHIPS)':
 'VIN10': CDS_PINID='VIN10';
NODE_NAME     PU296 9
 '@S9S_MB_2U_LIB.S9S_MB_2U(SCH_1):PAGE325_I35@PURE_QUANTA.MP5991GLUZ(CHIPS)':
 'VIN1': CDS_PINID='VIN1';
NODE_NAME     PU296 10
 '@S9S_MB_2U_LIB.S9S_MB_2U(SCH_1):PAGE325_I35@PURE_QUANTA.MP5991GLUZ(CHIPS)':
 'VIN2': CDS_PINID='VIN2';
NODE_NAME     PU296 11
 '@S9S_MB_2U_LIB.S9S_MB_2U(SCH_1):PAGE325_I35@PURE_QUANTA.MP5991GLUZ(CHIPS)':
 'VIN3': CDS_PINID='VIN3';
NODE_NAME     PU296 12
 '@S9S_MB_2U_LIB.S9S_MB_2U(SCH_1):PAGE325_I35@PURE_QUANTA.MP5991GLUZ(CHIPS)':
 'VIN4': CDS_PINID='VIN4';
NODE_NAME     PU296 13
 '@S9S_MB_2U_LIB.S9S_MB_2U(SCH_1):PAGE325_I35@PURE_QUANTA.MP5991GLUZ(CHIPS)':
 'VIN5': CDS_PINID='VIN5';
NODE_NAME     PU296 14
 '@S9S_MB_2U_LIB.S9S_MB_2U(SCH_1):PAGE325_I35@PURE_QUANTA.MP5991GLUZ(CHIPS)':
 'VIN6': CDS_PINID='VIN6';
NODE_NAME     PU296 15
 '@S9S_MB_2U_LIB.S9S_MB_2U(SCH_1):PAGE325_I35@PURE_QUANTA.MP5991GLUZ(CHIPS)':
 'VIN7': CDS_PINID='VIN7';
NODE_NAME     PU296 16
 '@S9S_MB_2U_LIB.S9S_MB_2U(SCH_1):PAGE325_I35@PURE_QUANTA.MP5991GLUZ(CHIPS)':
 'VIN8': CDS_PINID='VIN8';
NODE_NAME     PU296 33
 '@S9S_MB_2U_LIB.S9S_MB_2U(SCH_1):PAGE325_I35@PURE_QUANTA.MP5991GLUZ(CHIPS)':
 'VIN9': CDS_PINID='VIN9';
NODE_NAME     PC2188 1
 '@S9S_MB_2U_LIB.S9S_MB_2U(SCH_1):PAGE303_I51@PURE_QUANTA.Q_CAP(CHIPS)':
 'A': CDS_PINID='A';
NODE_NAME     PU287 9
 '@S9S_MB_2U_LIB.S9S_MB_2U(SCH_1):PAGE301_I35@PURE_QUANTA.MP5991GLUZ(CHIPS)':
 'VIN1': CDS_PINID='VIN1';
NODE_NAME     PU287 10
 '@S9S_MB_2U_LIB.S9S_MB_2U(SCH_1):PAGE301_I35@PURE_QUANTA.MP5991GLUZ(CHIPS)':
 'VIN2': CDS_PINID='VIN2';
NODE_NAME     PU287 11
 '@S9S_MB_2U_LIB.S9S_MB_2U(SCH_1):PAGE301_I35@PURE_QUANTA.MP5991GLUZ(CHIPS)':
 'VIN3': CDS_PINID='VIN3';
NODE_NAME     PU287 12
 '@S9S_MB_2U_LIB.S9S_MB_2U(SCH_1):PAGE301_I35@PURE_QUANTA.MP5991GLUZ(CHIPS)':
 'VIN4': CDS_PINID='VIN4';
NODE_NAME     PU287 13
 '@S9S_MB_2U_LIB.S9S_MB_2U(SCH_1):PAGE301_I35@PURE_QUANTA.MP5991GLUZ(CHIPS)':
 'VIN5': CDS_PINID='VIN5';
NODE_NAME     PU287 14
 '@S9S_MB_2U_LIB.S9S_MB_2U(SCH_1):PAGE301_I35@PURE_QUANTA.MP5991GLUZ(CHIPS)':
 'VIN6': CDS_PINID='VIN6';
NODE_NAME     PU287 15
 '@S9S_MB_2U_LIB.S9S_MB_2U(SCH_1):PAGE301_I35@PURE_QUANTA.MP5991GLUZ(CHIPS)':
 'VIN7': CDS_PINID='VIN7';
NODE_NAME     PU287 16
 '@S9S_MB_2U_LIB.S9S_MB_2U(SCH_1):PAGE301_I35@PURE_QUANTA.MP5991GLUZ(CHIPS)':
 'VIN8': CDS_PINID='VIN8';
NODE_NAME     PU287 33
 '@S9S_MB_2U_LIB.S9S_MB_2U(SCH_1):PAGE301_I35@PURE_QUANTA.MP5991GLUZ(CHIPS)':
 'VIN9': CDS_PINID='VIN9';
NODE_NAME     PU288 9
 '@S9S_MB_2U_LIB.S9S_MB_2U(SCH_1):PAGE301_I14@PURE_QUANTA.MP5991GLUZ(CHIPS)':
 'VIN1': CDS_PINID='VIN1';
NODE_NAME     PU288 10
 '@S9S_MB_2U_LIB.S9S_MB_2U(SCH_1):PAGE301_I14@PURE_QUANTA.MP5991GLUZ(CHIPS)':
 'VIN2': CDS_PINID='VIN2';
NODE_NAME     PU288 11
 '@S9S_MB_2U_LIB.S9S_MB_2U(SCH_1):PAGE301_I14@PURE_QUANTA.MP5991GLUZ(CHIPS)':
 'VIN3': CDS_PINID='VIN3';
NODE_NAME     PU288 12
 '@S9S_MB_2U_LIB.S9S_MB_2U(SCH_1):PAGE301_I14@PURE_QUANTA.MP5991GLUZ(CHIPS)':
 'VIN4': CDS_PINID='VIN4';
NODE_NAME     PU288 13
 '@S9S_MB_2U_LIB.S9S_MB_2U(SCH_1):PAGE301_I14@PURE_QUANTA.MP5991GLUZ(CHIPS)':
 'VIN5': CDS_PINID='VIN5';
NODE_NAME     PU288 14
 '@S9S_MB_2U_LIB.S9S_MB_2U(SCH_1):PAGE301_I14@PURE_QUANTA.MP5991GLUZ(CHIPS)':
 'VIN6': CDS_PINID='VIN6';
NODE_NAME     PU288 15
 '@S9S_MB_2U_LIB.S9S_MB_2U(SCH_1):PAGE301_I14@PURE_QUANTA.MP5991GLUZ(CHIPS)':
 'VIN7': CDS_PINID='VIN7';
NODE_NAME     PU288 16
 '@S9S_MB_2U_LIB.S9S_MB_2U(SCH_1):PAGE301_I14@PURE_QUANTA.MP5991GLUZ(CHIPS)':
 'VIN8': CDS_PINID='VIN8';
NODE_NAME     PU288 33
 '@S9S_MB_2U_LIB.S9S_MB_2U(SCH_1):PAGE301_I14@PURE_QUANTA.MP5991GLUZ(CHIPS)':
 'VIN9': CDS_PINID='VIN9';
NODE_NAME     FS1 1
 '@S9S_MB_2U_LIB.S9S_MB_2U(SCH_1):PAGE328_I54@PURE_QUANTA.Q_FUSE(CHIPS)':
 '1': CDS_PINID='\1\';
NODE_NAME     PR2534 1A
 '@S9S_MB_2U_LIB.S9S_MB_2U(SCH_1):PAGE328_I63@PURE_QUANTA.Q_SP_RES4P(CHIPS)':
 '1A': CDS_PINID='\1a\';
NODE_NAME     PR2533 1A
 '@S9S_MB_2U_LIB.S9S_MB_2U(SCH_1):PAGE328_I64@PURE_QUANTA.Q_SP_RES4P(CHIPS)':
 '1A': CDS_PINID='\1a\';
NODE_NAME     PR2532 1A
 '@S9S_MB_2U_LIB.S9S_MB_2U(SCH_1):PAGE328_I78@PURE_QUANTA.Q_SP_RES4P(CHIPS)':
 '1A': CDS_PINID='\1a\';
NODE_NAME     PR4 1A
 '@S9S_MB_2U_LIB.S9S_MB_2U(SCH_1):PAGE328_I79@PURE_QUANTA.Q_SP_RES4P(CHIPS)':
 '1A': CDS_PINID='\1a\';
NODE_NAME     PJ42 1
 '@S9S_MB_2U_LIB.S9S_MB_2U(SCH_1):PAGE327_I34@PURE_QUANTA.SCONN21_9193031121LF(CHIPS)':
 '1': CDS_PINID='\1\';
NODE_NAME     PR3 1
 '@S9S_MB_2U_LIB.S9S_MB_2U(SCH_1):PAGE328_I126@PURE_QUANTA.Q_RES_4P_12(CHIPS)':
 '1': CDS_PINID='\1\';
NODE_NAME     R4707 2
 '@S9S_MB_2U_LIB.S9S_MB_2U(SCH_1):PAGE241_I63@PURE_QUANTA.Q_RES(CHIPS)':
 'B': CDS_PINID='B';
NODE_NAME     J45 P4_1
 '@S9S_MB_2U_LIB.S9S_MB_2U(SCH_1):PAGE233_I12@PURE_QUANTA.CONN60_101062636003K02LF(CHIPS)':
 'P4_1': CDS_PINID='P4_1';
NODE_NAME     J45 P4_2
 '@S9S_MB_2U_LIB.S9S_MB_2U(SCH_1):PAGE233_I12@PURE_QUANTA.CONN60_101062636003K02LF(CHIPS)':
 'P4_2': CDS_PINID='P4_2';
NODE_NAME     J45 P4_3
 '@S9S_MB_2U_LIB.S9S_MB_2U(SCH_1):PAGE233_I12@PURE_QUANTA.CONN60_101062636003K02LF(CHIPS)':
 'P4_3': CDS_PINID='P4_3';
NODE_NAME     J45 P4_4
 '@S9S_MB_2U_LIB.S9S_MB_2U(SCH_1):PAGE233_I12@PURE_QUANTA.CONN60_101062636003K02LF(CHIPS)':
 'P4_4': CDS_PINID='P4_4';
NODE_NAME     J45 P4_5
 '@S9S_MB_2U_LIB.S9S_MB_2U(SCH_1):PAGE233_I12@PURE_QUANTA.CONN60_101062636003K02LF(CHIPS)':
 'P4_5': CDS_PINID='P4_5';
NODE_NAME     J45 P4_6
 '@S9S_MB_2U_LIB.S9S_MB_2U(SCH_1):PAGE233_I12@PURE_QUANTA.CONN60_101062636003K02LF(CHIPS)':
 'P4_6': CDS_PINID='P4_6';
NODE_NAME     J45 P4_7
 '@S9S_MB_2U_LIB.S9S_MB_2U(SCH_1):PAGE233_I12@PURE_QUANTA.CONN60_101062636003K02LF(CHIPS)':
 'P4_7': CDS_PINID='P4_7';
NODE_NAME     J45 P4_8
 '@S9S_MB_2U_LIB.S9S_MB_2U(SCH_1):PAGE233_I12@PURE_QUANTA.CONN60_101062636003K02LF(CHIPS)':
 'P4_8': CDS_PINID='P4_8';
NODE_NAME     J45 P5_1
 '@S9S_MB_2U_LIB.S9S_MB_2U(SCH_1):PAGE233_I12@PURE_QUANTA.CONN60_101062636003K02LF(CHIPS)':
 'P5_1': CDS_PINID='P5_1';
NODE_NAME     J45 P5_2
 '@S9S_MB_2U_LIB.S9S_MB_2U(SCH_1):PAGE233_I12@PURE_QUANTA.CONN60_101062636003K02LF(CHIPS)':
 'P5_2': CDS_PINID='P5_2';
NODE_NAME     J45 P5_3
 '@S9S_MB_2U_LIB.S9S_MB_2U(SCH_1):PAGE233_I12@PURE_QUANTA.CONN60_101062636003K02LF(CHIPS)':
 'P5_3': CDS_PINID='P5_3';
NODE_NAME     J45 P5_4
 '@S9S_MB_2U_LIB.S9S_MB_2U(SCH_1):PAGE233_I12@PURE_QUANTA.CONN60_101062636003K02LF(CHIPS)':
 'P5_4': CDS_PINID='P5_4';
NODE_NAME     J45 P5_5
 '@S9S_MB_2U_LIB.S9S_MB_2U(SCH_1):PAGE233_I12@PURE_QUANTA.CONN60_101062636003K02LF(CHIPS)':
 'P5_5': CDS_PINID='P5_5';
NODE_NAME     J45 P5_6
 '@S9S_MB_2U_LIB.S9S_MB_2U(SCH_1):PAGE233_I12@PURE_QUANTA.CONN60_101062636003K02LF(CHIPS)':
 'P5_6': CDS_PINID='P5_6';
NODE_NAME     J45 P5_7
 '@S9S_MB_2U_LIB.S9S_MB_2U(SCH_1):PAGE233_I12@PURE_QUANTA.CONN60_101062636003K02LF(CHIPS)':
 'P5_7': CDS_PINID='P5_7';
NODE_NAME     J45 P5_8
 '@S9S_MB_2U_LIB.S9S_MB_2U(SCH_1):PAGE233_I12@PURE_QUANTA.CONN60_101062636003K02LF(CHIPS)':
 'P5_8': CDS_PINID='P5_8';
NODE_NAME     J45 P6_1
 '@S9S_MB_2U_LIB.S9S_MB_2U(SCH_1):PAGE233_I12@PURE_QUANTA.CONN60_101062636003K02LF(CHIPS)':
 'P6_1': CDS_PINID='P6_1';
NODE_NAME     J45 P6_2
 '@S9S_MB_2U_LIB.S9S_MB_2U(SCH_1):PAGE233_I12@PURE_QUANTA.CONN60_101062636003K02LF(CHIPS)':
 'P6_2': CDS_PINID='P6_2';
NODE_NAME     J45 P6_3
 '@S9S_MB_2U_LIB.S9S_MB_2U(SCH_1):PAGE233_I12@PURE_QUANTA.CONN60_101062636003K02LF(CHIPS)':
 'P6_3': CDS_PINID='P6_3';
NODE_NAME     J45 P6_4
 '@S9S_MB_2U_LIB.S9S_MB_2U(SCH_1):PAGE233_I12@PURE_QUANTA.CONN60_101062636003K02LF(CHIPS)':
 'P6_4': CDS_PINID='P6_4';
NODE_NAME     J45 P6_5
 '@S9S_MB_2U_LIB.S9S_MB_2U(SCH_1):PAGE233_I12@PURE_QUANTA.CONN60_101062636003K02LF(CHIPS)':
 'P6_5': CDS_PINID='P6_5';
NODE_NAME     J45 P6_6
 '@S9S_MB_2U_LIB.S9S_MB_2U(SCH_1):PAGE233_I12@PURE_QUANTA.CONN60_101062636003K02LF(CHIPS)':
 'P6_6': CDS_PINID='P6_6';
NODE_NAME     J45 P6_7
 '@S9S_MB_2U_LIB.S9S_MB_2U(SCH_1):PAGE233_I12@PURE_QUANTA.CONN60_101062636003K02LF(CHIPS)':
 'P6_7': CDS_PINID='P6_7';
NODE_NAME     J45 P6_8
 '@S9S_MB_2U_LIB.S9S_MB_2U(SCH_1):PAGE233_I12@PURE_QUANTA.CONN60_101062636003K02LF(CHIPS)':
 'P6_8': CDS_PINID='P6_8';
NET_NAME
'P12V_PSU_FUSE'
 '@S9S_MB_2U_LIB.S9S_MB_2U(SCH_1):P12V_PSU_FUSE':
 C_SIGNAL='@s9s_mb_2u_lib.s9s_mb_2u(sch_1):p12v_psu_fuse';
NODE_NAME     R3923 1
 '@S9S_MB_2U_LIB.S9S_MB_2U(SCH_1):PAGE303_I10@PURE_QUANTA.Q_RES(CHIPS)':
 'A': CDS_PINID='A';
NODE_NAME     PD15 C
 '@S9S_MB_2U_LIB.S9S_MB_2U(SCH_1):PAGE328_I51@PURE_QUANTA.ZENER_AC(CHIPS)':
 'C': CDS_PINID='C';
NODE_NAME     PD16 C
 '@S9S_MB_2U_LIB.S9S_MB_2U(SCH_1):PAGE328_I53@PURE_QUANTA.ZENER_AC(CHIPS)':
 'C': CDS_PINID='C';
NODE_NAME     FS1 2
 '@S9S_MB_2U_LIB.S9S_MB_2U(SCH_1):PAGE328_I54@PURE_QUANTA.Q_FUSE(CHIPS)':
 '2': CDS_PINID='\2\';
NODE_NAME     R4901 1
 '@S9S_MB_2U_LIB.S9S_MB_2U(SCH_1):PAGE303_I26@PURE_QUANTA.Q_RES(CHIPS)':
 'A': CDS_PINID='A';
NET_NAME
'P12V_S3_AUX_CPU0_NVDIMM'
 '@S9S_MB_2U_LIB.S9S_MB_2U(SCH_1):P12V_S3_AUX_CPU0_NVDIMM':
 C_SIGNAL='@s9s_mb_2u_lib.s9s_mb_2u(sch_1):p12v_s3_aux_cpu0_nvdimm',
 CDS_GLOBAL_NET='TRUE';
NODE_NAME     C3 1
 '@S9S_MB_2U_LIB.S9S_MB_2U(SCH_1):PAGE82_I188@PURE_QUANTA.Q_CAP(CHIPS)':
 'A': CDS_PINID='A';
NODE_NAME     C4 1
 '@S9S_MB_2U_LIB.S9S_MB_2U(SCH_1):PAGE82_I190@PURE_QUANTA.Q_CAP(CHIPS)':
 'A': CDS_PINID='A';
NODE_NAME     C6 1
 '@S9S_MB_2U_LIB.S9S_MB_2U(SCH_1):PAGE83_I122@PURE_QUANTA.Q_CAP(CHIPS)':
 'A': CDS_PINID='A';
NODE_NAME     C7 1
 '@S9S_MB_2U_LIB.S9S_MB_2U(SCH_1):PAGE83_I144@PURE_QUANTA.Q_CAP(CHIPS)':
 'A': CDS_PINID='A';
NODE_NAME     J2 1
 '@S9S_MB_2U_LIB.S9S_MB_2U(SCH_1):PAGE83_I179@PURE_QUANTA.SCONN288_ADR50017P087CC(CHIPS)':
 'VIN_BULK0': CDS_PINID='VIN_BULK0';
NODE_NAME     J2 145
 '@S9S_MB_2U_LIB.S9S_MB_2U(SCH_1):PAGE83_I179@PURE_QUANTA.SCONN288_ADR50017P087CC(CHIPS)':
 'VIN_BULK1': CDS_PINID='VIN_BULK1';
NODE_NAME     J2 146
 '@S9S_MB_2U_LIB.S9S_MB_2U(SCH_1):PAGE83_I179@PURE_QUANTA.SCONN288_ADR50017P087CC(CHIPS)':
 'VIN_BULK2': CDS_PINID='VIN_BULK2';
NODE_NAME     C9 1
 '@S9S_MB_2U_LIB.S9S_MB_2U(SCH_1):PAGE84_I122@PURE_QUANTA.Q_CAP(CHIPS)':
 'A': CDS_PINID='A';
NODE_NAME     C10 1
 '@S9S_MB_2U_LIB.S9S_MB_2U(SCH_1):PAGE84_I144@PURE_QUANTA.Q_CAP(CHIPS)':
 'A': CDS_PINID='A';
NODE_NAME     J3 1
 '@S9S_MB_2U_LIB.S9S_MB_2U(SCH_1):PAGE84_I178@PURE_QUANTA.SCONN288_ADR50017P130CC(CHIPS)':
 'VIN_BULK0': CDS_PINID='VIN_BULK0';
NODE_NAME     J3 145
 '@S9S_MB_2U_LIB.S9S_MB_2U(SCH_1):PAGE84_I178@PURE_QUANTA.SCONN288_ADR50017P130CC(CHIPS)':
 'VIN_BULK1': CDS_PINID='VIN_BULK1';
NODE_NAME     J3 146
 '@S9S_MB_2U_LIB.S9S_MB_2U(SCH_1):PAGE84_I178@PURE_QUANTA.SCONN288_ADR50017P130CC(CHIPS)':
 'VIN_BULK2': CDS_PINID='VIN_BULK2';
NODE_NAME     C12 1
 '@S9S_MB_2U_LIB.S9S_MB_2U(SCH_1):PAGE85_I125@PURE_QUANTA.Q_CAP(CHIPS)':
 'A': CDS_PINID='A';
NODE_NAME     C13 1
 '@S9S_MB_2U_LIB.S9S_MB_2U(SCH_1):PAGE85_I127@PURE_QUANTA.Q_CAP(CHIPS)':
 'A': CDS_PINID='A';
NODE_NAME     J4 1
 '@S9S_MB_2U_LIB.S9S_MB_2U(SCH_1):PAGE85_I174@PURE_QUANTA.SCONN288_ADR50017P087CC(CHIPS)':
 'VIN_BULK0': CDS_PINID='VIN_BULK0';
NODE_NAME     J4 145
 '@S9S_MB_2U_LIB.S9S_MB_2U(SCH_1):PAGE85_I174@PURE_QUANTA.SCONN288_ADR50017P087CC(CHIPS)':
 'VIN_BULK1': CDS_PINID='VIN_BULK1';
NODE_NAME     J4 146
 '@S9S_MB_2U_LIB.S9S_MB_2U(SCH_1):PAGE85_I174@PURE_QUANTA.SCONN288_ADR50017P087CC(CHIPS)':
 'VIN_BULK2': CDS_PINID='VIN_BULK2';
NODE_NAME     C15 1
 '@S9S_MB_2U_LIB.S9S_MB_2U(SCH_1):PAGE86_I121@PURE_QUANTA.Q_CAP(CHIPS)':
 'A': CDS_PINID='A';
NODE_NAME     C16 1
 '@S9S_MB_2U_LIB.S9S_MB_2U(SCH_1):PAGE86_I123@PURE_QUANTA.Q_CAP(CHIPS)':
 'A': CDS_PINID='A';
NODE_NAME     J5 1
 '@S9S_MB_2U_LIB.S9S_MB_2U(SCH_1):PAGE86_I174@PURE_QUANTA.SCONN288_ADR50017P130CC(CHIPS)':
 'VIN_BULK0': CDS_PINID='VIN_BULK0';
NODE_NAME     J5 145
 '@S9S_MB_2U_LIB.S9S_MB_2U(SCH_1):PAGE86_I174@PURE_QUANTA.SCONN288_ADR50017P130CC(CHIPS)':
 'VIN_BULK1': CDS_PINID='VIN_BULK1';
NODE_NAME     J5 146
 '@S9S_MB_2U_LIB.S9S_MB_2U(SCH_1):PAGE86_I174@PURE_QUANTA.SCONN288_ADR50017P130CC(CHIPS)':
 'VIN_BULK2': CDS_PINID='VIN_BULK2';
NODE_NAME     C18 1
 '@S9S_MB_2U_LIB.S9S_MB_2U(SCH_1):PAGE87_I124@PURE_QUANTA.Q_CAP(CHIPS)':
 'A': CDS_PINID='A';
NODE_NAME     C19 1
 '@S9S_MB_2U_LIB.S9S_MB_2U(SCH_1):PAGE87_I127@PURE_QUANTA.Q_CAP(CHIPS)':
 'A': CDS_PINID='A';
NODE_NAME     J6 1
 '@S9S_MB_2U_LIB.S9S_MB_2U(SCH_1):PAGE87_I175@PURE_QUANTA.SCONN288_ADR50017P087CC(CHIPS)':
 'VIN_BULK0': CDS_PINID='VIN_BULK0';
NODE_NAME     J6 145
 '@S9S_MB_2U_LIB.S9S_MB_2U(SCH_1):PAGE87_I175@PURE_QUANTA.SCONN288_ADR50017P087CC(CHIPS)':
 'VIN_BULK1': CDS_PINID='VIN_BULK1';
NODE_NAME     J6 146
 '@S9S_MB_2U_LIB.S9S_MB_2U(SCH_1):PAGE87_I175@PURE_QUANTA.SCONN288_ADR50017P087CC(CHIPS)':
 'VIN_BULK2': CDS_PINID='VIN_BULK2';
NODE_NAME     C21 1
 '@S9S_MB_2U_LIB.S9S_MB_2U(SCH_1):PAGE88_I126@PURE_QUANTA.Q_CAP(CHIPS)':
 'A': CDS_PINID='A';
NODE_NAME     C22 1
 '@S9S_MB_2U_LIB.S9S_MB_2U(SCH_1):PAGE88_I166@PURE_QUANTA.Q_CAP(CHIPS)':
 'A': CDS_PINID='A';
NODE_NAME     J7 1
 '@S9S_MB_2U_LIB.S9S_MB_2U(SCH_1):PAGE88_I168@PURE_QUANTA.SCONN288_ADR50017P130CC(CHIPS)':
 'VIN_BULK0': CDS_PINID='VIN_BULK0';
NODE_NAME     J7 145
 '@S9S_MB_2U_LIB.S9S_MB_2U(SCH_1):PAGE88_I168@PURE_QUANTA.SCONN288_ADR50017P130CC(CHIPS)':
 'VIN_BULK1': CDS_PINID='VIN_BULK1';
NODE_NAME     J7 146
 '@S9S_MB_2U_LIB.S9S_MB_2U(SCH_1):PAGE88_I168@PURE_QUANTA.SCONN288_ADR50017P130CC(CHIPS)':
 'VIN_BULK2': CDS_PINID='VIN_BULK2';
NODE_NAME     C24 1
 '@S9S_MB_2U_LIB.S9S_MB_2U(SCH_1):PAGE89_I125@PURE_QUANTA.Q_CAP(CHIPS)':
 'A': CDS_PINID='A';
NODE_NAME     C25 1
 '@S9S_MB_2U_LIB.S9S_MB_2U(SCH_1):PAGE89_I127@PURE_QUANTA.Q_CAP(CHIPS)':
 'A': CDS_PINID='A';
NODE_NAME     J8 1
 '@S9S_MB_2U_LIB.S9S_MB_2U(SCH_1):PAGE89_I175@PURE_QUANTA.SCONN288_ADR50017P087CC(CHIPS)':
 'VIN_BULK0': CDS_PINID='VIN_BULK0';
NODE_NAME     J8 145
 '@S9S_MB_2U_LIB.S9S_MB_2U(SCH_1):PAGE89_I175@PURE_QUANTA.SCONN288_ADR50017P087CC(CHIPS)':
 'VIN_BULK1': CDS_PINID='VIN_BULK1';
NODE_NAME     J8 146
 '@S9S_MB_2U_LIB.S9S_MB_2U(SCH_1):PAGE89_I175@PURE_QUANTA.SCONN288_ADR50017P087CC(CHIPS)':
 'VIN_BULK2': CDS_PINID='VIN_BULK2';
NODE_NAME     C27 1
 '@S9S_MB_2U_LIB.S9S_MB_2U(SCH_1):PAGE90_I123@PURE_QUANTA.Q_CAP(CHIPS)':
 'A': CDS_PINID='A';
NODE_NAME     C28 1
 '@S9S_MB_2U_LIB.S9S_MB_2U(SCH_1):PAGE90_I145@PURE_QUANTA.Q_CAP(CHIPS)':
 'A': CDS_PINID='A';
NODE_NAME     J9 1
 '@S9S_MB_2U_LIB.S9S_MB_2U(SCH_1):PAGE90_I147@PURE_QUANTA.SCONN288_ADR50017P130CC(CHIPS)':
 'VIN_BULK0': CDS_PINID='VIN_BULK0';
NODE_NAME     J9 145
 '@S9S_MB_2U_LIB.S9S_MB_2U(SCH_1):PAGE90_I147@PURE_QUANTA.SCONN288_ADR50017P130CC(CHIPS)':
 'VIN_BULK1': CDS_PINID='VIN_BULK1';
NODE_NAME     J9 146
 '@S9S_MB_2U_LIB.S9S_MB_2U(SCH_1):PAGE90_I147@PURE_QUANTA.SCONN288_ADR50017P130CC(CHIPS)':
 'VIN_BULK2': CDS_PINID='VIN_BULK2';
NODE_NAME     C30 1
 '@S9S_MB_2U_LIB.S9S_MB_2U(SCH_1):PAGE91_I124@PURE_QUANTA.Q_CAP(CHIPS)':
 'A': CDS_PINID='A';
NODE_NAME     C31 1
 '@S9S_MB_2U_LIB.S9S_MB_2U(SCH_1):PAGE91_I146@PURE_QUANTA.Q_CAP(CHIPS)':
 'A': CDS_PINID='A';
NODE_NAME     J10 1
 '@S9S_MB_2U_LIB.S9S_MB_2U(SCH_1):PAGE91_I148@PURE_QUANTA.SCONN288_ADR50017P087CC(CHIPS)':
 'VIN_BULK0': CDS_PINID='VIN_BULK0';
NODE_NAME     J10 145
 '@S9S_MB_2U_LIB.S9S_MB_2U(SCH_1):PAGE91_I148@PURE_QUANTA.SCONN288_ADR50017P087CC(CHIPS)':
 'VIN_BULK1': CDS_PINID='VIN_BULK1';
NODE_NAME     J10 146
 '@S9S_MB_2U_LIB.S9S_MB_2U(SCH_1):PAGE91_I148@PURE_QUANTA.SCONN288_ADR50017P087CC(CHIPS)':
 'VIN_BULK2': CDS_PINID='VIN_BULK2';
NODE_NAME     C33 1
 '@S9S_MB_2U_LIB.S9S_MB_2U(SCH_1):PAGE92_I127@PURE_QUANTA.Q_CAP(CHIPS)':
 'A': CDS_PINID='A';
NODE_NAME     C34 1
 '@S9S_MB_2U_LIB.S9S_MB_2U(SCH_1):PAGE92_I130@PURE_QUANTA.Q_CAP(CHIPS)':
 'A': CDS_PINID='A';
NODE_NAME     J11 1
 '@S9S_MB_2U_LIB.S9S_MB_2U(SCH_1):PAGE92_I175@PURE_QUANTA.SCONN288_ADR50017P130CC(CHIPS)':
 'VIN_BULK0': CDS_PINID='VIN_BULK0';
NODE_NAME     J11 145
 '@S9S_MB_2U_LIB.S9S_MB_2U(SCH_1):PAGE92_I175@PURE_QUANTA.SCONN288_ADR50017P130CC(CHIPS)':
 'VIN_BULK1': CDS_PINID='VIN_BULK1';
NODE_NAME     J11 146
 '@S9S_MB_2U_LIB.S9S_MB_2U(SCH_1):PAGE92_I175@PURE_QUANTA.SCONN288_ADR50017P130CC(CHIPS)':
 'VIN_BULK2': CDS_PINID='VIN_BULK2';
NODE_NAME     C36 1
 '@S9S_MB_2U_LIB.S9S_MB_2U(SCH_1):PAGE93_I126@PURE_QUANTA.Q_CAP(CHIPS)':
 'A': CDS_PINID='A';
NODE_NAME     C37 1
 '@S9S_MB_2U_LIB.S9S_MB_2U(SCH_1):PAGE93_I128@PURE_QUANTA.Q_CAP(CHIPS)':
 'A': CDS_PINID='A';
NODE_NAME     J12 1
 '@S9S_MB_2U_LIB.S9S_MB_2U(SCH_1):PAGE93_I175@PURE_QUANTA.SCONN288_ADR50017P087CC(CHIPS)':
 'VIN_BULK0': CDS_PINID='VIN_BULK0';
NODE_NAME     J12 145
 '@S9S_MB_2U_LIB.S9S_MB_2U(SCH_1):PAGE93_I175@PURE_QUANTA.SCONN288_ADR50017P087CC(CHIPS)':
 'VIN_BULK1': CDS_PINID='VIN_BULK1';
NODE_NAME     J12 146
 '@S9S_MB_2U_LIB.S9S_MB_2U(SCH_1):PAGE93_I175@PURE_QUANTA.SCONN288_ADR50017P087CC(CHIPS)':
 'VIN_BULK2': CDS_PINID='VIN_BULK2';
NODE_NAME     C39 1
 '@S9S_MB_2U_LIB.S9S_MB_2U(SCH_1):PAGE94_I125@PURE_QUANTA.Q_CAP(CHIPS)':
 'A': CDS_PINID='A';
NODE_NAME     C40 1
 '@S9S_MB_2U_LIB.S9S_MB_2U(SCH_1):PAGE94_I162@PURE_QUANTA.Q_CAP(CHIPS)':
 'A': CDS_PINID='A';
NODE_NAME     J13 1
 '@S9S_MB_2U_LIB.S9S_MB_2U(SCH_1):PAGE94_I164@PURE_QUANTA.SCONN288_ADR50017P130CC(CHIPS)':
 'VIN_BULK0': CDS_PINID='VIN_BULK0';
NODE_NAME     J13 145
 '@S9S_MB_2U_LIB.S9S_MB_2U(SCH_1):PAGE94_I164@PURE_QUANTA.SCONN288_ADR50017P130CC(CHIPS)':
 'VIN_BULK1': CDS_PINID='VIN_BULK1';
NODE_NAME     J13 146
 '@S9S_MB_2U_LIB.S9S_MB_2U(SCH_1):PAGE94_I164@PURE_QUANTA.SCONN288_ADR50017P130CC(CHIPS)':
 'VIN_BULK2': CDS_PINID='VIN_BULK2';
NODE_NAME     C42 1
 '@S9S_MB_2U_LIB.S9S_MB_2U(SCH_1):PAGE95_I125@PURE_QUANTA.Q_CAP(CHIPS)':
 'A': CDS_PINID='A';
NODE_NAME     C43 1
 '@S9S_MB_2U_LIB.S9S_MB_2U(SCH_1):PAGE95_I128@PURE_QUANTA.Q_CAP(CHIPS)':
 'A': CDS_PINID='A';
NODE_NAME     J14 1
 '@S9S_MB_2U_LIB.S9S_MB_2U(SCH_1):PAGE95_I176@PURE_QUANTA.SCONN288_ADR50017P087CC(CHIPS)':
 'VIN_BULK0': CDS_PINID='VIN_BULK0';
NODE_NAME     J14 145
 '@S9S_MB_2U_LIB.S9S_MB_2U(SCH_1):PAGE95_I176@PURE_QUANTA.SCONN288_ADR50017P087CC(CHIPS)':
 'VIN_BULK1': CDS_PINID='VIN_BULK1';
NODE_NAME     J14 146
 '@S9S_MB_2U_LIB.S9S_MB_2U(SCH_1):PAGE95_I176@PURE_QUANTA.SCONN288_ADR50017P087CC(CHIPS)':
 'VIN_BULK2': CDS_PINID='VIN_BULK2';
NODE_NAME     C45 1
 '@S9S_MB_2U_LIB.S9S_MB_2U(SCH_1):PAGE96_I125@PURE_QUANTA.Q_CAP(CHIPS)':
 'A': CDS_PINID='A';
NODE_NAME     C46 1
 '@S9S_MB_2U_LIB.S9S_MB_2U(SCH_1):PAGE96_I127@PURE_QUANTA.Q_CAP(CHIPS)':
 'A': CDS_PINID='A';
NODE_NAME     J15 1
 '@S9S_MB_2U_LIB.S9S_MB_2U(SCH_1):PAGE96_I176@PURE_QUANTA.SCONN288_ADR50017P130CC(CHIPS)':
 'VIN_BULK0': CDS_PINID='VIN_BULK0';
NODE_NAME     J15 145
 '@S9S_MB_2U_LIB.S9S_MB_2U(SCH_1):PAGE96_I176@PURE_QUANTA.SCONN288_ADR50017P130CC(CHIPS)':
 'VIN_BULK1': CDS_PINID='VIN_BULK1';
NODE_NAME     J15 146
 '@S9S_MB_2U_LIB.S9S_MB_2U(SCH_1):PAGE96_I176@PURE_QUANTA.SCONN288_ADR50017P130CC(CHIPS)':
 'VIN_BULK2': CDS_PINID='VIN_BULK2';
NODE_NAME     C48 1
 '@S9S_MB_2U_LIB.S9S_MB_2U(SCH_1):PAGE97_I59@PURE_QUANTA.Q_CAP(CHIPS)':
 'A': CDS_PINID='A';
NODE_NAME     C49 1
 '@S9S_MB_2U_LIB.S9S_MB_2U(SCH_1):PAGE97_I62@PURE_QUANTA.Q_CAP(CHIPS)':
 'A': CDS_PINID='A';
NODE_NAME     J16 1
 '@S9S_MB_2U_LIB.S9S_MB_2U(SCH_1):PAGE97_I64@PURE_QUANTA.SCONN288_ADR50017P087CC(CHIPS)':
 'VIN_BULK0': CDS_PINID='VIN_BULK0';
NODE_NAME     J16 145
 '@S9S_MB_2U_LIB.S9S_MB_2U(SCH_1):PAGE97_I64@PURE_QUANTA.SCONN288_ADR50017P087CC(CHIPS)':
 'VIN_BULK1': CDS_PINID='VIN_BULK1';
NODE_NAME     J16 146
 '@S9S_MB_2U_LIB.S9S_MB_2U(SCH_1):PAGE97_I64@PURE_QUANTA.SCONN288_ADR50017P087CC(CHIPS)':
 'VIN_BULK2': CDS_PINID='VIN_BULK2';
NODE_NAME     J1 1
 '@S9S_MB_2U_LIB.S9S_MB_2U(SCH_1):PAGE82_I203@PURE_QUANTA.SCONN288_ADR50017P130CC(CHIPS)':
 'VIN_BULK0': CDS_PINID='VIN_BULK0';
NODE_NAME     J1 145
 '@S9S_MB_2U_LIB.S9S_MB_2U(SCH_1):PAGE82_I203@PURE_QUANTA.SCONN288_ADR50017P130CC(CHIPS)':
 'VIN_BULK1': CDS_PINID='VIN_BULK1';
NODE_NAME     J1 146
 '@S9S_MB_2U_LIB.S9S_MB_2U(SCH_1):PAGE82_I203@PURE_QUANTA.SCONN288_ADR50017P130CC(CHIPS)':
 'VIN_BULK2': CDS_PINID='VIN_BULK2';
NODE_NAME     R1838 2
 '@S9S_MB_2U_LIB.S9S_MB_2U(SCH_1):PAGE240_I11@PURE_QUANTA.Q_RES_4P_12(CHIPS)':
 '2': CDS_PINID='\2\';
NET_NAME
'P12V_S3_AUX_CPU1_NVDIMM'
 '@S9S_MB_2U_LIB.S9S_MB_2U(SCH_1):P12V_S3_AUX_CPU1_NVDIMM':
 C_SIGNAL='@s9s_mb_2u_lib.s9s_mb_2u(sch_1):p12v_s3_aux_cpu1_nvdimm',
 CDS_GLOBAL_NET='TRUE';
NODE_NAME     C51 1
 '@S9S_MB_2U_LIB.S9S_MB_2U(SCH_1):PAGE98_I123@PURE_QUANTA.Q_CAP(CHIPS)':
 'A': CDS_PINID='A';
NODE_NAME     C52 1
 '@S9S_MB_2U_LIB.S9S_MB_2U(SCH_1):PAGE98_I145@PURE_QUANTA.Q_CAP(CHIPS)':
 'A': CDS_PINID='A';
NODE_NAME     J17 1
 '@S9S_MB_2U_LIB.S9S_MB_2U(SCH_1):PAGE98_I147@PURE_QUANTA.SCONN288_ADR50017P130CC(CHIPS)':
 'VIN_BULK0': CDS_PINID='VIN_BULK0';
NODE_NAME     J17 145
 '@S9S_MB_2U_LIB.S9S_MB_2U(SCH_1):PAGE98_I147@PURE_QUANTA.SCONN288_ADR50017P130CC(CHIPS)':
 'VIN_BULK1': CDS_PINID='VIN_BULK1';
NODE_NAME     J17 146
 '@S9S_MB_2U_LIB.S9S_MB_2U(SCH_1):PAGE98_I147@PURE_QUANTA.SCONN288_ADR50017P130CC(CHIPS)':
 'VIN_BULK2': CDS_PINID='VIN_BULK2';
NODE_NAME     C54 1
 '@S9S_MB_2U_LIB.S9S_MB_2U(SCH_1):PAGE99_I126@PURE_QUANTA.Q_CAP(CHIPS)':
 'A': CDS_PINID='A';
NODE_NAME     C55 1
 '@S9S_MB_2U_LIB.S9S_MB_2U(SCH_1):PAGE99_I128@PURE_QUANTA.Q_CAP(CHIPS)':
 'A': CDS_PINID='A';
NODE_NAME     J18 1
 '@S9S_MB_2U_LIB.S9S_MB_2U(SCH_1):PAGE99_I175@PURE_QUANTA.SCONN288_ADR50017P087CC(CHIPS)':
 'VIN_BULK0': CDS_PINID='VIN_BULK0';
NODE_NAME     J18 145
 '@S9S_MB_2U_LIB.S9S_MB_2U(SCH_1):PAGE99_I175@PURE_QUANTA.SCONN288_ADR50017P087CC(CHIPS)':
 'VIN_BULK1': CDS_PINID='VIN_BULK1';
NODE_NAME     J18 146
 '@S9S_MB_2U_LIB.S9S_MB_2U(SCH_1):PAGE99_I175@PURE_QUANTA.SCONN288_ADR50017P087CC(CHIPS)':
 'VIN_BULK2': CDS_PINID='VIN_BULK2';
NODE_NAME     C57 1
 '@S9S_MB_2U_LIB.S9S_MB_2U(SCH_1):PAGE100_I122@PURE_QUANTA.Q_CAP(CHIPS)':
 'A': CDS_PINID='A';
NODE_NAME     C58 1
 '@S9S_MB_2U_LIB.S9S_MB_2U(SCH_1):PAGE100_I124@PURE_QUANTA.Q_CAP(CHIPS)':
 'A': CDS_PINID='A';
NODE_NAME     J19 1
 '@S9S_MB_2U_LIB.S9S_MB_2U(SCH_1):PAGE100_I175@PURE_QUANTA.SCONN288_ADR50017P130CC(CHIPS)':
 'VIN_BULK0': CDS_PINID='VIN_BULK0';
NODE_NAME     J19 145
 '@S9S_MB_2U_LIB.S9S_MB_2U(SCH_1):PAGE100_I175@PURE_QUANTA.SCONN288_ADR50017P130CC(CHIPS)':
 'VIN_BULK1': CDS_PINID='VIN_BULK1';
NODE_NAME     J19 146
 '@S9S_MB_2U_LIB.S9S_MB_2U(SCH_1):PAGE100_I175@PURE_QUANTA.SCONN288_ADR50017P130CC(CHIPS)':
 'VIN_BULK2': CDS_PINID='VIN_BULK2';
NODE_NAME     C60 1
 '@S9S_MB_2U_LIB.S9S_MB_2U(SCH_1):PAGE101_I125@PURE_QUANTA.Q_CAP(CHIPS)':
 'A': CDS_PINID='A';
NODE_NAME     C61 1
 '@S9S_MB_2U_LIB.S9S_MB_2U(SCH_1):PAGE101_I127@PURE_QUANTA.Q_CAP(CHIPS)':
 'A': CDS_PINID='A';
NODE_NAME     J20 1
 '@S9S_MB_2U_LIB.S9S_MB_2U(SCH_1):PAGE101_I176@PURE_QUANTA.SCONN288_ADR50017P087CC(CHIPS)':
 'VIN_BULK0': CDS_PINID='VIN_BULK0';
NODE_NAME     J20 145
 '@S9S_MB_2U_LIB.S9S_MB_2U(SCH_1):PAGE101_I176@PURE_QUANTA.SCONN288_ADR50017P087CC(CHIPS)':
 'VIN_BULK1': CDS_PINID='VIN_BULK1';
NODE_NAME     J20 146
 '@S9S_MB_2U_LIB.S9S_MB_2U(SCH_1):PAGE101_I176@PURE_QUANTA.SCONN288_ADR50017P087CC(CHIPS)':
 'VIN_BULK2': CDS_PINID='VIN_BULK2';
NODE_NAME     C63 1
 '@S9S_MB_2U_LIB.S9S_MB_2U(SCH_1):PAGE102_I127@PURE_QUANTA.Q_CAP(CHIPS)':
 'A': CDS_PINID='A';
NODE_NAME     C64 1
 '@S9S_MB_2U_LIB.S9S_MB_2U(SCH_1):PAGE102_I167@PURE_QUANTA.Q_CAP(CHIPS)':
 'A': CDS_PINID='A';
NODE_NAME     J21 1
 '@S9S_MB_2U_LIB.S9S_MB_2U(SCH_1):PAGE102_I169@PURE_QUANTA.SCONN288_ADR50017P130CC(CHIPS)':
 'VIN_BULK0': CDS_PINID='VIN_BULK0';
NODE_NAME     J21 145
 '@S9S_MB_2U_LIB.S9S_MB_2U(SCH_1):PAGE102_I169@PURE_QUANTA.SCONN288_ADR50017P130CC(CHIPS)':
 'VIN_BULK1': CDS_PINID='VIN_BULK1';
NODE_NAME     J21 146
 '@S9S_MB_2U_LIB.S9S_MB_2U(SCH_1):PAGE102_I169@PURE_QUANTA.SCONN288_ADR50017P130CC(CHIPS)':
 'VIN_BULK2': CDS_PINID='VIN_BULK2';
NODE_NAME     C66 1
 '@S9S_MB_2U_LIB.S9S_MB_2U(SCH_1):PAGE103_I126@PURE_QUANTA.Q_CAP(CHIPS)':
 'A': CDS_PINID='A';
NODE_NAME     C67 1
 '@S9S_MB_2U_LIB.S9S_MB_2U(SCH_1):PAGE103_I128@PURE_QUANTA.Q_CAP(CHIPS)':
 'A': CDS_PINID='A';
NODE_NAME     J22 1
 '@S9S_MB_2U_LIB.S9S_MB_2U(SCH_1):PAGE103_I176@PURE_QUANTA.SCONN288_ADR50017P087CC(CHIPS)':
 'VIN_BULK0': CDS_PINID='VIN_BULK0';
NODE_NAME     J22 145
 '@S9S_MB_2U_LIB.S9S_MB_2U(SCH_1):PAGE103_I176@PURE_QUANTA.SCONN288_ADR50017P087CC(CHIPS)':
 'VIN_BULK1': CDS_PINID='VIN_BULK1';
NODE_NAME     J22 146
 '@S9S_MB_2U_LIB.S9S_MB_2U(SCH_1):PAGE103_I176@PURE_QUANTA.SCONN288_ADR50017P087CC(CHIPS)':
 'VIN_BULK2': CDS_PINID='VIN_BULK2';
NODE_NAME     C69 1
 '@S9S_MB_2U_LIB.S9S_MB_2U(SCH_1):PAGE104_I127@PURE_QUANTA.Q_CAP(CHIPS)':
 'A': CDS_PINID='A';
NODE_NAME     C70 1
 '@S9S_MB_2U_LIB.S9S_MB_2U(SCH_1):PAGE104_I129@PURE_QUANTA.Q_CAP(CHIPS)':
 'A': CDS_PINID='A';
NODE_NAME     J23 1
 '@S9S_MB_2U_LIB.S9S_MB_2U(SCH_1):PAGE104_I175@PURE_QUANTA.SCONN288_ADR50017P130CC(CHIPS)':
 'VIN_BULK0': CDS_PINID='VIN_BULK0';
NODE_NAME     J23 145
 '@S9S_MB_2U_LIB.S9S_MB_2U(SCH_1):PAGE104_I175@PURE_QUANTA.SCONN288_ADR50017P130CC(CHIPS)':
 'VIN_BULK1': CDS_PINID='VIN_BULK1';
NODE_NAME     J23 146
 '@S9S_MB_2U_LIB.S9S_MB_2U(SCH_1):PAGE104_I175@PURE_QUANTA.SCONN288_ADR50017P130CC(CHIPS)':
 'VIN_BULK2': CDS_PINID='VIN_BULK2';
NODE_NAME     C97 1
 '@S9S_MB_2U_LIB.S9S_MB_2U(SCH_1):PAGE105_I124@PURE_QUANTA.Q_CAP(CHIPS)':
 'A': CDS_PINID='A';
NODE_NAME     C98 1
 '@S9S_MB_2U_LIB.S9S_MB_2U(SCH_1):PAGE105_I146@PURE_QUANTA.Q_CAP(CHIPS)':
 'A': CDS_PINID='A';
NODE_NAME     J24 1
 '@S9S_MB_2U_LIB.S9S_MB_2U(SCH_1):PAGE105_I180@PURE_QUANTA.SCONN288_ADR50017P087CC(CHIPS)':
 'VIN_BULK0': CDS_PINID='VIN_BULK0';
NODE_NAME     J24 145
 '@S9S_MB_2U_LIB.S9S_MB_2U(SCH_1):PAGE105_I180@PURE_QUANTA.SCONN288_ADR50017P087CC(CHIPS)':
 'VIN_BULK1': CDS_PINID='VIN_BULK1';
NODE_NAME     J24 146
 '@S9S_MB_2U_LIB.S9S_MB_2U(SCH_1):PAGE105_I180@PURE_QUANTA.SCONN288_ADR50017P087CC(CHIPS)':
 'VIN_BULK2': CDS_PINID='VIN_BULK2';
NODE_NAME     C94 1
 '@S9S_MB_2U_LIB.S9S_MB_2U(SCH_1):PAGE106_I127@PURE_QUANTA.Q_CAP(CHIPS)':
 'A': CDS_PINID='A';
NODE_NAME     C95 1
 '@S9S_MB_2U_LIB.S9S_MB_2U(SCH_1):PAGE106_I130@PURE_QUANTA.Q_CAP(CHIPS)':
 'A': CDS_PINID='A';
NODE_NAME     J25 1
 '@S9S_MB_2U_LIB.S9S_MB_2U(SCH_1):PAGE106_I178@PURE_QUANTA.SCONN288_ADR50017P130CC(CHIPS)':
 'VIN_BULK0': CDS_PINID='VIN_BULK0';
NODE_NAME     J25 145
 '@S9S_MB_2U_LIB.S9S_MB_2U(SCH_1):PAGE106_I178@PURE_QUANTA.SCONN288_ADR50017P130CC(CHIPS)':
 'VIN_BULK1': CDS_PINID='VIN_BULK1';
NODE_NAME     J25 146
 '@S9S_MB_2U_LIB.S9S_MB_2U(SCH_1):PAGE106_I178@PURE_QUANTA.SCONN288_ADR50017P130CC(CHIPS)':
 'VIN_BULK2': CDS_PINID='VIN_BULK2';
NODE_NAME     C91 1
 '@S9S_MB_2U_LIB.S9S_MB_2U(SCH_1):PAGE107_I126@PURE_QUANTA.Q_CAP(CHIPS)':
 'A': CDS_PINID='A';
NODE_NAME     C92 1
 '@S9S_MB_2U_LIB.S9S_MB_2U(SCH_1):PAGE107_I128@PURE_QUANTA.Q_CAP(CHIPS)':
 'A': CDS_PINID='A';
NODE_NAME     J26 1
 '@S9S_MB_2U_LIB.S9S_MB_2U(SCH_1):PAGE107_I179@PURE_QUANTA.SCONN288_ADR50017P087CC(CHIPS)':
 'VIN_BULK0': CDS_PINID='VIN_BULK0';
NODE_NAME     J26 145
 '@S9S_MB_2U_LIB.S9S_MB_2U(SCH_1):PAGE107_I179@PURE_QUANTA.SCONN288_ADR50017P087CC(CHIPS)':
 'VIN_BULK1': CDS_PINID='VIN_BULK1';
NODE_NAME     J26 146
 '@S9S_MB_2U_LIB.S9S_MB_2U(SCH_1):PAGE107_I179@PURE_QUANTA.SCONN288_ADR50017P087CC(CHIPS)':
 'VIN_BULK2': CDS_PINID='VIN_BULK2';
NODE_NAME     C88 1
 '@S9S_MB_2U_LIB.S9S_MB_2U(SCH_1):PAGE108_I123@PURE_QUANTA.Q_CAP(CHIPS)':
 'A': CDS_PINID='A';
NODE_NAME     C89 1
 '@S9S_MB_2U_LIB.S9S_MB_2U(SCH_1):PAGE108_I160@PURE_QUANTA.Q_CAP(CHIPS)':
 'A': CDS_PINID='A';
NODE_NAME     J27 1
 '@S9S_MB_2U_LIB.S9S_MB_2U(SCH_1):PAGE108_I178@PURE_QUANTA.SCONN288_ADR50017P130CC(CHIPS)':
 'VIN_BULK0': CDS_PINID='VIN_BULK0';
NODE_NAME     J27 145
 '@S9S_MB_2U_LIB.S9S_MB_2U(SCH_1):PAGE108_I178@PURE_QUANTA.SCONN288_ADR50017P130CC(CHIPS)':
 'VIN_BULK1': CDS_PINID='VIN_BULK1';
NODE_NAME     J27 146
 '@S9S_MB_2U_LIB.S9S_MB_2U(SCH_1):PAGE108_I178@PURE_QUANTA.SCONN288_ADR50017P130CC(CHIPS)':
 'VIN_BULK2': CDS_PINID='VIN_BULK2';
NODE_NAME     C85 1
 '@S9S_MB_2U_LIB.S9S_MB_2U(SCH_1):PAGE109_I125@PURE_QUANTA.Q_CAP(CHIPS)':
 'A': CDS_PINID='A';
NODE_NAME     C86 1
 '@S9S_MB_2U_LIB.S9S_MB_2U(SCH_1):PAGE109_I128@PURE_QUANTA.Q_CAP(CHIPS)':
 'A': CDS_PINID='A';
NODE_NAME     J28 1
 '@S9S_MB_2U_LIB.S9S_MB_2U(SCH_1):PAGE109_I176@PURE_QUANTA.SCONN288_ADR50017P087CC(CHIPS)':
 'VIN_BULK0': CDS_PINID='VIN_BULK0';
NODE_NAME     J28 145
 '@S9S_MB_2U_LIB.S9S_MB_2U(SCH_1):PAGE109_I176@PURE_QUANTA.SCONN288_ADR50017P087CC(CHIPS)':
 'VIN_BULK1': CDS_PINID='VIN_BULK1';
NODE_NAME     J28 146
 '@S9S_MB_2U_LIB.S9S_MB_2U(SCH_1):PAGE109_I176@PURE_QUANTA.SCONN288_ADR50017P087CC(CHIPS)':
 'VIN_BULK2': CDS_PINID='VIN_BULK2';
NODE_NAME     C82 1
 '@S9S_MB_2U_LIB.S9S_MB_2U(SCH_1):PAGE110_I124@PURE_QUANTA.Q_CAP(CHIPS)':
 'A': CDS_PINID='A';
NODE_NAME     C83 1
 '@S9S_MB_2U_LIB.S9S_MB_2U(SCH_1):PAGE110_I126@PURE_QUANTA.Q_CAP(CHIPS)':
 'A': CDS_PINID='A';
NODE_NAME     J29 1
 '@S9S_MB_2U_LIB.S9S_MB_2U(SCH_1):PAGE110_I178@PURE_QUANTA.SCONN288_ADR50017P130CC(CHIPS)':
 'VIN_BULK0': CDS_PINID='VIN_BULK0';
NODE_NAME     J29 145
 '@S9S_MB_2U_LIB.S9S_MB_2U(SCH_1):PAGE110_I178@PURE_QUANTA.SCONN288_ADR50017P130CC(CHIPS)':
 'VIN_BULK1': CDS_PINID='VIN_BULK1';
NODE_NAME     J29 146
 '@S9S_MB_2U_LIB.S9S_MB_2U(SCH_1):PAGE110_I178@PURE_QUANTA.SCONN288_ADR50017P130CC(CHIPS)':
 'VIN_BULK2': CDS_PINID='VIN_BULK2';
NODE_NAME     C79 1
 '@S9S_MB_2U_LIB.S9S_MB_2U(SCH_1):PAGE111_I56@PURE_QUANTA.Q_CAP(CHIPS)':
 'A': CDS_PINID='A';
NODE_NAME     C80 1
 '@S9S_MB_2U_LIB.S9S_MB_2U(SCH_1):PAGE111_I59@PURE_QUANTA.Q_CAP(CHIPS)':
 'A': CDS_PINID='A';
NODE_NAME     J30 1
 '@S9S_MB_2U_LIB.S9S_MB_2U(SCH_1):PAGE111_I178@PURE_QUANTA.SCONN288_ADR50017P087CC(CHIPS)':
 'VIN_BULK0': CDS_PINID='VIN_BULK0';
NODE_NAME     J30 145
 '@S9S_MB_2U_LIB.S9S_MB_2U(SCH_1):PAGE111_I178@PURE_QUANTA.SCONN288_ADR50017P087CC(CHIPS)':
 'VIN_BULK1': CDS_PINID='VIN_BULK1';
NODE_NAME     J30 146
 '@S9S_MB_2U_LIB.S9S_MB_2U(SCH_1):PAGE111_I178@PURE_QUANTA.SCONN288_ADR50017P087CC(CHIPS)':
 'VIN_BULK2': CDS_PINID='VIN_BULK2';
NODE_NAME     C76 1
 '@S9S_MB_2U_LIB.S9S_MB_2U(SCH_1):PAGE112_I125@PURE_QUANTA.Q_CAP(CHIPS)':
 'A': CDS_PINID='A';
NODE_NAME     C77 1
 '@S9S_MB_2U_LIB.S9S_MB_2U(SCH_1):PAGE112_I126@PURE_QUANTA.Q_CAP(CHIPS)':
 'A': CDS_PINID='A';
NODE_NAME     J31 1
 '@S9S_MB_2U_LIB.S9S_MB_2U(SCH_1):PAGE112_I178@PURE_QUANTA.SCONN288_ADR50017P130CC(CHIPS)':
 'VIN_BULK0': CDS_PINID='VIN_BULK0';
NODE_NAME     J31 145
 '@S9S_MB_2U_LIB.S9S_MB_2U(SCH_1):PAGE112_I178@PURE_QUANTA.SCONN288_ADR50017P130CC(CHIPS)':
 'VIN_BULK1': CDS_PINID='VIN_BULK1';
NODE_NAME     J31 146
 '@S9S_MB_2U_LIB.S9S_MB_2U(SCH_1):PAGE112_I178@PURE_QUANTA.SCONN288_ADR50017P130CC(CHIPS)':
 'VIN_BULK2': CDS_PINID='VIN_BULK2';
NODE_NAME     C73 1
 '@S9S_MB_2U_LIB.S9S_MB_2U(SCH_1):PAGE113_I120@PURE_QUANTA.Q_CAP(CHIPS)':
 'A': CDS_PINID='A';
NODE_NAME     C74 1
 '@S9S_MB_2U_LIB.S9S_MB_2U(SCH_1):PAGE113_I122@PURE_QUANTA.Q_CAP(CHIPS)':
 'A': CDS_PINID='A';
NODE_NAME     J32 1
 '@S9S_MB_2U_LIB.S9S_MB_2U(SCH_1):PAGE113_I177@PURE_QUANTA.SCONN288_ADR50017P087CC(CHIPS)':
 'VIN_BULK0': CDS_PINID='VIN_BULK0';
NODE_NAME     J32 145
 '@S9S_MB_2U_LIB.S9S_MB_2U(SCH_1):PAGE113_I177@PURE_QUANTA.SCONN288_ADR50017P087CC(CHIPS)':
 'VIN_BULK1': CDS_PINID='VIN_BULK1';
NODE_NAME     J32 146
 '@S9S_MB_2U_LIB.S9S_MB_2U(SCH_1):PAGE113_I177@PURE_QUANTA.SCONN288_ADR50017P087CC(CHIPS)':
 'VIN_BULK2': CDS_PINID='VIN_BULK2';
NODE_NAME     R1837 2
 '@S9S_MB_2U_LIB.S9S_MB_2U(SCH_1):PAGE240_I3@PURE_QUANTA.Q_RES_4P_12(CHIPS)':
 '2': CDS_PINID='\2\';
NET_NAME
'P12V_SCM'
 '@S9S_MB_2U_LIB.S9S_MB_2U(SCH_1):P12V_SCM':
 C_SIGNAL='@s9s_mb_2u_lib.s9s_mb_2u(sch_1):p12v_scm',
 CDS_GLOBAL_NET='TRUE';
NODE_NAME     R3579 1
 '@S9S_MB_2U_LIB.S9S_MB_2U(SCH_1):PAGE163_I56@PURE_QUANTA.Q_RES(CHIPS)':
 'A': CDS_PINID='A';
NODE_NAME     R3635 1
 '@S9S_MB_2U_LIB.S9S_MB_2U(SCH_1):PAGE163_I129@PURE_QUANTA.Q_RES(CHIPS)':
 'A': CDS_PINID='A';
NODE_NAME     J41 OB2
 '@S9S_MB_2U_LIB.S9S_MB_2U(SCH_1):PAGE227_I173@PURE_QUANTA.SCONN168_ME1016810202011(CHIPS)':
 'MAIN_PWR_EN': CDS_PINID='MAIN_PWR_EN';
NODE_NAME     J41 OB1
 '@S9S_MB_2U_LIB.S9S_MB_2U(SCH_1):PAGE227_I173@PURE_QUANTA.SCONN168_ME1016810202011(CHIPS)':
 'NIC_PWR_GOOD': CDS_PINID='NIC_PWR_GOOD';
NODE_NAME     J41 OA1
 '@S9S_MB_2U_LIB.S9S_MB_2U(SCH_1):PAGE227_I173@PURE_QUANTA.SCONN168_ME1016810202011(CHIPS)':
 'PERST2#': CDS_PINID='\perst2#\';
NODE_NAME     J41 OA2
 '@S9S_MB_2U_LIB.S9S_MB_2U(SCH_1):PAGE227_I173@PURE_QUANTA.SCONN168_ME1016810202011(CHIPS)':
 'PERST3#': CDS_PINID='\perst3#\';
NET_NAME
'P12V_SCM_ADC_ALERT'
 '@S9S_MB_2U_LIB.S9S_MB_2U(SCH_1):P12V_SCM_ADC_ALERT':
 C_SIGNAL='@s9s_mb_2u_lib.s9s_mb_2u(sch_1):p12v_scm_adc_alert';
NODE_NAME     U249 K16
 '@S9S_MB_2U_LIB.S9S_MB_2U(SCH_1):PAGE313_I1@PURE_QUANTA.LCMXO3LF9400C5BG484C(CHIPS)':
 'PR13D': CDS_PINID='PR13D';
NODE_NAME     R3561 2
 '@S9S_MB_2U_LIB.S9S_MB_2U(SCH_1):PAGE163_I64@PURE_QUANTA.Q_RES(CHIPS)':
 'B': CDS_PINID='B';
NET_NAME
'P12V_SCM_ADC_ALERT_R'
 '@S9S_MB_2U_LIB.S9S_MB_2U(SCH_1):P12V_SCM_ADC_ALERT_R':
 C_SIGNAL='@s9s_mb_2u_lib.s9s_mb_2u(sch_1):p12v_scm_adc_alert_r';
NODE_NAME     R3561 1
 '@S9S_MB_2U_LIB.S9S_MB_2U(SCH_1):PAGE163_I64@PURE_QUANTA.Q_RES(CHIPS)':
 'A': CDS_PINID='A';
NODE_NAME     U265 3
 '@S9S_MB_2U_LIB.S9S_MB_2U(SCH_1):PAGE163_I69@PURE_QUANTA.INA230AIRGTR(CHIPS)':
 'ALERT': CDS_PINID='ALERT';
NODE_NAME     R4091 2
 '@S9S_MB_2U_LIB.S9S_MB_2U(SCH_1):PAGE163_I122@PURE_QUANTA.Q_RES(CHIPS)':
 'B': CDS_PINID='B';
NET_NAME
'P12V_SCM_AVIN_PD'
 '@S9S_MB_2U_LIB.S9S_MB_2U(SCH_1):P12V_SCM_AVIN_PD':
 C_SIGNAL='@s9s_mb_2u_lib.s9s_mb_2u(sch_1):p12v_scm_avin_pd';
NODE_NAME     PC2239 1
 '@S9S_MB_2U_LIB.S9S_MB_2U(SCH_1):PAGE229_I53@PURE_QUANTA.Q_CAP(CHIPS)':
 'A': CDS_PINID='A';
NODE_NAME     PR4006 2
 '@S9S_MB_2U_LIB.S9S_MB_2U(SCH_1):PAGE229_I39@PURE_QUANTA.Q_RES(CHIPS)':
 'B': CDS_PINID='B';
NODE_NAME     PR4014 2
 '@S9S_MB_2U_LIB.S9S_MB_2U(SCH_1):PAGE229_I54@PURE_QUANTA.Q_RES(CHIPS)':
 'B': CDS_PINID='B';
NODE_NAME     PU299 12
 '@S9S_MB_2U_LIB.S9S_MB_2U(SCH_1):PAGE229_I90@PURE_QUANTA.RS31312R(CHIPS)':
 'AVIN': CDS_PINID='AVIN';
NET_NAME
'P12V_SCM_CB'
 '@S9S_MB_2U_LIB.S9S_MB_2U(SCH_1):P12V_SCM_CB':
 C_SIGNAL='@s9s_mb_2u_lib.s9s_mb_2u(sch_1):p12v_scm_cb';
NODE_NAME     PR4004 1
 '@S9S_MB_2U_LIB.S9S_MB_2U(SCH_1):PAGE229_I63@PURE_QUANTA.Q_RES(CHIPS)':
 'A': CDS_PINID='A';
NODE_NAME     PU300 B1
 '@S9S_MB_2U_LIB.S9S_MB_2U(SCH_1):PAGE229_I69@PURE_QUANTA.MAX15090BEWIT(CHIPS)':
 'CB': CDS_PINID='CB';
NET_NAME
'P12V_SCM_EN'
 '@S9S_MB_2U_LIB.S9S_MB_2U(SCH_1):P12V_SCM_EN':
 C_SIGNAL='@s9s_mb_2u_lib.s9s_mb_2u(sch_1):p12v_scm_en';
NODE_NAME     R3998 1
 '@S9S_MB_2U_LIB.S9S_MB_2U(SCH_1):PAGE229_I14@PURE_QUANTA.Q_RES(CHIPS)':
 'A': CDS_PINID='A';
NODE_NAME     R3996 2
 '@S9S_MB_2U_LIB.S9S_MB_2U(SCH_1):PAGE229_I17@PURE_QUANTA.Q_RES(CHIPS)':
 'B': CDS_PINID='B';
NODE_NAME     R1857 2
 '@S9S_MB_2U_LIB.S9S_MB_2U(SCH_1):PAGE229_I18@PURE_QUANTA.Q_RES(CHIPS)':
 'B': CDS_PINID='B';
NODE_NAME     R4062 1
 '@S9S_MB_2U_LIB.S9S_MB_2U(SCH_1):PAGE229_I20@PURE_QUANTA.Q_RES(CHIPS)':
 'A': CDS_PINID='A';
NODE_NAME     Q39 D
 '@S9S_MB_2U_LIB.S9S_MB_2U(SCH_1):PAGE229_I9@PURE_QUANTA.MOSFET_NCH_GDS_ESD_PROTECTED(CHIPS)':
 'D': CDS_PINID='D';
NET_NAME
'P12V_SCM_EN_G'
 '@S9S_MB_2U_LIB.S9S_MB_2U(SCH_1):P12V_SCM_EN_G':
 C_SIGNAL='@s9s_mb_2u_lib.s9s_mb_2u(sch_1):p12v_scm_en_g';
NODE_NAME     Q125 6
 '@S9S_MB_2U_LIB.S9S_MB_2U(SCH_1):PAGE229_I21@PURE_QUANTA.MOSFET_NCH_DUAL(CHIPS)':
 'D1': CDS_PINID='D1';
NODE_NAME     R4071 2
 '@S9S_MB_2U_LIB.S9S_MB_2U(SCH_1):PAGE229_I24@PURE_QUANTA.Q_RES(CHIPS)':
 'B': CDS_PINID='B';
NODE_NAME     Q125 5
 '@S9S_MB_2U_LIB.S9S_MB_2U(SCH_1):PAGE229_I26@PURE_QUANTA.MOSFET_NCH_DUAL(CHIPS)':
 'G2': CDS_PINID='G2';
NET_NAME
'P12V_SCM_EN_R'
 '@S9S_MB_2U_LIB.S9S_MB_2U(SCH_1):P12V_SCM_EN_R':
 C_SIGNAL='@s9s_mb_2u_lib.s9s_mb_2u(sch_1):p12v_scm_en_r';
NODE_NAME     Q125 2
 '@S9S_MB_2U_LIB.S9S_MB_2U(SCH_1):PAGE229_I21@PURE_QUANTA.MOSFET_NCH_DUAL(CHIPS)':
 'G1': CDS_PINID='G1';
NODE_NAME     R4062 2
 '@S9S_MB_2U_LIB.S9S_MB_2U(SCH_1):PAGE229_I20@PURE_QUANTA.Q_RES(CHIPS)':
 'B': CDS_PINID='B';
NET_NAME
'P12V_SCM_EN_R2'
 '@S9S_MB_2U_LIB.S9S_MB_2U(SCH_1):P12V_SCM_EN_R2':
 C_SIGNAL='@s9s_mb_2u_lib.s9s_mb_2u(sch_1):p12v_scm_en_r2';
NODE_NAME     R3998 2
 '@S9S_MB_2U_LIB.S9S_MB_2U(SCH_1):PAGE229_I14@PURE_QUANTA.Q_RES(CHIPS)':
 'B': CDS_PINID='B';
NODE_NAME     PU299 1
 '@S9S_MB_2U_LIB.S9S_MB_2U(SCH_1):PAGE229_I90@PURE_QUANTA.RS31312R(CHIPS)':
 'EN': CDS_PINID='EN';
NET_NAME
'P12V_SCM_FAULT_N'
 '@S9S_MB_2U_LIB.S9S_MB_2U(SCH_1):P12V_SCM_FAULT_N':
 C_SIGNAL='@s9s_mb_2u_lib.s9s_mb_2u(sch_1):p12v_scm_fault_n';
NODE_NAME     PU300 C7
 '@S9S_MB_2U_LIB.S9S_MB_2U(SCH_1):PAGE229_I69@PURE_QUANTA.MAX15090BEWIT(CHIPS)':
 'FAULT#': CDS_PINID='\fault#\';
NODE_NAME     R4708 1
 '@S9S_MB_2U_LIB.S9S_MB_2U(SCH_1):PAGE229_I77@PURE_QUANTA.Q_RES(CHIPS)':
 'A': CDS_PINID='A';
NET_NAME
'P12V_SCM_FAULT_R_N'
 '@S9S_MB_2U_LIB.S9S_MB_2U(SCH_1):P12V_SCM_FAULT_R_N':
 C_SIGNAL='@s9s_mb_2u_lib.s9s_mb_2u(sch_1):p12v_scm_fault_r_n';
NODE_NAME     R4013 2
 '@S9S_MB_2U_LIB.S9S_MB_2U(SCH_1):PAGE229_I79@PURE_QUANTA.Q_RES(CHIPS)':
 'B': CDS_PINID='B';
NODE_NAME     Q150 2
 '@S9S_MB_2U_LIB.S9S_MB_2U(SCH_1):PAGE241_I69@PURE_QUANTA.MOSFET_NCH_DUAL(CHIPS)':
 'G1': CDS_PINID='G1';
NODE_NAME     R4709 2
 '@S9S_MB_2U_LIB.S9S_MB_2U(SCH_1):PAGE229_I44@PURE_QUANTA.Q_RES(CHIPS)':
 'B': CDS_PINID='B';
NODE_NAME     R4708 2
 '@S9S_MB_2U_LIB.S9S_MB_2U(SCH_1):PAGE229_I77@PURE_QUANTA.Q_RES(CHIPS)':
 'B': CDS_PINID='B';
NET_NAME
'P12V_SCM_FLTB_N'
 '@S9S_MB_2U_LIB.S9S_MB_2U(SCH_1):P12V_SCM_FLTB_N':
 C_SIGNAL='@s9s_mb_2u_lib.s9s_mb_2u(sch_1):p12v_scm_fltb_n';
NODE_NAME     PR4007 1
 '@S9S_MB_2U_LIB.S9S_MB_2U(SCH_1):PAGE229_I48@PURE_QUANTA.Q_RES(CHIPS)':
 'A': CDS_PINID='A';
NODE_NAME     R4709 1
 '@S9S_MB_2U_LIB.S9S_MB_2U(SCH_1):PAGE229_I44@PURE_QUANTA.Q_RES(CHIPS)':
 'A': CDS_PINID='A';
NODE_NAME     PU299 9
 '@S9S_MB_2U_LIB.S9S_MB_2U(SCH_1):PAGE229_I90@PURE_QUANTA.RS31312R(CHIPS)':
 'FLTB': CDS_PINID='FLTB';
NET_NAME
'P12V_SCM_GATE'
 '@S9S_MB_2U_LIB.S9S_MB_2U(SCH_1):P12V_SCM_GATE':
 C_SIGNAL='@s9s_mb_2u_lib.s9s_mb_2u(sch_1):p12v_scm_gate';
NODE_NAME     PC2236 2
 '@S9S_MB_2U_LIB.S9S_MB_2U(SCH_1):PAGE229_I73@PURE_QUANTA.Q_CAP(CHIPS)':
 'B': CDS_PINID='B';
NODE_NAME     PR4526 2
 '@S9S_MB_2U_LIB.S9S_MB_2U(SCH_1):PAGE229_I76@PURE_QUANTA.Q_RES(CHIPS)':
 'B': CDS_PINID='B';
NODE_NAME     PU300 A6
 '@S9S_MB_2U_LIB.S9S_MB_2U(SCH_1):PAGE229_I69@PURE_QUANTA.MAX15090BEWIT(CHIPS)':
 'GATE': CDS_PINID='GATE';
NODE_NAME     PC2237 1
 '@S9S_MB_2U_LIB.S9S_MB_2U(SCH_1):PAGE229_I75@PURE_QUANTA.Q_CAP(CHIPS)':
 'A': CDS_PINID='A';
NET_NAME
'P12V_SCM_IMON'
 '@S9S_MB_2U_LIB.S9S_MB_2U(SCH_1):P12V_SCM_IMON':
 C_SIGNAL='@s9s_mb_2u_lib.s9s_mb_2u(sch_1):p12v_scm_imon';
NODE_NAME     PR4005 1
 '@S9S_MB_2U_LIB.S9S_MB_2U(SCH_1):PAGE229_I34@PURE_QUANTA.Q_RES(CHIPS)':
 'A': CDS_PINID='A';
NODE_NAME     PC2235 1
 '@S9S_MB_2U_LIB.S9S_MB_2U(SCH_1):PAGE229_I42@PURE_QUANTA.Q_CAP(CHIPS)':
 'A': CDS_PINID='A';
NODE_NAME     PU299 8
 '@S9S_MB_2U_LIB.S9S_MB_2U(SCH_1):PAGE229_I90@PURE_QUANTA.RS31312R(CHIPS)':
 'IMON': CDS_PINID='IMON';
NET_NAME
'P12V_SCM_ISET'
 '@S9S_MB_2U_LIB.S9S_MB_2U(SCH_1):P12V_SCM_ISET':
 C_SIGNAL='@s9s_mb_2u_lib.s9s_mb_2u(sch_1):p12v_scm_iset';
NODE_NAME     PR4540 1
 '@S9S_MB_2U_LIB.S9S_MB_2U(SCH_1):PAGE229_I12@PURE_QUANTA.Q_RES(CHIPS)':
 'A': CDS_PINID='A';
NODE_NAME     PR3999 1
 '@S9S_MB_2U_LIB.S9S_MB_2U(SCH_1):PAGE229_I11@PURE_QUANTA.Q_RES(CHIPS)':
 'A': CDS_PINID='A';
NODE_NAME     PU299 5
 '@S9S_MB_2U_LIB.S9S_MB_2U(SCH_1):PAGE229_I90@PURE_QUANTA.RS31312R(CHIPS)':
 'ISET': CDS_PINID='ISET';
NET_NAME
'P12V_SCM_ISET_R'
 '@S9S_MB_2U_LIB.S9S_MB_2U(SCH_1):P12V_SCM_ISET_R':
 C_SIGNAL='@s9s_mb_2u_lib.s9s_mb_2u(sch_1):p12v_scm_iset_r';
NODE_NAME     PR4540 2
 '@S9S_MB_2U_LIB.S9S_MB_2U(SCH_1):PAGE229_I12@PURE_QUANTA.Q_RES(CHIPS)':
 'B': CDS_PINID='B';
NODE_NAME     PC2340 1
 '@S9S_MB_2U_LIB.S9S_MB_2U(SCH_1):PAGE229_I7@PURE_QUANTA.Q_CAP(CHIPS)':
 'A': CDS_PINID='A';
NET_NAME
'P12V_SCM_OV'
 '@S9S_MB_2U_LIB.S9S_MB_2U(SCH_1):P12V_SCM_OV':
 C_SIGNAL='@s9s_mb_2u_lib.s9s_mb_2u(sch_1):p12v_scm_ov';
NODE_NAME     PR4002 1
 '@S9S_MB_2U_LIB.S9S_MB_2U(SCH_1):PAGE229_I61@PURE_QUANTA.Q_RES(CHIPS)':
 'A': CDS_PINID='A';
NODE_NAME     PR4001 2
 '@S9S_MB_2U_LIB.S9S_MB_2U(SCH_1):PAGE229_I64@PURE_QUANTA.Q_RES(CHIPS)':
 'B': CDS_PINID='B';
NODE_NAME     PU300 D3
 '@S9S_MB_2U_LIB.S9S_MB_2U(SCH_1):PAGE229_I69@PURE_QUANTA.MAX15090BEWIT(CHIPS)':
 'OV': CDS_PINID='OV';
NET_NAME
'P12V_SCM_OV_FB'
 '@S9S_MB_2U_LIB.S9S_MB_2U(SCH_1):P12V_SCM_OV_FB':
 C_SIGNAL='@s9s_mb_2u_lib.s9s_mb_2u(sch_1):p12v_scm_ov_fb';
NODE_NAME     PR4011 1
 '@S9S_MB_2U_LIB.S9S_MB_2U(SCH_1):PAGE229_I50@PURE_QUANTA.Q_RES(CHIPS)':
 'A': CDS_PINID='A';
NODE_NAME     PR4009 2
 '@S9S_MB_2U_LIB.S9S_MB_2U(SCH_1):PAGE229_I51@PURE_QUANTA.Q_RES(CHIPS)':
 'B': CDS_PINID='B';
NODE_NAME     PR4010 2
 '@S9S_MB_2U_LIB.S9S_MB_2U(SCH_1):PAGE229_I52@PURE_QUANTA.Q_RES(CHIPS)':
 'B': CDS_PINID='B';
NODE_NAME     PU299 11
 '@S9S_MB_2U_LIB.S9S_MB_2U(SCH_1):PAGE229_I90@PURE_QUANTA.RS31312R(CHIPS)':
 'OV': CDS_PINID='OV';
NET_NAME
'P12V_SCM_PWRGD'
 '@S9S_MB_2U_LIB.S9S_MB_2U(SCH_1):P12V_SCM_PWRGD':
 C_SIGNAL='@s9s_mb_2u_lib.s9s_mb_2u(sch_1):p12v_scm_pwrgd';
NODE_NAME     PR4012 1
 '@S9S_MB_2U_LIB.S9S_MB_2U(SCH_1):PAGE229_I74@PURE_QUANTA.Q_RES(CHIPS)':
 'A': CDS_PINID='A';
NODE_NAME     PU300 D7
 '@S9S_MB_2U_LIB.S9S_MB_2U(SCH_1):PAGE229_I69@PURE_QUANTA.MAX15090BEWIT(CHIPS)':
 'PG': CDS_PINID='PG';
NET_NAME
'P12V_SCM_R'
 '@S9S_MB_2U_LIB.S9S_MB_2U(SCH_1):P12V_SCM_R':
 C_SIGNAL='@s9s_mb_2u_lib.s9s_mb_2u(sch_1):p12v_scm_r',
 CDS_GLOBAL_NET='TRUE';
NODE_NAME     C2019 1
 '@S9S_MB_2U_LIB.S9S_MB_2U(SCH_1):PAGE163_I49@PURE_QUANTA.Q_CAP(CHIPS)':
 'A': CDS_PINID='A';
NODE_NAME     R3578 1
 '@S9S_MB_2U_LIB.S9S_MB_2U(SCH_1):PAGE163_I58@PURE_QUANTA.Q_RES(CHIPS)':
 'A': CDS_PINID='A';
NODE_NAME     U265 11
 '@S9S_MB_2U_LIB.S9S_MB_2U(SCH_1):PAGE163_I69@PURE_QUANTA.INA230AIRGTR(CHIPS)':
 'BUS': CDS_PINID='\bus\';
NODE_NAME     PR4009 1
 '@S9S_MB_2U_LIB.S9S_MB_2U(SCH_1):PAGE229_I51@PURE_QUANTA.Q_RES(CHIPS)':
 'A': CDS_PINID='A';
NODE_NAME     PC2236 1
 '@S9S_MB_2U_LIB.S9S_MB_2U(SCH_1):PAGE229_I73@PURE_QUANTA.Q_CAP(CHIPS)':
 'A': CDS_PINID='A';
NODE_NAME     PR4526 1
 '@S9S_MB_2U_LIB.S9S_MB_2U(SCH_1):PAGE229_I76@PURE_QUANTA.Q_RES(CHIPS)':
 'A': CDS_PINID='A';
NODE_NAME     PC2238 1
 '@S9S_MB_2U_LIB.S9S_MB_2U(SCH_1):PAGE229_I83@PURE_QUANTA.Q_CAP(CHIPS)':
 'A': CDS_PINID='A';
NODE_NAME     R3635 2
 '@S9S_MB_2U_LIB.S9S_MB_2U(SCH_1):PAGE163_I129@PURE_QUANTA.Q_RES(CHIPS)':
 'B': CDS_PINID='B';
NODE_NAME     PR4006 1
 '@S9S_MB_2U_LIB.S9S_MB_2U(SCH_1):PAGE229_I39@PURE_QUANTA.Q_RES(CHIPS)':
 'A': CDS_PINID='A';
NODE_NAME     PC2241 1
 '@S9S_MB_2U_LIB.S9S_MB_2U(SCH_1):PAGE229_I57@PURE_QUANTA.Q_CAP(CHIPS)':
 'A': CDS_PINID='A';
NODE_NAME     PU300 A4
 '@S9S_MB_2U_LIB.S9S_MB_2U(SCH_1):PAGE229_I69@PURE_QUANTA.MAX15090BEWIT(CHIPS)':
 'OUT_A4': CDS_PINID='OUT_A4';
NODE_NAME     PU300 B4
 '@S9S_MB_2U_LIB.S9S_MB_2U(SCH_1):PAGE229_I69@PURE_QUANTA.MAX15090BEWIT(CHIPS)':
 'OUT_B4': CDS_PINID='OUT_B4';
NODE_NAME     PU300 B6
 '@S9S_MB_2U_LIB.S9S_MB_2U(SCH_1):PAGE229_I69@PURE_QUANTA.MAX15090BEWIT(CHIPS)':
 'OUT_B6': CDS_PINID='OUT_B6';
NODE_NAME     PU300 C4
 '@S9S_MB_2U_LIB.S9S_MB_2U(SCH_1):PAGE229_I69@PURE_QUANTA.MAX15090BEWIT(CHIPS)':
 'OUT_C4': CDS_PINID='OUT_C4';
NODE_NAME     PU300 C6
 '@S9S_MB_2U_LIB.S9S_MB_2U(SCH_1):PAGE229_I69@PURE_QUANTA.MAX15090BEWIT(CHIPS)':
 'OUT_C6': CDS_PINID='OUT_C6';
NODE_NAME     PU300 D4
 '@S9S_MB_2U_LIB.S9S_MB_2U(SCH_1):PAGE229_I69@PURE_QUANTA.MAX15090BEWIT(CHIPS)':
 'OUT_D4': CDS_PINID='OUT_D4';
NODE_NAME     PU300 D6
 '@S9S_MB_2U_LIB.S9S_MB_2U(SCH_1):PAGE229_I69@PURE_QUANTA.MAX15090BEWIT(CHIPS)':
 'OUT_D6': CDS_PINID='OUT_D6';
NODE_NAME     PD116 C
 '@S9S_MB_2U_LIB.S9S_MB_2U(SCH_1):PAGE229_I82@PURE_QUANTA.SCHOTTKY_AC(CHIPS)':
 'C': CDS_PINID='C';
NODE_NAME     PC2240 1
 '@S9S_MB_2U_LIB.S9S_MB_2U(SCH_1):PAGE229_I84@PURE_QUANTA.Q_CAP(CHIPS)':
 'A': CDS_PINID='A';
NODE_NAME     PC2242 1
 '@S9S_MB_2U_LIB.S9S_MB_2U(SCH_1):PAGE229_I88@PURE_QUANTA.Q_CAP(CHIPS)':
 'A': CDS_PINID='A';
NODE_NAME     PU299 13
 '@S9S_MB_2U_LIB.S9S_MB_2U(SCH_1):PAGE229_I90@PURE_QUANTA.RS31312R(CHIPS)':
 'VOUT_13': CDS_PINID='VOUT_13';
NODE_NAME     PU299 14
 '@S9S_MB_2U_LIB.S9S_MB_2U(SCH_1):PAGE229_I90@PURE_QUANTA.RS31312R(CHIPS)':
 'VOUT_14': CDS_PINID='VOUT_14';
NODE_NAME     PU299 15
 '@S9S_MB_2U_LIB.S9S_MB_2U(SCH_1):PAGE229_I90@PURE_QUANTA.RS31312R(CHIPS)':
 'VOUT_15': CDS_PINID='VOUT_15';
NODE_NAME     PU299 16
 '@S9S_MB_2U_LIB.S9S_MB_2U(SCH_1):PAGE229_I90@PURE_QUANTA.RS31312R(CHIPS)':
 'VOUT_16': CDS_PINID='VOUT_16';
NODE_NAME     PU299 17
 '@S9S_MB_2U_LIB.S9S_MB_2U(SCH_1):PAGE229_I90@PURE_QUANTA.RS31312R(CHIPS)':
 'VOUT_17': CDS_PINID='VOUT_17';
NODE_NAME     PU299 18
 '@S9S_MB_2U_LIB.S9S_MB_2U(SCH_1):PAGE229_I90@PURE_QUANTA.RS31312R(CHIPS)':
 'VOUT_18': CDS_PINID='VOUT_18';
NODE_NAME     PU299 19
 '@S9S_MB_2U_LIB.S9S_MB_2U(SCH_1):PAGE229_I90@PURE_QUANTA.RS31312R(CHIPS)':
 'VOUT_19': CDS_PINID='VOUT_19';
NODE_NAME     PU299 20
 '@S9S_MB_2U_LIB.S9S_MB_2U(SCH_1):PAGE229_I90@PURE_QUANTA.RS31312R(CHIPS)':
 'VOUT_20': CDS_PINID='VOUT_20';
NET_NAME
'P12V_SCM_REG'
 '@S9S_MB_2U_LIB.S9S_MB_2U(SCH_1):P12V_SCM_REG':
 C_SIGNAL='@s9s_mb_2u_lib.s9s_mb_2u(sch_1):p12v_scm_reg';
NODE_NAME     PC2234 2
 '@S9S_MB_2U_LIB.S9S_MB_2U(SCH_1):PAGE229_I66@PURE_QUANTA.Q_CAP(CHIPS)':
 'B': CDS_PINID='B';
NODE_NAME     PU300 D1
 '@S9S_MB_2U_LIB.S9S_MB_2U(SCH_1):PAGE229_I69@PURE_QUANTA.MAX15090BEWIT(CHIPS)':
 'REG': CDS_PINID='REG';
NET_NAME
'P12V_SCM_SENSE'
 '@S9S_MB_2U_LIB.S9S_MB_2U(SCH_1):P12V_SCM_SENSE':
 C_SIGNAL='@s9s_mb_2u_lib.s9s_mb_2u(sch_1):p12v_scm_sense';
NODE_NAME     PR4008 1
 '@S9S_MB_2U_LIB.S9S_MB_2U(SCH_1):PAGE229_I72@PURE_QUANTA.Q_RES(CHIPS)':
 'A': CDS_PINID='A';
NODE_NAME     PU300 A1
 '@S9S_MB_2U_LIB.S9S_MB_2U(SCH_1):PAGE229_I69@PURE_QUANTA.MAX15090BEWIT(CHIPS)':
 'ISENSE': CDS_PINID='ISENSE';
NET_NAME
'P12V_SCM_SS'
 '@S9S_MB_2U_LIB.S9S_MB_2U(SCH_1):P12V_SCM_SS':
 C_SIGNAL='@s9s_mb_2u_lib.s9s_mb_2u(sch_1):p12v_scm_ss';
NODE_NAME     PC2232 1
 '@S9S_MB_2U_LIB.S9S_MB_2U(SCH_1):PAGE229_I33@PURE_QUANTA.Q_CAP(CHIPS)':
 'A': CDS_PINID='A';
NODE_NAME     PU299 6
 '@S9S_MB_2U_LIB.S9S_MB_2U(SCH_1):PAGE229_I90@PURE_QUANTA.RS31312R(CHIPS)':
 'SS': CDS_PINID='SS';
NET_NAME
'P12V_SCM_TIMER'
 '@S9S_MB_2U_LIB.S9S_MB_2U(SCH_1):P12V_SCM_TIMER':
 C_SIGNAL='@s9s_mb_2u_lib.s9s_mb_2u(sch_1):p12v_scm_timer';
NODE_NAME     PC2229 1
 '@S9S_MB_2U_LIB.S9S_MB_2U(SCH_1):PAGE229_I8@PURE_QUANTA.Q_CAP(CHIPS)':
 'A': CDS_PINID='A';
NODE_NAME     PU299 4
 '@S9S_MB_2U_LIB.S9S_MB_2U(SCH_1):PAGE229_I90@PURE_QUANTA.RS31312R(CHIPS)':
 'TIMER': CDS_PINID='TIMER';
NET_NAME
'P12V_SCM_UV'
 '@S9S_MB_2U_LIB.S9S_MB_2U(SCH_1):P12V_SCM_UV':
 C_SIGNAL='@s9s_mb_2u_lib.s9s_mb_2u(sch_1):p12v_scm_uv';
NODE_NAME     PR4000 2
 '@S9S_MB_2U_LIB.S9S_MB_2U(SCH_1):PAGE229_I67@PURE_QUANTA.Q_RES(CHIPS)':
 'B': CDS_PINID='B';
NODE_NAME     R3997 2
 '@S9S_MB_2U_LIB.S9S_MB_2U(SCH_1):PAGE229_I27@PURE_QUANTA.Q_RES(CHIPS)':
 'B': CDS_PINID='B';
NODE_NAME     PR4001 1
 '@S9S_MB_2U_LIB.S9S_MB_2U(SCH_1):PAGE229_I64@PURE_QUANTA.Q_RES(CHIPS)':
 'A': CDS_PINID='A';
NODE_NAME     PU300 D2
 '@S9S_MB_2U_LIB.S9S_MB_2U(SCH_1):PAGE229_I69@PURE_QUANTA.MAX15090BEWIT(CHIPS)':
 'UV': CDS_PINID='UV';
NET_NAME
'P12V_SCM_UV_R'
 '@S9S_MB_2U_LIB.S9S_MB_2U(SCH_1):P12V_SCM_UV_R':
 C_SIGNAL='@s9s_mb_2u_lib.s9s_mb_2u(sch_1):p12v_scm_uv_r';
NODE_NAME     R3997 1
 '@S9S_MB_2U_LIB.S9S_MB_2U(SCH_1):PAGE229_I27@PURE_QUANTA.Q_RES(CHIPS)':
 'A': CDS_PINID='A';
NODE_NAME     Q125 3
 '@S9S_MB_2U_LIB.S9S_MB_2U(SCH_1):PAGE229_I26@PURE_QUANTA.MOSFET_NCH_DUAL(CHIPS)':
 'D2': CDS_PINID='D2';
NET_NAME
'P12V_SCM_VCC'
 '@S9S_MB_2U_LIB.S9S_MB_2U(SCH_1):P12V_SCM_VCC':
 C_SIGNAL='@s9s_mb_2u_lib.s9s_mb_2u(sch_1):p12v_scm_vcc';
NODE_NAME     PC2233 1
 '@S9S_MB_2U_LIB.S9S_MB_2U(SCH_1):PAGE229_I68@PURE_QUANTA.Q_CAP(CHIPS)':
 'A': CDS_PINID='A';
NODE_NAME     PR4003 2
 '@S9S_MB_2U_LIB.S9S_MB_2U(SCH_1):PAGE229_I70@PURE_QUANTA.Q_RES(CHIPS)':
 'B': CDS_PINID='B';
NODE_NAME     PU300 A2
 '@S9S_MB_2U_LIB.S9S_MB_2U(SCH_1):PAGE229_I69@PURE_QUANTA.MAX15090BEWIT(CHIPS)':
 'VCC': CDS_PINID='VCC';
NET_NAME
'P1V05_PCH_AUX'
 '@S9S_MB_2U_LIB.S9S_MB_2U(SCH_1):P1V05_PCH_AUX':
 C_SIGNAL='@s9s_mb_2u_lib.s9s_mb_2u(sch_1):p1v05_pch_aux',
 CDS_GLOBAL_NET='TRUE';
NODE_NAME     J42 1
 '@S9S_MB_2U_LIB.S9S_MB_2U(SCH_1):PAGE133_I44@PURE_QUANTA.SCONN60_ASP21410801(CHIPS)':
 '1': CDS_PINID='\1\';
NODE_NAME     C547 1
 '@S9S_MB_2U_LIB.S9S_MB_2U(SCH_1):PAGE133_I100@PURE_QUANTA.Q_CAP(CHIPS)':
 'A': CDS_PINID='A';
NODE_NAME     R747 1
 '@S9S_MB_2U_LIB.S9S_MB_2U(SCH_1):PAGE134_I176@PURE_QUANTA.Q_RES(CHIPS)':
 'A': CDS_PINID='A';
NODE_NAME     R751 1
 '@S9S_MB_2U_LIB.S9S_MB_2U(SCH_1):PAGE134_I177@PURE_QUANTA.Q_RES(CHIPS)':
 'A': CDS_PINID='A';
NODE_NAME     R750 1
 '@S9S_MB_2U_LIB.S9S_MB_2U(SCH_1):PAGE134_I178@PURE_QUANTA.Q_RES(CHIPS)':
 'A': CDS_PINID='A';
NODE_NAME     R749 1
 '@S9S_MB_2U_LIB.S9S_MB_2U(SCH_1):PAGE134_I179@PURE_QUANTA.Q_RES(CHIPS)':
 'A': CDS_PINID='A';
NODE_NAME     R748 1
 '@S9S_MB_2U_LIB.S9S_MB_2U(SCH_1):PAGE134_I180@PURE_QUANTA.Q_RES(CHIPS)':
 'A': CDS_PINID='A';
NODE_NAME     U87 D
 '@S9S_MB_2U_LIB.S9S_MB_2U(SCH_1):PAGE137_I96@PURE_QUANTA.MOSFET_N(CHIPS)':
 'DRAIN': CDS_PINID='DRAIN';
NODE_NAME     R1026 2
 '@S9S_MB_2U_LIB.S9S_MB_2U(SCH_1):PAGE174_I37@PURE_QUANTA.Q_RES(CHIPS)':
 'B': CDS_PINID='B';
NODE_NAME     U4 AB19
 '@S9S_MB_2U_LIB.S9S_MB_2U(SCH_1):PAGE178_I11@PURE_QUANTA.EMMITSBURG_REV0P9(CHIPS)':
 'VCCP_1P05_AB19': CDS_PINID='VCCP_1P05_AB19';
NODE_NAME     U4 AB20
 '@S9S_MB_2U_LIB.S9S_MB_2U(SCH_1):PAGE178_I11@PURE_QUANTA.EMMITSBURG_REV0P9(CHIPS)':
 'VCCP_1P05_AB20': CDS_PINID='VCCP_1P05_AB20';
NODE_NAME     U4 AB22
 '@S9S_MB_2U_LIB.S9S_MB_2U(SCH_1):PAGE178_I11@PURE_QUANTA.EMMITSBURG_REV0P9(CHIPS)':
 'VCCP_1P05_AB22': CDS_PINID='VCCP_1P05_AB22';
NODE_NAME     U4 AB24
 '@S9S_MB_2U_LIB.S9S_MB_2U(SCH_1):PAGE178_I11@PURE_QUANTA.EMMITSBURG_REV0P9(CHIPS)':
 'VCCP_1P05_AB24': CDS_PINID='VCCP_1P05_AB24';
NODE_NAME     U4 AD25
 '@S9S_MB_2U_LIB.S9S_MB_2U(SCH_1):PAGE178_I11@PURE_QUANTA.EMMITSBURG_REV0P9(CHIPS)':
 'VCCP_1P05_AD25': CDS_PINID='VCCP_1P05_AD25';
NODE_NAME     U4 AD27
 '@S9S_MB_2U_LIB.S9S_MB_2U(SCH_1):PAGE178_I11@PURE_QUANTA.EMMITSBURG_REV0P9(CHIPS)':
 'VCCP_1P05_AD27': CDS_PINID='VCCP_1P05_AD27';
NODE_NAME     U4 AF25
 '@S9S_MB_2U_LIB.S9S_MB_2U(SCH_1):PAGE178_I11@PURE_QUANTA.EMMITSBURG_REV0P9(CHIPS)':
 'VCCP_1P05_AF25': CDS_PINID='VCCP_1P05_AF25';
NODE_NAME     U4 AF27
 '@S9S_MB_2U_LIB.S9S_MB_2U(SCH_1):PAGE178_I11@PURE_QUANTA.EMMITSBURG_REV0P9(CHIPS)':
 'VCCP_1P05_AF27': CDS_PINID='VCCP_1P05_AF27';
NODE_NAME     U4 AG25
 '@S9S_MB_2U_LIB.S9S_MB_2U(SCH_1):PAGE178_I11@PURE_QUANTA.EMMITSBURG_REV0P9(CHIPS)':
 'VCCP_1P05_AG25': CDS_PINID='VCCP_1P05_AG25';
NODE_NAME     U4 AG27
 '@S9S_MB_2U_LIB.S9S_MB_2U(SCH_1):PAGE178_I11@PURE_QUANTA.EMMITSBURG_REV0P9(CHIPS)':
 'VCCP_1P05_AG27': CDS_PINID='VCCP_1P05_AG27';
NODE_NAME     U4 AJ25
 '@S9S_MB_2U_LIB.S9S_MB_2U(SCH_1):PAGE178_I11@PURE_QUANTA.EMMITSBURG_REV0P9(CHIPS)':
 'VCCP_1P05_AJ25': CDS_PINID='VCCP_1P05_AJ25';
NODE_NAME     U4 AJ27
 '@S9S_MB_2U_LIB.S9S_MB_2U(SCH_1):PAGE178_I11@PURE_QUANTA.EMMITSBURG_REV0P9(CHIPS)':
 'VCCP_1P05_AJ27': CDS_PINID='VCCP_1P05_AJ27';
NODE_NAME     U4 AR26
 '@S9S_MB_2U_LIB.S9S_MB_2U(SCH_1):PAGE178_I11@PURE_QUANTA.EMMITSBURG_REV0P9(CHIPS)':
 'VCCP_1P05_AR26': CDS_PINID='VCCP_1P05_AR26';
NODE_NAME     U4 M24
 '@S9S_MB_2U_LIB.S9S_MB_2U(SCH_1):PAGE178_I11@PURE_QUANTA.EMMITSBURG_REV0P9(CHIPS)':
 'VCCP_1P05_M24': CDS_PINID='VCCP_1P05_M24';
NODE_NAME     U4 N23
 '@S9S_MB_2U_LIB.S9S_MB_2U(SCH_1):PAGE178_I11@PURE_QUANTA.EMMITSBURG_REV0P9(CHIPS)':
 'VCCP_1P05_N23': CDS_PINID='VCCP_1P05_N23';
NODE_NAME     U4 N26
 '@S9S_MB_2U_LIB.S9S_MB_2U(SCH_1):PAGE178_I11@PURE_QUANTA.EMMITSBURG_REV0P9(CHIPS)':
 'VCCP_1P05_N26': CDS_PINID='VCCP_1P05_N26';
NODE_NAME     U4 P15
 '@S9S_MB_2U_LIB.S9S_MB_2U(SCH_1):PAGE178_I11@PURE_QUANTA.EMMITSBURG_REV0P9(CHIPS)':
 'VCCP_1P05_P15': CDS_PINID='VCCP_1P05_P15';
NODE_NAME     U4 W17
 '@S9S_MB_2U_LIB.S9S_MB_2U(SCH_1):PAGE178_I11@PURE_QUANTA.EMMITSBURG_REV0P9(CHIPS)':
 'VCCP_1P05_W17': CDS_PINID='VCCP_1P05_W17';
NODE_NAME     U4 W19
 '@S9S_MB_2U_LIB.S9S_MB_2U(SCH_1):PAGE178_I11@PURE_QUANTA.EMMITSBURG_REV0P9(CHIPS)':
 'VCCP_1P05_W19': CDS_PINID='VCCP_1P05_W19';
NODE_NAME     U4 W20
 '@S9S_MB_2U_LIB.S9S_MB_2U(SCH_1):PAGE178_I11@PURE_QUANTA.EMMITSBURG_REV0P9(CHIPS)':
 'VCCP_1P05_W20': CDS_PINID='VCCP_1P05_W20';
NODE_NAME     U4 W22
 '@S9S_MB_2U_LIB.S9S_MB_2U(SCH_1):PAGE178_I11@PURE_QUANTA.EMMITSBURG_REV0P9(CHIPS)':
 'VCCP_1P05_W22': CDS_PINID='VCCP_1P05_W22';
NODE_NAME     U4 W24
 '@S9S_MB_2U_LIB.S9S_MB_2U(SCH_1):PAGE178_I11@PURE_QUANTA.EMMITSBURG_REV0P9(CHIPS)':
 'VCCP_1P05_W24': CDS_PINID='VCCP_1P05_W24';
NODE_NAME     U4 AF20
 '@S9S_MB_2U_LIB.S9S_MB_2U(SCH_1):PAGE178_I11@PURE_QUANTA.EMMITSBURG_REV0P9(CHIPS)':
 'VCCP_VNN_AF20': CDS_PINID='VCCP_VNN_AF20';
NODE_NAME     U4 AF22
 '@S9S_MB_2U_LIB.S9S_MB_2U(SCH_1):PAGE178_I11@PURE_QUANTA.EMMITSBURG_REV0P9(CHIPS)':
 'VCCP_VNN_AF22': CDS_PINID='VCCP_VNN_AF22';
NODE_NAME     U4 AG20
 '@S9S_MB_2U_LIB.S9S_MB_2U(SCH_1):PAGE178_I11@PURE_QUANTA.EMMITSBURG_REV0P9(CHIPS)':
 'VCCP_VNN_AG20': CDS_PINID='VCCP_VNN_AG20';
NODE_NAME     U4 AG22
 '@S9S_MB_2U_LIB.S9S_MB_2U(SCH_1):PAGE178_I11@PURE_QUANTA.EMMITSBURG_REV0P9(CHIPS)':
 'VCCP_VNN_AG22': CDS_PINID='VCCP_VNN_AG22';
NODE_NAME     U4 AJ20
 '@S9S_MB_2U_LIB.S9S_MB_2U(SCH_1):PAGE178_I11@PURE_QUANTA.EMMITSBURG_REV0P9(CHIPS)':
 'VCCP_VNN_AJ20': CDS_PINID='VCCP_VNN_AJ20';
NODE_NAME     U4 AJ22
 '@S9S_MB_2U_LIB.S9S_MB_2U(SCH_1):PAGE178_I11@PURE_QUANTA.EMMITSBURG_REV0P9(CHIPS)':
 'VCCP_VNN_AJ22': CDS_PINID='VCCP_VNN_AJ22';
NODE_NAME     U4 AL20
 '@S9S_MB_2U_LIB.S9S_MB_2U(SCH_1):PAGE178_I11@PURE_QUANTA.EMMITSBURG_REV0P9(CHIPS)':
 'VCCP_VNN_AL20': CDS_PINID='VCCP_VNN_AL20';
NODE_NAME     U4 AL22
 '@S9S_MB_2U_LIB.S9S_MB_2U(SCH_1):PAGE178_I11@PURE_QUANTA.EMMITSBURG_REV0P9(CHIPS)':
 'VCCP_VNN_AL22': CDS_PINID='VCCP_VNN_AL22';
NODE_NAME     U4 AN23
 '@S9S_MB_2U_LIB.S9S_MB_2U(SCH_1):PAGE178_I11@PURE_QUANTA.EMMITSBURG_REV0P9(CHIPS)':
 'VCCP_VNN_AN23': CDS_PINID='VCCP_VNN_AN23';
NODE_NAME     U4 AP21
 '@S9S_MB_2U_LIB.S9S_MB_2U(SCH_1):PAGE178_I11@PURE_QUANTA.EMMITSBURG_REV0P9(CHIPS)':
 'VCCP_VNN_AP21': CDS_PINID='VCCP_VNN_AP21';
NODE_NAME     U4 AR23
 '@S9S_MB_2U_LIB.S9S_MB_2U(SCH_1):PAGE178_I11@PURE_QUANTA.EMMITSBURG_REV0P9(CHIPS)':
 'VCCP_VNN_AR23': CDS_PINID='VCCP_VNN_AR23';
NODE_NAME     C1178 1
 '@S9S_MB_2U_LIB.S9S_MB_2U(SCH_1):PAGE181_I6@PURE_QUANTA.Q_CAP(CHIPS)':
 'A': CDS_PINID='A';
NODE_NAME     C1185 1
 '@S9S_MB_2U_LIB.S9S_MB_2U(SCH_1):PAGE181_I7@PURE_QUANTA.Q_CAP(CHIPS)':
 'A': CDS_PINID='A';
NODE_NAME     C1192 1
 '@S9S_MB_2U_LIB.S9S_MB_2U(SCH_1):PAGE181_I8@PURE_QUANTA.Q_CAP(CHIPS)':
 'A': CDS_PINID='A';
NODE_NAME     C1205 1
 '@S9S_MB_2U_LIB.S9S_MB_2U(SCH_1):PAGE181_I12@PURE_QUANTA.Q_CAP(CHIPS)':
 'A': CDS_PINID='A';
NODE_NAME     C1228 1
 '@S9S_MB_2U_LIB.S9S_MB_2U(SCH_1):PAGE181_I13@PURE_QUANTA.Q_CAP(CHIPS)':
 'A': CDS_PINID='A';
NODE_NAME     C1187 1
 '@S9S_MB_2U_LIB.S9S_MB_2U(SCH_1):PAGE181_I40@PURE_QUANTA.Q_CAP(CHIPS)':
 'A': CDS_PINID='A';
NODE_NAME     C1182 1
 '@S9S_MB_2U_LIB.S9S_MB_2U(SCH_1):PAGE181_I42@PURE_QUANTA.Q_CAP(CHIPS)':
 'A': CDS_PINID='A';
NODE_NAME     C1198 1
 '@S9S_MB_2U_LIB.S9S_MB_2U(SCH_1):PAGE181_I43@PURE_QUANTA.Q_CAP(CHIPS)':
 'A': CDS_PINID='A';
NODE_NAME     C1210 1
 '@S9S_MB_2U_LIB.S9S_MB_2U(SCH_1):PAGE181_I45@PURE_QUANTA.Q_CAP(CHIPS)':
 'A': CDS_PINID='A';
NODE_NAME     C1203 1
 '@S9S_MB_2U_LIB.S9S_MB_2U(SCH_1):PAGE181_I48@PURE_QUANTA.Q_CAP(CHIPS)':
 'A': CDS_PINID='A';
NODE_NAME     C1231 1
 '@S9S_MB_2U_LIB.S9S_MB_2U(SCH_1):PAGE181_I49@PURE_QUANTA.Q_CAP(CHIPS)':
 'A': CDS_PINID='A';
NODE_NAME     C1183 1
 '@S9S_MB_2U_LIB.S9S_MB_2U(SCH_1):PAGE181_I51@PURE_QUANTA.Q_CAP(CHIPS)':
 'A': CDS_PINID='A';
NODE_NAME     C1189 1
 '@S9S_MB_2U_LIB.S9S_MB_2U(SCH_1):PAGE181_I58@PURE_QUANTA.Q_CAP(CHIPS)':
 'A': CDS_PINID='A';
NODE_NAME     C1200 1
 '@S9S_MB_2U_LIB.S9S_MB_2U(SCH_1):PAGE181_I59@PURE_QUANTA.Q_CAP(CHIPS)':
 'A': CDS_PINID='A';
NODE_NAME     C1204 1
 '@S9S_MB_2U_LIB.S9S_MB_2U(SCH_1):PAGE181_I60@PURE_QUANTA.Q_CAP(CHIPS)':
 'A': CDS_PINID='A';
NODE_NAME     C1214 1
 '@S9S_MB_2U_LIB.S9S_MB_2U(SCH_1):PAGE181_I61@PURE_QUANTA.Q_CAP(CHIPS)':
 'A': CDS_PINID='A';
NODE_NAME     C1242 1
 '@S9S_MB_2U_LIB.S9S_MB_2U(SCH_1):PAGE181_I63@PURE_QUANTA.Q_CAP(CHIPS)':
 'A': CDS_PINID='A';
NODE_NAME     R1463 1
 '@S9S_MB_2U_LIB.S9S_MB_2U(SCH_1):PAGE181_I129@PURE_QUANTA.Q_RES(CHIPS)':
 'A': CDS_PINID='A';
NODE_NAME     C1250 1
 '@S9S_MB_2U_LIB.S9S_MB_2U(SCH_1):PAGE181_I137@PURE_QUANTA.Q_CAP(CHIPS)':
 'A': CDS_PINID='A';
NODE_NAME     R1298 1
 '@S9S_MB_2U_LIB.S9S_MB_2U(SCH_1):PAGE188_I22@PURE_QUANTA.Q_RES(CHIPS)':
 'A': CDS_PINID='A';
NODE_NAME     R1498 1
 '@S9S_MB_2U_LIB.S9S_MB_2U(SCH_1):PAGE188_I76@PURE_QUANTA.Q_RES(CHIPS)':
 'A': CDS_PINID='A';
NODE_NAME     R1262 1
 '@S9S_MB_2U_LIB.S9S_MB_2U(SCH_1):PAGE192_I11@PURE_QUANTA.Q_RES(CHIPS)':
 'A': CDS_PINID='A';
NODE_NAME     R1260 1
 '@S9S_MB_2U_LIB.S9S_MB_2U(SCH_1):PAGE192_I17@PURE_QUANTA.Q_RES(CHIPS)':
 'A': CDS_PINID='A';
NODE_NAME     R3042 1
 '@S9S_MB_2U_LIB.S9S_MB_2U(SCH_1):PAGE192_I18@PURE_QUANTA.Q_RES(CHIPS)':
 'A': CDS_PINID='A';
NODE_NAME     PC1227 1
 '@S9S_MB_2U_LIB.S9S_MB_2U(SCH_1):PAGE248_I41@PURE_QUANTA.Q_CAPP(CHIPS)':
 'A': CDS_PINID='A';
NODE_NAME     PJ62 2
 '@S9S_MB_2U_LIB.S9S_MB_2U(SCH_1):PAGE248_I43@PURE_QUANTA.Q_SHORT(CHIPS)':
 '2': CDS_PINID='\2\';
NODE_NAME     R2512 1
 '@S9S_MB_2U_LIB.S9S_MB_2U(SCH_1):PAGE226_I91@PURE_QUANTA.Q_RES(CHIPS)':
 'A': CDS_PINID='A';
NODE_NAME     R1317 1
 '@S9S_MB_2U_LIB.S9S_MB_2U(SCH_1):PAGE189_I88@PURE_QUANTA.Q_RES(CHIPS)':
 'A': CDS_PINID='A';
NODE_NAME     R1343 1
 '@S9S_MB_2U_LIB.S9S_MB_2U(SCH_1):PAGE189_I113@PURE_QUANTA.Q_RES(CHIPS)':
 'A': CDS_PINID='A';
NODE_NAME     R1342 1
 '@S9S_MB_2U_LIB.S9S_MB_2U(SCH_1):PAGE189_I114@PURE_QUANTA.Q_RES(CHIPS)':
 'A': CDS_PINID='A';
NODE_NAME     PC1225 1
 '@S9S_MB_2U_LIB.S9S_MB_2U(SCH_1):PAGE248_I44@PURE_QUANTA.Q_CAP(CHIPS)':
 'A': CDS_PINID='A';
NODE_NAME     C1244 1
 '@S9S_MB_2U_LIB.S9S_MB_2U(SCH_1):PAGE181_I152@PURE_QUANTA.Q_CAP(CHIPS)':
 'A': CDS_PINID='A';
NODE_NAME     C1246 1
 '@S9S_MB_2U_LIB.S9S_MB_2U(SCH_1):PAGE181_I153@PURE_QUANTA.Q_CAP(CHIPS)':
 'A': CDS_PINID='A';
NODE_NAME     C1247 1
 '@S9S_MB_2U_LIB.S9S_MB_2U(SCH_1):PAGE181_I154@PURE_QUANTA.Q_CAP(CHIPS)':
 'A': CDS_PINID='A';
NODE_NAME     C1248 1
 '@S9S_MB_2U_LIB.S9S_MB_2U(SCH_1):PAGE181_I155@PURE_QUANTA.Q_CAP(CHIPS)':
 'A': CDS_PINID='A';
NODE_NAME     C1249 1
 '@S9S_MB_2U_LIB.S9S_MB_2U(SCH_1):PAGE181_I156@PURE_QUANTA.Q_CAP(CHIPS)':
 'A': CDS_PINID='A';
NODE_NAME     R1266 1
 '@S9S_MB_2U_LIB.S9S_MB_2U(SCH_1):PAGE191_I38@PURE_QUANTA.Q_RES(CHIPS)':
 'A': CDS_PINID='A';
NODE_NAME     PL150 2
 '@S9S_MB_2U_LIB.S9S_MB_2U(SCH_1):PAGE248_I53@PURE_QUANTA.Q_INDUCTOR(CHIPS)':
 '2': CDS_PINID='\2\';
NODE_NAME     PC1226 1
 '@S9S_MB_2U_LIB.S9S_MB_2U(SCH_1):PAGE248_I45@PURE_QUANTA.Q_CAP(CHIPS)':
 'A': CDS_PINID='A';
NODE_NAME     R2242 1
 '@S9S_MB_2U_LIB.S9S_MB_2U(SCH_1):PAGE184_I50@PURE_QUANTA.Q_RES(CHIPS)':
 'A': CDS_PINID='A';
NODE_NAME     PC1229 1
 '@S9S_MB_2U_LIB.S9S_MB_2U(SCH_1):PAGE248_I47@PURE_QUANTA.Q_CAPP(CHIPS)':
 'A': CDS_PINID='A';
NODE_NAME     L2 1
 '@S9S_MB_2U_LIB.S9S_MB_2U(SCH_1):PAGE181_I164@PURE_QUANTA.Q_INDUCTOR(CHIPS)':
 '1': CDS_PINID='\1\';
NODE_NAME     R4803 1
 '@S9S_MB_2U_LIB.S9S_MB_2U(SCH_1):PAGE181_I165@PURE_QUANTA.Q_RES(CHIPS)':
 'A': CDS_PINID='A';
NODE_NAME     PC1224 1
 '@S9S_MB_2U_LIB.S9S_MB_2U(SCH_1):PAGE248_I38@PURE_QUANTA.Q_CAP(CHIPS)':
 'A': CDS_PINID='A';
NODE_NAME     PC117 1
 '@S9S_MB_2U_LIB.S9S_MB_2U(SCH_1):PAGE248_I40@PURE_QUANTA.Q_CAPP(CHIPS)':
 'A': CDS_PINID='A';
NODE_NAME     PC1230 1
 '@S9S_MB_2U_LIB.S9S_MB_2U(SCH_1):PAGE248_I48@PURE_QUANTA.Q_CAPP(CHIPS)':
 'A': CDS_PINID='A';
NODE_NAME     R2234 1
 '@S9S_MB_2U_LIB.S9S_MB_2U(SCH_1):PAGE184_I12@PURE_QUANTA.Q_RES(CHIPS)':
 'A': CDS_PINID='A';
NODE_NAME     R2976 1
 '@S9S_MB_2U_LIB.S9S_MB_2U(SCH_1):PAGE184_I13@PURE_QUANTA.Q_RES(CHIPS)':
 'A': CDS_PINID='A';
NODE_NAME     R2979 1
 '@S9S_MB_2U_LIB.S9S_MB_2U(SCH_1):PAGE184_I48@PURE_QUANTA.Q_RES(CHIPS)':
 'A': CDS_PINID='A';
NODE_NAME     R2240 1
 '@S9S_MB_2U_LIB.S9S_MB_2U(SCH_1):PAGE184_I49@PURE_QUANTA.Q_RES(CHIPS)':
 'A': CDS_PINID='A';
NODE_NAME     R2972 1
 '@S9S_MB_2U_LIB.S9S_MB_2U(SCH_1):PAGE184_I71@PURE_QUANTA.Q_RES(CHIPS)':
 'A': CDS_PINID='A';
NODE_NAME     R2974 1
 '@S9S_MB_2U_LIB.S9S_MB_2U(SCH_1):PAGE184_I72@PURE_QUANTA.Q_RES(CHIPS)':
 'A': CDS_PINID='A';
NODE_NAME     R2232 1
 '@S9S_MB_2U_LIB.S9S_MB_2U(SCH_1):PAGE184_I75@PURE_QUANTA.Q_RES(CHIPS)':
 'A': CDS_PINID='A';
NET_NAME
'P1V05_PCH_AUX_CS'
 '@S9S_MB_2U_LIB.S9S_MB_2U(SCH_1):P1V05_PCH_AUX_CS':
 C_SIGNAL='@s9s_mb_2u_lib.s9s_mb_2u(sch_1):p1v05_pch_aux_cs';
NODE_NAME     PR1327 1
 '@S9S_MB_2U_LIB.S9S_MB_2U(SCH_1):PAGE248_I6@PURE_QUANTA.Q_RES(CHIPS)':
 'A': CDS_PINID='A';
NODE_NAME     PU73 3
 '@S9S_MB_2U_LIB.S9S_MB_2U(SCH_1):PAGE248_I11@PURE_QUANTA.RS53319LR(CHIPS)':
 'CS': CDS_PINID='CS';
NET_NAME
'P1V05_PCH_AUX_FB'
 '@S9S_MB_2U_LIB.S9S_MB_2U(SCH_1):P1V05_PCH_AUX_FB':
 C_SIGNAL='@s9s_mb_2u_lib.s9s_mb_2u(sch_1):p1v05_pch_aux_fb';
NODE_NAME     PR187 1
 '@S9S_MB_2U_LIB.S9S_MB_2U(SCH_1):PAGE248_I34@PURE_QUANTA.Q_RES(CHIPS)':
 'A': CDS_PINID='A';
NODE_NAME     PC1223 1
 '@S9S_MB_2U_LIB.S9S_MB_2U(SCH_1):PAGE248_I35@PURE_QUANTA.Q_CAP(CHIPS)':
 'A': CDS_PINID='A';
NODE_NAME     PR1328 1
 '@S9S_MB_2U_LIB.S9S_MB_2U(SCH_1):PAGE248_I36@PURE_QUANTA.Q_RES(CHIPS)':
 'A': CDS_PINID='A';
NODE_NAME     PU73 7
 '@S9S_MB_2U_LIB.S9S_MB_2U(SCH_1):PAGE248_I11@PURE_QUANTA.RS53319LR(CHIPS)':
 'FB': CDS_PINID='FB';
NET_NAME
'P1V05_PCH_AUX_MODE'
 '@S9S_MB_2U_LIB.S9S_MB_2U(SCH_1):P1V05_PCH_AUX_MODE':
 C_SIGNAL='@s9s_mb_2u_lib.s9s_mb_2u(sch_1):p1v05_pch_aux_mode';
NODE_NAME     PU73 4
 '@S9S_MB_2U_LIB.S9S_MB_2U(SCH_1):PAGE248_I11@PURE_QUANTA.RS53319LR(CHIPS)':
 'MODE': CDS_PINID='MODE';
NODE_NAME     PR338 1
 '@S9S_MB_2U_LIB.S9S_MB_2U(SCH_1):PAGE248_I10@PURE_QUANTA.Q_RES(CHIPS)':
 'A': CDS_PINID='A';
NET_NAME
'P1V05_PCH_AUX_REF'
 '@S9S_MB_2U_LIB.S9S_MB_2U(SCH_1):P1V05_PCH_AUX_REF':
 C_SIGNAL='@s9s_mb_2u_lib.s9s_mb_2u(sch_1):p1v05_pch_aux_ref';
NODE_NAME     PU73 5
 '@S9S_MB_2U_LIB.S9S_MB_2U(SCH_1):PAGE248_I11@PURE_QUANTA.RS53319LR(CHIPS)':
 'REF': CDS_PINID='REF';
NODE_NAME     PC2000 1
 '@S9S_MB_2U_LIB.S9S_MB_2U(SCH_1):PAGE248_I14@PURE_QUANTA.Q_CAP(CHIPS)':
 'A': CDS_PINID='A';
NODE_NAME     PC1221 1
 '@S9S_MB_2U_LIB.S9S_MB_2U(SCH_1):PAGE248_I16@PURE_QUANTA.Q_CAP(CHIPS)':
 'A': CDS_PINID='A';
NET_NAME
'P1V05_PCH_AUX_VCC'
 '@S9S_MB_2U_LIB.S9S_MB_2U(SCH_1):P1V05_PCH_AUX_VCC':
 C_SIGNAL='@s9s_mb_2u_lib.s9s_mb_2u(sch_1):p1v05_pch_aux_vcc';
NODE_NAME     PR1326 2
 '@S9S_MB_2U_LIB.S9S_MB_2U(SCH_1):PAGE248_I3@PURE_QUANTA.Q_RES(CHIPS)':
 'B': CDS_PINID='B';
NODE_NAME     PU73 19
 '@S9S_MB_2U_LIB.S9S_MB_2U(SCH_1):PAGE248_I11@PURE_QUANTA.RS53319LR(CHIPS)':
 'VCC': CDS_PINID='VCC';
NODE_NAME     PC113 1
 '@S9S_MB_2U_LIB.S9S_MB_2U(SCH_1):PAGE248_I2@PURE_QUANTA.Q_CAP(CHIPS)':
 'A': CDS_PINID='A';
NET_NAME
'P1V05_PCH_PLL_AUX'
 '@S9S_MB_2U_LIB.S9S_MB_2U(SCH_1):P1V05_PCH_PLL_AUX':
 C_SIGNAL='@s9s_mb_2u_lib.s9s_mb_2u(sch_1):p1v05_pch_pll_aux',
 CDS_GLOBAL_NET='TRUE';
NODE_NAME     U4 AA29
 '@S9S_MB_2U_LIB.S9S_MB_2U(SCH_1):PAGE178_I11@PURE_QUANTA.EMMITSBURG_REV0P9(CHIPS)':
 'VCCP_1P05_FILTERED_AA29': CDS_PINID='VCCP_1P05_FILTERED_AA29';
NODE_NAME     U4 AB27
 '@S9S_MB_2U_LIB.S9S_MB_2U(SCH_1):PAGE178_I11@PURE_QUANTA.EMMITSBURG_REV0P9(CHIPS)':
 'VCCP_1P05_FILTERED_AB27': CDS_PINID='VCCP_1P05_FILTERED_AB27';
NODE_NAME     U4 AE29
 '@S9S_MB_2U_LIB.S9S_MB_2U(SCH_1):PAGE178_I11@PURE_QUANTA.EMMITSBURG_REV0P9(CHIPS)':
 'VCCP_1P05_FILTERED_AE29': CDS_PINID='VCCP_1P05_FILTERED_AE29';
NODE_NAME     U4 AG29
 '@S9S_MB_2U_LIB.S9S_MB_2U(SCH_1):PAGE178_I11@PURE_QUANTA.EMMITSBURG_REV0P9(CHIPS)':
 'VCCP_1P05_FILTERED_AG29': CDS_PINID='VCCP_1P05_FILTERED_AG29';
NODE_NAME     U4 AL25
 '@S9S_MB_2U_LIB.S9S_MB_2U(SCH_1):PAGE178_I11@PURE_QUANTA.EMMITSBURG_REV0P9(CHIPS)':
 'VCCP_1P05_FILTERED_AL25': CDS_PINID='VCCP_1P05_FILTERED_AL25';
NODE_NAME     U4 R23
 '@S9S_MB_2U_LIB.S9S_MB_2U(SCH_1):PAGE178_I11@PURE_QUANTA.EMMITSBURG_REV0P9(CHIPS)':
 'VCCP_1P05_FILTERED_R23': CDS_PINID='VCCP_1P05_FILTERED_R23';
NODE_NAME     U4 R26
 '@S9S_MB_2U_LIB.S9S_MB_2U(SCH_1):PAGE178_I11@PURE_QUANTA.EMMITSBURG_REV0P9(CHIPS)':
 'VCCP_1P05_FILTERED_R26': CDS_PINID='VCCP_1P05_FILTERED_R26';
NODE_NAME     U4 R29
 '@S9S_MB_2U_LIB.S9S_MB_2U(SCH_1):PAGE178_I11@PURE_QUANTA.EMMITSBURG_REV0P9(CHIPS)':
 'VCCP_1P05_FILTERED_R29': CDS_PINID='VCCP_1P05_FILTERED_R29';
NODE_NAME     U4 U27
 '@S9S_MB_2U_LIB.S9S_MB_2U(SCH_1):PAGE178_I11@PURE_QUANTA.EMMITSBURG_REV0P9(CHIPS)':
 'VCCP_1P05_FILTERED_U27': CDS_PINID='VCCP_1P05_FILTERED_U27';
NODE_NAME     C1262 1
 '@S9S_MB_2U_LIB.S9S_MB_2U(SCH_1):PAGE181_I104@PURE_QUANTA.Q_CAP(CHIPS)':
 'A': CDS_PINID='A';
NODE_NAME     C1251 1
 '@S9S_MB_2U_LIB.S9S_MB_2U(SCH_1):PAGE181_I110@PURE_QUANTA.Q_CAP(CHIPS)':
 'A': CDS_PINID='A';
NODE_NAME     C1254 1
 '@S9S_MB_2U_LIB.S9S_MB_2U(SCH_1):PAGE181_I111@PURE_QUANTA.Q_CAP(CHIPS)':
 'A': CDS_PINID='A';
NODE_NAME     R1463 2
 '@S9S_MB_2U_LIB.S9S_MB_2U(SCH_1):PAGE181_I129@PURE_QUANTA.Q_RES(CHIPS)':
 'B': CDS_PINID='B';
NODE_NAME     C1260 1
 '@S9S_MB_2U_LIB.S9S_MB_2U(SCH_1):PAGE181_I131@PURE_QUANTA.Q_CAP(CHIPS)':
 'A': CDS_PINID='A';
NODE_NAME     C1264 1
 '@S9S_MB_2U_LIB.S9S_MB_2U(SCH_1):PAGE181_I133@PURE_QUANTA.Q_CAP(CHIPS)':
 'A': CDS_PINID='A';
NODE_NAME     C1256 1
 '@S9S_MB_2U_LIB.S9S_MB_2U(SCH_1):PAGE181_I136@PURE_QUANTA.Q_CAP(CHIPS)':
 'A': CDS_PINID='A';
NODE_NAME     C1258 1
 '@S9S_MB_2U_LIB.S9S_MB_2U(SCH_1):PAGE181_I157@PURE_QUANTA.Q_CAP(CHIPS)':
 'A': CDS_PINID='A';
NODE_NAME     C1272 1
 '@S9S_MB_2U_LIB.S9S_MB_2U(SCH_1):PAGE181_I159@PURE_QUANTA.Q_CAP(CHIPS)':
 'A': CDS_PINID='A';
NODE_NAME     L2 2
 '@S9S_MB_2U_LIB.S9S_MB_2U(SCH_1):PAGE181_I164@PURE_QUANTA.Q_INDUCTOR(CHIPS)':
 '2': CDS_PINID='\2\';
NODE_NAME     R4803 2
 '@S9S_MB_2U_LIB.S9S_MB_2U(SCH_1):PAGE181_I165@PURE_QUANTA.Q_RES(CHIPS)':
 'B': CDS_PINID='B';
NET_NAME
'P1V581_PDB_ADC'
 '@S9S_MB_2U_LIB.S9S_MB_2U(SCH_1):P1V581_PDB_ADC':
 C_SIGNAL='@s9s_mb_2u_lib.s9s_mb_2u(sch_1):p1v581_pdb_adc';
NODE_NAME     R3687 1
 '@S9S_MB_2U_LIB.S9S_MB_2U(SCH_1):PAGE239_I240@PURE_QUANTA.Q_RES(CHIPS)':
 'A': CDS_PINID='A';
NODE_NAME     R3688 1
 '@S9S_MB_2U_LIB.S9S_MB_2U(SCH_1):PAGE239_I241@PURE_QUANTA.Q_RES(CHIPS)':
 'A': CDS_PINID='A';
NODE_NAME     R4568 1
 '@S9S_MB_2U_LIB.S9S_MB_2U(SCH_1):PAGE239_I346@PURE_QUANTA.Q_RES(CHIPS)':
 'A': CDS_PINID='A';
NODE_NAME     R4567 2
 '@S9S_MB_2U_LIB.S9S_MB_2U(SCH_1):PAGE239_I348@PURE_QUANTA.Q_RES(CHIPS)':
 'B': CDS_PINID='B';
NET_NAME
'P1V8_PCH_AUX'
 '@S9S_MB_2U_LIB.S9S_MB_2U(SCH_1):P1V8_PCH_AUX':
 C_SIGNAL='@s9s_mb_2u_lib.s9s_mb_2u(sch_1):p1v8_pch_aux',
 CDS_GLOBAL_NET='TRUE';
NODE_NAME     J42 12
 '@S9S_MB_2U_LIB.S9S_MB_2U(SCH_1):PAGE133_I44@PURE_QUANTA.SCONN60_ASP21410801(CHIPS)':
 '12': CDS_PINID='\12\';
NODE_NAME     C550 1
 '@S9S_MB_2U_LIB.S9S_MB_2U(SCH_1):PAGE133_I99@PURE_QUANTA.Q_CAP(CHIPS)':
 'A': CDS_PINID='A';
NODE_NAME     U4 N20
 '@S9S_MB_2U_LIB.S9S_MB_2U(SCH_1):PAGE178_I11@PURE_QUANTA.EMMITSBURG_REV0P9(CHIPS)':
 'VCCP_1P8_N20': CDS_PINID='VCCP_1P8_N20';
NODE_NAME     U4 U17
 '@S9S_MB_2U_LIB.S9S_MB_2U(SCH_1):PAGE178_I11@PURE_QUANTA.EMMITSBURG_REV0P9(CHIPS)':
 'VCCP_1P8_U17': CDS_PINID='VCCP_1P8_U17';
NODE_NAME     U4 U19
 '@S9S_MB_2U_LIB.S9S_MB_2U(SCH_1):PAGE178_I11@PURE_QUANTA.EMMITSBURG_REV0P9(CHIPS)':
 'VCCP_1P8_U19': CDS_PINID='VCCP_1P8_U19';
NODE_NAME     U4 U20
 '@S9S_MB_2U_LIB.S9S_MB_2U(SCH_1):PAGE178_I11@PURE_QUANTA.EMMITSBURG_REV0P9(CHIPS)':
 'VCCP_1P8_U20': CDS_PINID='VCCP_1P8_U20';
NODE_NAME     U4 U22
 '@S9S_MB_2U_LIB.S9S_MB_2U(SCH_1):PAGE178_I11@PURE_QUANTA.EMMITSBURG_REV0P9(CHIPS)':
 'VCCP_1P8_U22': CDS_PINID='VCCP_1P8_U22';
NODE_NAME     U4 U24
 '@S9S_MB_2U_LIB.S9S_MB_2U(SCH_1):PAGE178_I11@PURE_QUANTA.EMMITSBURG_REV0P9(CHIPS)':
 'VCCP_1P8_U24': CDS_PINID='VCCP_1P8_U24';
NODE_NAME     C1186 1
 '@S9S_MB_2U_LIB.S9S_MB_2U(SCH_1):PAGE181_I25@PURE_QUANTA.Q_CAP(CHIPS)':
 'A': CDS_PINID='A';
NODE_NAME     C1181 1
 '@S9S_MB_2U_LIB.S9S_MB_2U(SCH_1):PAGE181_I27@PURE_QUANTA.Q_CAP(CHIPS)':
 'A': CDS_PINID='A';
NODE_NAME     C1202 1
 '@S9S_MB_2U_LIB.S9S_MB_2U(SCH_1):PAGE181_I29@PURE_QUANTA.Q_CAP(CHIPS)':
 'A': CDS_PINID='A';
NODE_NAME     C1197 1
 '@S9S_MB_2U_LIB.S9S_MB_2U(SCH_1):PAGE181_I30@PURE_QUANTA.Q_CAP(CHIPS)':
 'A': CDS_PINID='A';
NODE_NAME     C1207 1
 '@S9S_MB_2U_LIB.S9S_MB_2U(SCH_1):PAGE181_I32@PURE_QUANTA.Q_CAP(CHIPS)':
 'A': CDS_PINID='A';
NODE_NAME     R1464 1
 '@S9S_MB_2U_LIB.S9S_MB_2U(SCH_1):PAGE181_I144@PURE_QUANTA.Q_RES(CHIPS)':
 'A': CDS_PINID='A';
NODE_NAME     L10 1
 '@S9S_MB_2U_LIB.S9S_MB_2U(SCH_1):PAGE181_I145@PURE_QUANTA.Q_INDUCTOR(CHIPS)':
 '1': CDS_PINID='\1\';
NODE_NAME     C1253 1
 '@S9S_MB_2U_LIB.S9S_MB_2U(SCH_1):PAGE181_I147@PURE_QUANTA.Q_CAP(CHIPS)':
 'A': CDS_PINID='A';
NODE_NAME     U98 2
 '@S9S_MB_2U_LIB.S9S_MB_2U(SCH_1):PAGE183_I27@PURE_QUANTA.PCA9306DP1(CHIPS)':
 'VREF1': CDS_PINID='VREF1';
NODE_NAME     C1323 1
 '@S9S_MB_2U_LIB.S9S_MB_2U(SCH_1):PAGE183_I28@PURE_QUANTA.Q_CAP(CHIPS)':
 'A': CDS_PINID='A';
NODE_NAME     R1702 1
 '@S9S_MB_2U_LIB.S9S_MB_2U(SCH_1):PAGE183_I43@PURE_QUANTA.Q_RES(CHIPS)':
 'A': CDS_PINID='A';
NODE_NAME     R1703 1
 '@S9S_MB_2U_LIB.S9S_MB_2U(SCH_1):PAGE183_I45@PURE_QUANTA.Q_RES(CHIPS)':
 'A': CDS_PINID='A';
NODE_NAME     R1747 1
 '@S9S_MB_2U_LIB.S9S_MB_2U(SCH_1):PAGE243_I2@PURE_QUANTA.Q_RES(CHIPS)':
 'A': CDS_PINID='A';
NODE_NAME     PU74 12
 '@S9S_MB_2U_LIB.S9S_MB_2U(SCH_1):PAGE249_I26@PURE_QUANTA.NB682GDZ(CHIPS)':
 'VOUT': CDS_PINID='VOUT';
NODE_NAME     PC1236 1
 '@S9S_MB_2U_LIB.S9S_MB_2U(SCH_1):PAGE249_I28@PURE_QUANTA.Q_CAP(CHIPS)':
 'A': CDS_PINID='A';
NODE_NAME     PC1240 1
 '@S9S_MB_2U_LIB.S9S_MB_2U(SCH_1):PAGE249_I39@PURE_QUANTA.Q_CAP(CHIPS)':
 'A': CDS_PINID='A';
NODE_NAME     PC1237 1
 '@S9S_MB_2U_LIB.S9S_MB_2U(SCH_1):PAGE249_I29@PURE_QUANTA.Q_CAP(CHIPS)':
 'A': CDS_PINID='A';
NODE_NAME     PC1238 1
 '@S9S_MB_2U_LIB.S9S_MB_2U(SCH_1):PAGE249_I37@PURE_QUANTA.Q_CAP(CHIPS)':
 'A': CDS_PINID='A';
NODE_NAME     PC1239 1
 '@S9S_MB_2U_LIB.S9S_MB_2U(SCH_1):PAGE249_I38@PURE_QUANTA.Q_CAP(CHIPS)':
 'A': CDS_PINID='A';
NODE_NAME     PC1241 1
 '@S9S_MB_2U_LIB.S9S_MB_2U(SCH_1):PAGE249_I41@PURE_QUANTA.Q_CAP(CHIPS)':
 'A': CDS_PINID='A';
NODE_NAME     PR1653 1
 '@S9S_MB_2U_LIB.S9S_MB_2U(SCH_1):PAGE249_I42@PURE_QUANTA.Q_RES(CHIPS)':
 'A': CDS_PINID='A';
NODE_NAME     PL170 2
 '@S9S_MB_2U_LIB.S9S_MB_2U(SCH_1):PAGE249_I45@PURE_QUANTA.Q_INDUCTOR(CHIPS)':
 '2': CDS_PINID='\2\';
NET_NAME
'P1V8_PCH_AUX_MODE'
 '@S9S_MB_2U_LIB.S9S_MB_2U(SCH_1):P1V8_PCH_AUX_MODE':
 C_SIGNAL='@s9s_mb_2u_lib.s9s_mb_2u(sch_1):p1v8_pch_aux_mode';
NODE_NAME     PU74 7
 '@S9S_MB_2U_LIB.S9S_MB_2U(SCH_1):PAGE249_I26@PURE_QUANTA.NB682GDZ(CHIPS)':
 'MODE': CDS_PINID='MODE';
NODE_NAME     PR1330 1
 '@S9S_MB_2U_LIB.S9S_MB_2U(SCH_1):PAGE249_I24@PURE_QUANTA.Q_RES(CHIPS)':
 'A': CDS_PINID='A';
NET_NAME
'P1V8_PCH_AUX_VCC'
 '@S9S_MB_2U_LIB.S9S_MB_2U(SCH_1):P1V8_PCH_AUX_VCC':
 C_SIGNAL='@s9s_mb_2u_lib.s9s_mb_2u(sch_1):p1v8_pch_aux_vcc';
NODE_NAME     PU74 10
 '@S9S_MB_2U_LIB.S9S_MB_2U(SCH_1):PAGE249_I26@PURE_QUANTA.NB682GDZ(CHIPS)':
 '3V3': CDS_PINID='\3v3\';
NODE_NAME     PU74 3
 '@S9S_MB_2U_LIB.S9S_MB_2U(SCH_1):PAGE249_I26@PURE_QUANTA.NB682GDZ(CHIPS)':
 'C1': CDS_PINID='C1';
NODE_NAME     PU74 6
 '@S9S_MB_2U_LIB.S9S_MB_2U(SCH_1):PAGE249_I26@PURE_QUANTA.NB682GDZ(CHIPS)':
 'LP#': CDS_PINID='\lp#\';
NODE_NAME     PC1642 1
 '@S9S_MB_2U_LIB.S9S_MB_2U(SCH_1):PAGE249_I4@PURE_QUANTA.Q_CAP(CHIPS)':
 'A': CDS_PINID='A';
NODE_NAME     PR1329 2
 '@S9S_MB_2U_LIB.S9S_MB_2U(SCH_1):PAGE249_I5@PURE_QUANTA.Q_RES(CHIPS)':
 'B': CDS_PINID='B';
NET_NAME
'P1V8_PCH_PLL_AUX'
 '@S9S_MB_2U_LIB.S9S_MB_2U(SCH_1):P1V8_PCH_PLL_AUX':
 C_SIGNAL='@s9s_mb_2u_lib.s9s_mb_2u(sch_1):p1v8_pch_pll_aux',
 CDS_GLOBAL_NET='TRUE';
NODE_NAME     U4 AB31
 '@S9S_MB_2U_LIB.S9S_MB_2U(SCH_1):PAGE178_I11@PURE_QUANTA.EMMITSBURG_REV0P9(CHIPS)':
 'VCCP_1P8_FILTERED_AB31': CDS_PINID='VCCP_1P8_FILTERED_AB31';
NODE_NAME     U4 AB34
 '@S9S_MB_2U_LIB.S9S_MB_2U(SCH_1):PAGE178_I11@PURE_QUANTA.EMMITSBURG_REV0P9(CHIPS)':
 'VCCP_1P8_FILTERED_AB34': CDS_PINID='VCCP_1P8_FILTERED_AB34';
NODE_NAME     U4 U29
 '@S9S_MB_2U_LIB.S9S_MB_2U(SCH_1):PAGE178_I11@PURE_QUANTA.EMMITSBURG_REV0P9(CHIPS)':
 'VCCP_1P8_FILTERED_U29': CDS_PINID='VCCP_1P8_FILTERED_U29';
NODE_NAME     U4 W27
 '@S9S_MB_2U_LIB.S9S_MB_2U(SCH_1):PAGE178_I11@PURE_QUANTA.EMMITSBURG_REV0P9(CHIPS)':
 'VCCP_1P8_FILTERED_W27': CDS_PINID='VCCP_1P8_FILTERED_W27';
NODE_NAME     U4 W29
 '@S9S_MB_2U_LIB.S9S_MB_2U(SCH_1):PAGE178_I11@PURE_QUANTA.EMMITSBURG_REV0P9(CHIPS)':
 'VCCP_1P8_FILTERED_W29': CDS_PINID='VCCP_1P8_FILTERED_W29';
NODE_NAME     C1263 1
 '@S9S_MB_2U_LIB.S9S_MB_2U(SCH_1):PAGE181_I119@PURE_QUANTA.Q_CAP(CHIPS)':
 'A': CDS_PINID='A';
NODE_NAME     C1255 1
 '@S9S_MB_2U_LIB.S9S_MB_2U(SCH_1):PAGE181_I123@PURE_QUANTA.Q_CAP(CHIPS)':
 'A': CDS_PINID='A';
NODE_NAME     C1252 1
 '@S9S_MB_2U_LIB.S9S_MB_2U(SCH_1):PAGE181_I125@PURE_QUANTA.Q_CAP(CHIPS)':
 'A': CDS_PINID='A';
NODE_NAME     C1266 1
 '@S9S_MB_2U_LIB.S9S_MB_2U(SCH_1):PAGE181_I127@PURE_QUANTA.Q_CAP(CHIPS)':
 'A': CDS_PINID='A';
NODE_NAME     C1265 1
 '@S9S_MB_2U_LIB.S9S_MB_2U(SCH_1):PAGE181_I140@PURE_QUANTA.Q_CAP(CHIPS)':
 'A': CDS_PINID='A';
NODE_NAME     C1261 1
 '@S9S_MB_2U_LIB.S9S_MB_2U(SCH_1):PAGE181_I142@PURE_QUANTA.Q_CAP(CHIPS)':
 'A': CDS_PINID='A';
NODE_NAME     R1464 2
 '@S9S_MB_2U_LIB.S9S_MB_2U(SCH_1):PAGE181_I144@PURE_QUANTA.Q_RES(CHIPS)':
 'B': CDS_PINID='B';
NODE_NAME     L10 2
 '@S9S_MB_2U_LIB.S9S_MB_2U(SCH_1):PAGE181_I145@PURE_QUANTA.Q_INDUCTOR(CHIPS)':
 '2': CDS_PINID='\2\';
NODE_NAME     C1257 1
 '@S9S_MB_2U_LIB.S9S_MB_2U(SCH_1):PAGE181_I146@PURE_QUANTA.Q_CAP(CHIPS)':
 'A': CDS_PINID='A';
NODE_NAME     C1273 1
 '@S9S_MB_2U_LIB.S9S_MB_2U(SCH_1):PAGE181_I151@PURE_QUANTA.Q_CAP(CHIPS)':
 'A': CDS_PINID='A';
NODE_NAME     C1259 1
 '@S9S_MB_2U_LIB.S9S_MB_2U(SCH_1):PAGE181_I158@PURE_QUANTA.Q_CAP(CHIPS)':
 'A': CDS_PINID='A';
NET_NAME
'P2E_BUF2_VDD'
 '@S9S_MB_2U_LIB.S9S_MB_2U(SCH_1):P2E_BUF2_VDD':
 C_SIGNAL='@s9s_mb_2u_lib.s9s_mb_2u(sch_1):p2e_buf2_vdd';
NODE_NAME     U328 21
 '@S9S_MB_2U_LIB.S9S_MB_2U(SCH_1):PAGE159_I95@PURE_QUANTA.DS125BR111RTWR(CHIPS)':
 'VDD_21': CDS_PINID='VDD_21';
NODE_NAME     U328 22
 '@S9S_MB_2U_LIB.S9S_MB_2U(SCH_1):PAGE159_I95@PURE_QUANTA.DS125BR111RTWR(CHIPS)':
 'VDD_22': CDS_PINID='VDD_22';
NODE_NAME     C2358 1
 '@S9S_MB_2U_LIB.S9S_MB_2U(SCH_1):PAGE159_I100@PURE_QUANTA.Q_CAP(CHIPS)':
 'A': CDS_PINID='A';
NODE_NAME     C2357 1
 '@S9S_MB_2U_LIB.S9S_MB_2U(SCH_1):PAGE159_I99@PURE_QUANTA.Q_CAP(CHIPS)':
 'A': CDS_PINID='A';
NET_NAME
'P2E_MB_BMC_RX_BUF2_C_DN<0>'
 '@S9S_MB_2U_LIB.S9S_MB_2U(SCH_1):P2E_MB_BMC_RX_BUF2_C_DN'<0>:
 C_SIGNAL='@s9s_mb_2u_lib.s9s_mb_2u(sch_1):p2e_mb_bmc_rx_buf2_c_dn(0)';
NODE_NAME     U328 19
 '@S9S_MB_2U_LIB.S9S_MB_2U(SCH_1):PAGE159_I95@PURE_QUANTA.DS125BR111RTWR(CHIPS)':
 'OUTB-': CDS_PINID='\outb-\';
NODE_NAME     C2354 1
 '@S9S_MB_2U_LIB.S9S_MB_2U(SCH_1):PAGE159_I28@PURE_QUANTA.Q_CAP(CHIPS)':
 'A': CDS_PINID='A';
NET_NAME
'P2E_MB_BMC_RX_BUF2_C_DP<0>'
 '@S9S_MB_2U_LIB.S9S_MB_2U(SCH_1):P2E_MB_BMC_RX_BUF2_C_DP'<0>:
 C_SIGNAL='@s9s_mb_2u_lib.s9s_mb_2u(sch_1):p2e_mb_bmc_rx_buf2_c_dp(0)';
NODE_NAME     C2353 1
 '@S9S_MB_2U_LIB.S9S_MB_2U(SCH_1):PAGE159_I27@PURE_QUANTA.Q_CAP(CHIPS)':
 'A': CDS_PINID='A';
NODE_NAME     U328 20
 '@S9S_MB_2U_LIB.S9S_MB_2U(SCH_1):PAGE159_I95@PURE_QUANTA.DS125BR111RTWR(CHIPS)':
 'OUTB+': CDS_PINID='\outb+\';
NET_NAME
'P2E_MB_BMC_RX_BUF_C_DN<0>'
 '@S9S_MB_2U_LIB.S9S_MB_2U(SCH_1):P2E_MB_BMC_RX_BUF_C_DN'<0>:
 C_SIGNAL='@s9s_mb_2u_lib.s9s_mb_2u(sch_1):p2e_mb_bmc_rx_buf_c_dn(0)';
NODE_NAME     U237 8
 '@S9S_MB_2U_LIB.S9S_MB_2U(SCH_1):PAGE136_I50@PURE_QUANTA.PI3EQX12902AZLEX(CHIPS)':
 'BON': CDS_PINID='BON';
NODE_NAME     C1869 1
 '@S9S_MB_2U_LIB.S9S_MB_2U(SCH_1):PAGE159_I30@PURE_QUANTA.Q_CAP(CHIPS)':
 'A': CDS_PINID='A';
NET_NAME
'P2E_MB_BMC_RX_BUF_C_DP<0>'
 '@S9S_MB_2U_LIB.S9S_MB_2U(SCH_1):P2E_MB_BMC_RX_BUF_C_DP'<0>:
 C_SIGNAL='@s9s_mb_2u_lib.s9s_mb_2u(sch_1):p2e_mb_bmc_rx_buf_c_dp(0)';
NODE_NAME     U237 9
 '@S9S_MB_2U_LIB.S9S_MB_2U(SCH_1):PAGE136_I50@PURE_QUANTA.PI3EQX12902AZLEX(CHIPS)':
 'BOP': CDS_PINID='BOP';
NODE_NAME     C1868 1
 '@S9S_MB_2U_LIB.S9S_MB_2U(SCH_1):PAGE159_I29@PURE_QUANTA.Q_CAP(CHIPS)':
 'A': CDS_PINID='A';
NET_NAME
'P2E_MB_BMC_RX_BUF_DN<0>'
 '@S9S_MB_2U_LIB.S9S_MB_2U(SCH_1):P2E_MB_BMC_RX_BUF_DN'<0>:
 C_SIGNAL='@s9s_mb_2u_lib.s9s_mb_2u(sch_1):p2e_mb_bmc_rx_buf_dn(0)';
NODE_NAME     C2354 2
 '@S9S_MB_2U_LIB.S9S_MB_2U(SCH_1):PAGE159_I28@PURE_QUANTA.Q_CAP(CHIPS)':
 'B': CDS_PINID='B';
NODE_NAME     C1869 2
 '@S9S_MB_2U_LIB.S9S_MB_2U(SCH_1):PAGE159_I30@PURE_QUANTA.Q_CAP(CHIPS)':
 'B': CDS_PINID='B';
NODE_NAME     J41 A66
 '@S9S_MB_2U_LIB.S9S_MB_2U(SCH_1):PAGE227_I173@PURE_QUANTA.SCONN168_ME1016810202011(CHIPS)':
 'PERP15': CDS_PINID='PERP15';
NET_NAME
'P2E_MB_BMC_RX_BUF_DP<0>'
 '@S9S_MB_2U_LIB.S9S_MB_2U(SCH_1):P2E_MB_BMC_RX_BUF_DP'<0>:
 C_SIGNAL='@s9s_mb_2u_lib.s9s_mb_2u(sch_1):p2e_mb_bmc_rx_buf_dp(0)';
NODE_NAME     C2353 2
 '@S9S_MB_2U_LIB.S9S_MB_2U(SCH_1):PAGE159_I27@PURE_QUANTA.Q_CAP(CHIPS)':
 'B': CDS_PINID='B';
NODE_NAME     C1868 2
 '@S9S_MB_2U_LIB.S9S_MB_2U(SCH_1):PAGE159_I29@PURE_QUANTA.Q_CAP(CHIPS)':
 'B': CDS_PINID='B';
NODE_NAME     J41 A65
 '@S9S_MB_2U_LIB.S9S_MB_2U(SCH_1):PAGE227_I173@PURE_QUANTA.SCONN168_ME1016810202011(CHIPS)':
 'PERN15': CDS_PINID='PERN15';
NET_NAME
'P2E_MB_BMC_RX_DN<0>'
 '@S9S_MB_2U_LIB.S9S_MB_2U(SCH_1):P2E_MB_BMC_RX_DN'<0>:
 C_SIGNAL='@s9s_mb_2u_lib.s9s_mb_2u(sch_1):p2e_mb_bmc_rx_dn(0)';
NODE_NAME     J112 N6
 '@S9S_MB_2U_LIB.S9S_MB_2U(SCH_1):PAGE149_I75@PURE_QUANTA.CONN160_10131762101LF(CHIPS)':
 'N6': CDS_PINID='N6';
NODE_NAME     R4666 1
 '@S9S_MB_2U_LIB.S9S_MB_2U(SCH_1):PAGE159_I35@PURE_QUANTA.Q_RES(CHIPS)':
 'A': CDS_PINID='A';
NODE_NAME     R4664 1
 '@S9S_MB_2U_LIB.S9S_MB_2U(SCH_1):PAGE159_I42@PURE_QUANTA.Q_RES(CHIPS)':
 'A': CDS_PINID='A';
NET_NAME
'P2E_MB_BMC_RX_DP<0>'
 '@S9S_MB_2U_LIB.S9S_MB_2U(SCH_1):P2E_MB_BMC_RX_DP'<0>:
 C_SIGNAL='@s9s_mb_2u_lib.s9s_mb_2u(sch_1):p2e_mb_bmc_rx_dp(0)';
NODE_NAME     J112 O6
 '@S9S_MB_2U_LIB.S9S_MB_2U(SCH_1):PAGE149_I75@PURE_QUANTA.CONN160_10131762101LF(CHIPS)':
 'O6': CDS_PINID='O6';
NODE_NAME     R4665 1
 '@S9S_MB_2U_LIB.S9S_MB_2U(SCH_1):PAGE159_I36@PURE_QUANTA.Q_RES(CHIPS)':
 'A': CDS_PINID='A';
NODE_NAME     R4663 1
 '@S9S_MB_2U_LIB.S9S_MB_2U(SCH_1):PAGE159_I41@PURE_QUANTA.Q_RES(CHIPS)':
 'A': CDS_PINID='A';
NET_NAME
'P2E_MB_BMC_RX_R1_DN<0>'
 '@S9S_MB_2U_LIB.S9S_MB_2U(SCH_1):P2E_MB_BMC_RX_R1_DN'<0>:
 C_SIGNAL='@s9s_mb_2u_lib.s9s_mb_2u(sch_1):p2e_mb_bmc_rx_r1_dn(0)';
NODE_NAME     U237 18
 '@S9S_MB_2U_LIB.S9S_MB_2U(SCH_1):PAGE136_I50@PURE_QUANTA.PI3EQX12902AZLEX(CHIPS)':
 'BIN': CDS_PINID='BIN';
NODE_NAME     R4664 2
 '@S9S_MB_2U_LIB.S9S_MB_2U(SCH_1):PAGE159_I42@PURE_QUANTA.Q_RES(CHIPS)':
 'B': CDS_PINID='B';
NET_NAME
'P2E_MB_BMC_RX_R1_DP<0>'
 '@S9S_MB_2U_LIB.S9S_MB_2U(SCH_1):P2E_MB_BMC_RX_R1_DP'<0>:
 C_SIGNAL='@s9s_mb_2u_lib.s9s_mb_2u(sch_1):p2e_mb_bmc_rx_r1_dp(0)';
NODE_NAME     U237 17
 '@S9S_MB_2U_LIB.S9S_MB_2U(SCH_1):PAGE136_I50@PURE_QUANTA.PI3EQX12902AZLEX(CHIPS)':
 'BIP': CDS_PINID='BIP';
NODE_NAME     R4663 2
 '@S9S_MB_2U_LIB.S9S_MB_2U(SCH_1):PAGE159_I41@PURE_QUANTA.Q_RES(CHIPS)':
 'B': CDS_PINID='B';
NET_NAME
'P2E_MB_BMC_RX_R2_DN<0>'
 '@S9S_MB_2U_LIB.S9S_MB_2U(SCH_1):P2E_MB_BMC_RX_R2_DN'<0>:
 C_SIGNAL='@s9s_mb_2u_lib.s9s_mb_2u(sch_1):p2e_mb_bmc_rx_r2_dn(0)';
NODE_NAME     U328 12
 '@S9S_MB_2U_LIB.S9S_MB_2U(SCH_1):PAGE159_I95@PURE_QUANTA.DS125BR111RTWR(CHIPS)':
 'INB-': CDS_PINID='\inb-\';
NODE_NAME     R4666 2
 '@S9S_MB_2U_LIB.S9S_MB_2U(SCH_1):PAGE159_I35@PURE_QUANTA.Q_RES(CHIPS)':
 'B': CDS_PINID='B';
NET_NAME
'P2E_MB_BMC_RX_R2_DP<0>'
 '@S9S_MB_2U_LIB.S9S_MB_2U(SCH_1):P2E_MB_BMC_RX_R2_DP'<0>:
 C_SIGNAL='@s9s_mb_2u_lib.s9s_mb_2u(sch_1):p2e_mb_bmc_rx_r2_dp(0)';
NODE_NAME     U328 11
 '@S9S_MB_2U_LIB.S9S_MB_2U(SCH_1):PAGE159_I95@PURE_QUANTA.DS125BR111RTWR(CHIPS)':
 'INB+': CDS_PINID='\inb+\';
NODE_NAME     R4665 2
 '@S9S_MB_2U_LIB.S9S_MB_2U(SCH_1):PAGE159_I36@PURE_QUANTA.Q_RES(CHIPS)':
 'B': CDS_PINID='B';
NET_NAME
'P2E_MB_BMC_TX_BUF2_DN<0>'
 '@S9S_MB_2U_LIB.S9S_MB_2U(SCH_1):P2E_MB_BMC_TX_BUF2_DN'<0>:
 C_SIGNAL='@s9s_mb_2u_lib.s9s_mb_2u(sch_1):p2e_mb_bmc_tx_buf2_dn(0)';
NODE_NAME     C2352 1
 '@S9S_MB_2U_LIB.S9S_MB_2U(SCH_1):PAGE159_I32@PURE_QUANTA.Q_CAP(CHIPS)':
 'A': CDS_PINID='A';
NODE_NAME     U328 8
 '@S9S_MB_2U_LIB.S9S_MB_2U(SCH_1):PAGE159_I95@PURE_QUANTA.DS125BR111RTWR(CHIPS)':
 'OUTA-': CDS_PINID='\outa-\';
NET_NAME
'P2E_MB_BMC_TX_BUF2_DP<0>'
 '@S9S_MB_2U_LIB.S9S_MB_2U(SCH_1):P2E_MB_BMC_TX_BUF2_DP'<0>:
 C_SIGNAL='@s9s_mb_2u_lib.s9s_mb_2u(sch_1):p2e_mb_bmc_tx_buf2_dp(0)';
NODE_NAME     U328 7
 '@S9S_MB_2U_LIB.S9S_MB_2U(SCH_1):PAGE159_I95@PURE_QUANTA.DS125BR111RTWR(CHIPS)':
 'OUTA+': CDS_PINID='\outa+\';
NODE_NAME     C2351 1
 '@S9S_MB_2U_LIB.S9S_MB_2U(SCH_1):PAGE159_I31@PURE_QUANTA.Q_CAP(CHIPS)':
 'A': CDS_PINID='A';
NET_NAME
'P2E_MB_BMC_TX_BUF_C_DN<0>'
 '@S9S_MB_2U_LIB.S9S_MB_2U(SCH_1):P2E_MB_BMC_TX_BUF_C_DN'<0>:
 C_SIGNAL='@s9s_mb_2u_lib.s9s_mb_2u(sch_1):p2e_mb_bmc_tx_buf_c_dn(0)';
NODE_NAME     J112 Q6
 '@S9S_MB_2U_LIB.S9S_MB_2U(SCH_1):PAGE149_I75@PURE_QUANTA.CONN160_10131762101LF(CHIPS)':
 'Q6': CDS_PINID='Q6';
NODE_NAME     C2352 2
 '@S9S_MB_2U_LIB.S9S_MB_2U(SCH_1):PAGE159_I32@PURE_QUANTA.Q_CAP(CHIPS)':
 'B': CDS_PINID='B';
NODE_NAME     C1871 2
 '@S9S_MB_2U_LIB.S9S_MB_2U(SCH_1):PAGE159_I34@PURE_QUANTA.Q_CAP(CHIPS)':
 'B': CDS_PINID='B';
NET_NAME
'P2E_MB_BMC_TX_BUF_C_DP<0>'
 '@S9S_MB_2U_LIB.S9S_MB_2U(SCH_1):P2E_MB_BMC_TX_BUF_C_DP'<0>:
 C_SIGNAL='@s9s_mb_2u_lib.s9s_mb_2u(sch_1):p2e_mb_bmc_tx_buf_c_dp(0)';
NODE_NAME     J112 R6
 '@S9S_MB_2U_LIB.S9S_MB_2U(SCH_1):PAGE149_I75@PURE_QUANTA.CONN160_10131762101LF(CHIPS)':
 'R6': CDS_PINID='R6';
NODE_NAME     C2351 2
 '@S9S_MB_2U_LIB.S9S_MB_2U(SCH_1):PAGE159_I31@PURE_QUANTA.Q_CAP(CHIPS)':
 'B': CDS_PINID='B';
NODE_NAME     C1870 2
 '@S9S_MB_2U_LIB.S9S_MB_2U(SCH_1):PAGE159_I33@PURE_QUANTA.Q_CAP(CHIPS)':
 'B': CDS_PINID='B';
NET_NAME
'P2E_MB_BMC_TX_BUF_DN<0>'
 '@S9S_MB_2U_LIB.S9S_MB_2U(SCH_1):P2E_MB_BMC_TX_BUF_DN'<0>:
 C_SIGNAL='@s9s_mb_2u_lib.s9s_mb_2u(sch_1):p2e_mb_bmc_tx_buf_dn(0)';
NODE_NAME     U237 23
 '@S9S_MB_2U_LIB.S9S_MB_2U(SCH_1):PAGE136_I50@PURE_QUANTA.PI3EQX12902AZLEX(CHIPS)':
 'AON': CDS_PINID='AON';
NODE_NAME     C1871 1
 '@S9S_MB_2U_LIB.S9S_MB_2U(SCH_1):PAGE159_I34@PURE_QUANTA.Q_CAP(CHIPS)':
 'A': CDS_PINID='A';
NET_NAME
'P2E_MB_BMC_TX_BUF_DP<0>'
 '@S9S_MB_2U_LIB.S9S_MB_2U(SCH_1):P2E_MB_BMC_TX_BUF_DP'<0>:
 C_SIGNAL='@s9s_mb_2u_lib.s9s_mb_2u(sch_1):p2e_mb_bmc_tx_buf_dp(0)';
NODE_NAME     U237 24
 '@S9S_MB_2U_LIB.S9S_MB_2U(SCH_1):PAGE136_I50@PURE_QUANTA.PI3EQX12902AZLEX(CHIPS)':
 'AOP': CDS_PINID='AOP';
NODE_NAME     C1870 1
 '@S9S_MB_2U_LIB.S9S_MB_2U(SCH_1):PAGE159_I33@PURE_QUANTA.Q_CAP(CHIPS)':
 'A': CDS_PINID='A';
NET_NAME
'P2E_MB_BMC_TX_C_DN<0>'
 '@S9S_MB_2U_LIB.S9S_MB_2U(SCH_1):P2E_MB_BMC_TX_C_DN'<0>:
 C_SIGNAL='@s9s_mb_2u_lib.s9s_mb_2u(sch_1):p2e_mb_bmc_tx_c_dn(0)';
NODE_NAME     R4662 1
 '@S9S_MB_2U_LIB.S9S_MB_2U(SCH_1):PAGE159_I43@PURE_QUANTA.Q_RES(CHIPS)':
 'A': CDS_PINID='A';
NODE_NAME     R4660 1
 '@S9S_MB_2U_LIB.S9S_MB_2U(SCH_1):PAGE159_I45@PURE_QUANTA.Q_RES(CHIPS)':
 'A': CDS_PINID='A';
NODE_NAME     J41 B66
 '@S9S_MB_2U_LIB.S9S_MB_2U(SCH_1):PAGE227_I173@PURE_QUANTA.SCONN168_ME1016810202011(CHIPS)':
 'PETP15': CDS_PINID='PETP15';
NET_NAME
'P2E_MB_BMC_TX_C_DP<0>'
 '@S9S_MB_2U_LIB.S9S_MB_2U(SCH_1):P2E_MB_BMC_TX_C_DP'<0>:
 C_SIGNAL='@s9s_mb_2u_lib.s9s_mb_2u(sch_1):p2e_mb_bmc_tx_c_dp(0)';
NODE_NAME     R4661 1
 '@S9S_MB_2U_LIB.S9S_MB_2U(SCH_1):PAGE159_I44@PURE_QUANTA.Q_RES(CHIPS)':
 'A': CDS_PINID='A';
NODE_NAME     R4659 1
 '@S9S_MB_2U_LIB.S9S_MB_2U(SCH_1):PAGE159_I46@PURE_QUANTA.Q_RES(CHIPS)':
 'A': CDS_PINID='A';
NODE_NAME     J41 B65
 '@S9S_MB_2U_LIB.S9S_MB_2U(SCH_1):PAGE227_I173@PURE_QUANTA.SCONN168_ME1016810202011(CHIPS)':
 'PETN15': CDS_PINID='PETN15';
NET_NAME
'P2E_MB_BMC_TX_C_R1_DN<0>'
 '@S9S_MB_2U_LIB.S9S_MB_2U(SCH_1):P2E_MB_BMC_TX_C_R1_DN'<0>:
 C_SIGNAL='@s9s_mb_2u_lib.s9s_mb_2u(sch_1):p2e_mb_bmc_tx_c_r1_dn(0)';
NODE_NAME     U237 3
 '@S9S_MB_2U_LIB.S9S_MB_2U(SCH_1):PAGE136_I50@PURE_QUANTA.PI3EQX12902AZLEX(CHIPS)':
 'AIN': CDS_PINID='AIN';
NODE_NAME     R4660 2
 '@S9S_MB_2U_LIB.S9S_MB_2U(SCH_1):PAGE159_I45@PURE_QUANTA.Q_RES(CHIPS)':
 'B': CDS_PINID='B';
NET_NAME
'P2E_MB_BMC_TX_C_R1_DP<0>'
 '@S9S_MB_2U_LIB.S9S_MB_2U(SCH_1):P2E_MB_BMC_TX_C_R1_DP'<0>:
 C_SIGNAL='@s9s_mb_2u_lib.s9s_mb_2u(sch_1):p2e_mb_bmc_tx_c_r1_dp(0)';
NODE_NAME     U237 2
 '@S9S_MB_2U_LIB.S9S_MB_2U(SCH_1):PAGE136_I50@PURE_QUANTA.PI3EQX12902AZLEX(CHIPS)':
 'AIP': CDS_PINID='AIP';
NODE_NAME     R4659 2
 '@S9S_MB_2U_LIB.S9S_MB_2U(SCH_1):PAGE159_I46@PURE_QUANTA.Q_RES(CHIPS)':
 'B': CDS_PINID='B';
NET_NAME
'P2E_MB_BMC_TX_C_R2_DN<0>'
 '@S9S_MB_2U_LIB.S9S_MB_2U(SCH_1):P2E_MB_BMC_TX_C_R2_DN'<0>:
 C_SIGNAL='@s9s_mb_2u_lib.s9s_mb_2u(sch_1):p2e_mb_bmc_tx_c_r2_dn(0)';
NODE_NAME     U328 23
 '@S9S_MB_2U_LIB.S9S_MB_2U(SCH_1):PAGE159_I95@PURE_QUANTA.DS125BR111RTWR(CHIPS)':
 'INA-': CDS_PINID='\ina-\';
NODE_NAME     R4662 2
 '@S9S_MB_2U_LIB.S9S_MB_2U(SCH_1):PAGE159_I43@PURE_QUANTA.Q_RES(CHIPS)':
 'B': CDS_PINID='B';
NET_NAME
'P2E_MB_BMC_TX_C_R2_DP<0>'
 '@S9S_MB_2U_LIB.S9S_MB_2U(SCH_1):P2E_MB_BMC_TX_C_R2_DP'<0>:
 C_SIGNAL='@s9s_mb_2u_lib.s9s_mb_2u(sch_1):p2e_mb_bmc_tx_c_r2_dp(0)';
NODE_NAME     U328 24
 '@S9S_MB_2U_LIB.S9S_MB_2U(SCH_1):PAGE159_I95@PURE_QUANTA.DS125BR111RTWR(CHIPS)':
 'INA+': CDS_PINID='\ina+\';
NODE_NAME     R4661 2
 '@S9S_MB_2U_LIB.S9S_MB_2U(SCH_1):PAGE159_I44@PURE_QUANTA.Q_RES(CHIPS)':
 'B': CDS_PINID='B';
NET_NAME
'P3E_PCH_BMC_RX_DN'
 '@S9S_MB_2U_LIB.S9S_MB_2U(SCH_1):P3E_PCH_BMC_RX_DN':
 C_SIGNAL='@s9s_mb_2u_lib.s9s_mb_2u(sch_1):p3e_pch_bmc_rx_dn';
NODE_NAME     U4 U41
 '@S9S_MB_2U_LIB.S9S_MB_2U(SCH_1):PAGE173_I110@PURE_QUANTA.EMMITSBURG_REV0P9(CHIPS)':
 'SATA_8_PCIE3_8_USB3_8_RXN': CDS_PINID='SATA_8_PCIE3_8_USB3_8_RXN';
NODE_NAME     J41 A21
 '@S9S_MB_2U_LIB.S9S_MB_2U(SCH_1):PAGE227_I173@PURE_QUANTA.SCONN168_ME1016810202011(CHIPS)':
 'PERP1': CDS_PINID='PERP1';
NET_NAME
'P3E_PCH_BMC_RX_DP'
 '@S9S_MB_2U_LIB.S9S_MB_2U(SCH_1):P3E_PCH_BMC_RX_DP':
 C_SIGNAL='@s9s_mb_2u_lib.s9s_mb_2u(sch_1):p3e_pch_bmc_rx_dp';
NODE_NAME     U4 U43
 '@S9S_MB_2U_LIB.S9S_MB_2U(SCH_1):PAGE173_I110@PURE_QUANTA.EMMITSBURG_REV0P9(CHIPS)':
 'SATA_8_PCIE3_8_USB3_8_RXP': CDS_PINID='SATA_8_PCIE3_8_USB3_8_RXP';
NODE_NAME     J41 A20
 '@S9S_MB_2U_LIB.S9S_MB_2U(SCH_1):PAGE227_I173@PURE_QUANTA.SCONN168_ME1016810202011(CHIPS)':
 'PERN1': CDS_PINID='PERN1';
NET_NAME
'P3E_PCH_BMC_TX_C_DN'
 '@S9S_MB_2U_LIB.S9S_MB_2U(SCH_1):P3E_PCH_BMC_TX_C_DN':
 C_SIGNAL='@s9s_mb_2u_lib.s9s_mb_2u(sch_1):p3e_pch_bmc_tx_c_dn';
NODE_NAME     C2078 2
 '@S9S_MB_2U_LIB.S9S_MB_2U(SCH_1):PAGE173_I76@PURE_QUANTA.Q_CAP_DIFFBUS(CHIPS)':
 '2': CDS_PINID='\2\';
NODE_NAME     J41 A18
 '@S9S_MB_2U_LIB.S9S_MB_2U(SCH_1):PAGE227_I173@PURE_QUANTA.SCONN168_ME1016810202011(CHIPS)':
 'PERP0': CDS_PINID='PERP0';
NET_NAME
'P3E_PCH_BMC_TX_C_DP'
 '@S9S_MB_2U_LIB.S9S_MB_2U(SCH_1):P3E_PCH_BMC_TX_C_DP':
 C_SIGNAL='@s9s_mb_2u_lib.s9s_mb_2u(sch_1):p3e_pch_bmc_tx_c_dp';
NODE_NAME     C2077 2
 '@S9S_MB_2U_LIB.S9S_MB_2U(SCH_1):PAGE173_I77@PURE_QUANTA.Q_CAP_DIFFBUS(CHIPS)':
 '2': CDS_PINID='\2\';
NODE_NAME     J41 A17
 '@S9S_MB_2U_LIB.S9S_MB_2U(SCH_1):PAGE227_I173@PURE_QUANTA.SCONN168_ME1016810202011(CHIPS)':
 'PERN0': CDS_PINID='PERN0';
NET_NAME
'P3E_PCH_BMC_TX_DN'
 '@S9S_MB_2U_LIB.S9S_MB_2U(SCH_1):P3E_PCH_BMC_TX_DN':
 C_SIGNAL='@s9s_mb_2u_lib.s9s_mb_2u(sch_1):p3e_pch_bmc_tx_dn';
NODE_NAME     C2078 1
 '@S9S_MB_2U_LIB.S9S_MB_2U(SCH_1):PAGE173_I76@PURE_QUANTA.Q_CAP_DIFFBUS(CHIPS)':
 '1': CDS_PINID='\1\';
NODE_NAME     U4 AE36
 '@S9S_MB_2U_LIB.S9S_MB_2U(SCH_1):PAGE173_I110@PURE_QUANTA.EMMITSBURG_REV0P9(CHIPS)':
 'SATA_8_PCIE3_8_USB3_8_TXN': CDS_PINID='SATA_8_PCIE3_8_USB3_8_TXN';
NET_NAME
'P3E_PCH_BMC_TX_DP'
 '@S9S_MB_2U_LIB.S9S_MB_2U(SCH_1):P3E_PCH_BMC_TX_DP':
 C_SIGNAL='@s9s_mb_2u_lib.s9s_mb_2u(sch_1):p3e_pch_bmc_tx_dp';
NODE_NAME     C2077 1
 '@S9S_MB_2U_LIB.S9S_MB_2U(SCH_1):PAGE173_I77@PURE_QUANTA.Q_CAP_DIFFBUS(CHIPS)':
 '1': CDS_PINID='\1\';
NODE_NAME     U4 AD37
 '@S9S_MB_2U_LIB.S9S_MB_2U(SCH_1):PAGE173_I110@PURE_QUANTA.EMMITSBURG_REV0P9(CHIPS)':
 'SATA_8_PCIE3_8_USB3_8_TXP': CDS_PINID='SATA_8_PCIE3_8_USB3_8_TXP';
NET_NAME
'P3E_PCH_E1S_RX_DN<0>'
 '@S9S_MB_2U_LIB.S9S_MB_2U(SCH_1):P3E_PCH_E1S_RX_DN'<0>:
 C_SIGNAL='@s9s_mb_2u_lib.s9s_mb_2u(sch_1):p3e_pch_e1s_rx_dn(0)';
NODE_NAME     J90 A18
 '@S9S_MB_2U_LIB.S9S_MB_2U(SCH_1):PAGE297_I318@PURE_QUANTA.SCONN56_123276793(CHIPS)':
 'PER_P0': CDS_PINID='PER_P0';
NODE_NAME     U4 AA41
 '@S9S_MB_2U_LIB.S9S_MB_2U(SCH_1):PAGE173_I110@PURE_QUANTA.EMMITSBURG_REV0P9(CHIPS)':
 'SATA_4_PCIE3_4_USB3_4_RXN': CDS_PINID='SATA_4_PCIE3_4_USB3_4_RXN';
NET_NAME
'P3E_PCH_E1S_RX_DN<1>'
 '@S9S_MB_2U_LIB.S9S_MB_2U(SCH_1):P3E_PCH_E1S_RX_DN'<1>:
 C_SIGNAL='@s9s_mb_2u_lib.s9s_mb_2u(sch_1):p3e_pch_e1s_rx_dn(1)';
NODE_NAME     J90 A20
 '@S9S_MB_2U_LIB.S9S_MB_2U(SCH_1):PAGE297_I318@PURE_QUANTA.SCONN56_123276793(CHIPS)':
 'PER_N1': CDS_PINID='PER_N1';
NODE_NAME     U4 Y40
 '@S9S_MB_2U_LIB.S9S_MB_2U(SCH_1):PAGE173_I110@PURE_QUANTA.EMMITSBURG_REV0P9(CHIPS)':
 'SATA_5_PCIE3_5_USB3_5_RXN': CDS_PINID='SATA_5_PCIE3_5_USB3_5_RXN';
NET_NAME
'P3E_PCH_E1S_RX_DN<2>'
 '@S9S_MB_2U_LIB.S9S_MB_2U(SCH_1):P3E_PCH_E1S_RX_DN'<2>:
 C_SIGNAL='@s9s_mb_2u_lib.s9s_mb_2u(sch_1):p3e_pch_e1s_rx_dn(2)';
NODE_NAME     J90 A23
 '@S9S_MB_2U_LIB.S9S_MB_2U(SCH_1):PAGE297_I318@PURE_QUANTA.SCONN56_123276793(CHIPS)':
 'PER_N2': CDS_PINID='PER_N2';
NODE_NAME     U4 W41
 '@S9S_MB_2U_LIB.S9S_MB_2U(SCH_1):PAGE173_I110@PURE_QUANTA.EMMITSBURG_REV0P9(CHIPS)':
 'SATA_6_PCIE3_6_USB3_6_RXN': CDS_PINID='SATA_6_PCIE3_6_USB3_6_RXN';
NET_NAME
'P3E_PCH_E1S_RX_DN<3>'
 '@S9S_MB_2U_LIB.S9S_MB_2U(SCH_1):P3E_PCH_E1S_RX_DN'<3>:
 C_SIGNAL='@s9s_mb_2u_lib.s9s_mb_2u(sch_1):p3e_pch_e1s_rx_dn(3)';
NODE_NAME     J90 A26
 '@S9S_MB_2U_LIB.S9S_MB_2U(SCH_1):PAGE297_I318@PURE_QUANTA.SCONN56_123276793(CHIPS)':
 'PER_N3': CDS_PINID='PER_N3';
NODE_NAME     U4 V40
 '@S9S_MB_2U_LIB.S9S_MB_2U(SCH_1):PAGE173_I110@PURE_QUANTA.EMMITSBURG_REV0P9(CHIPS)':
 'SATA_7_PCIE3_7_USB3_7_RXN': CDS_PINID='SATA_7_PCIE3_7_USB3_7_RXN';
NET_NAME
'P3E_PCH_E1S_RX_DP<0>'
 '@S9S_MB_2U_LIB.S9S_MB_2U(SCH_1):P3E_PCH_E1S_RX_DP'<0>:
 C_SIGNAL='@s9s_mb_2u_lib.s9s_mb_2u(sch_1):p3e_pch_e1s_rx_dp(0)';
NODE_NAME     J90 A17
 '@S9S_MB_2U_LIB.S9S_MB_2U(SCH_1):PAGE297_I318@PURE_QUANTA.SCONN56_123276793(CHIPS)':
 'PER_N0': CDS_PINID='PER_N0';
NODE_NAME     U4 AA43
 '@S9S_MB_2U_LIB.S9S_MB_2U(SCH_1):PAGE173_I110@PURE_QUANTA.EMMITSBURG_REV0P9(CHIPS)':
 'SATA_4_PCIE3_4_USB3_4_RXP': CDS_PINID='SATA_4_PCIE3_4_USB3_4_RXP';
NET_NAME
'P3E_PCH_E1S_RX_DP<1>'
 '@S9S_MB_2U_LIB.S9S_MB_2U(SCH_1):P3E_PCH_E1S_RX_DP'<1>:
 C_SIGNAL='@s9s_mb_2u_lib.s9s_mb_2u(sch_1):p3e_pch_e1s_rx_dp(1)';
NODE_NAME     J90 A21
 '@S9S_MB_2U_LIB.S9S_MB_2U(SCH_1):PAGE297_I318@PURE_QUANTA.SCONN56_123276793(CHIPS)':
 'PER_P1': CDS_PINID='PER_P1';
NODE_NAME     U4 Y42
 '@S9S_MB_2U_LIB.S9S_MB_2U(SCH_1):PAGE173_I110@PURE_QUANTA.EMMITSBURG_REV0P9(CHIPS)':
 'SATA_5_PCIE3_5_USB3_5_RXP': CDS_PINID='SATA_5_PCIE3_5_USB3_5_RXP';
NET_NAME
'P3E_PCH_E1S_RX_DP<2>'
 '@S9S_MB_2U_LIB.S9S_MB_2U(SCH_1):P3E_PCH_E1S_RX_DP'<2>:
 C_SIGNAL='@s9s_mb_2u_lib.s9s_mb_2u(sch_1):p3e_pch_e1s_rx_dp(2)';
NODE_NAME     J90 A24
 '@S9S_MB_2U_LIB.S9S_MB_2U(SCH_1):PAGE297_I318@PURE_QUANTA.SCONN56_123276793(CHIPS)':
 'PER_P2': CDS_PINID='PER_P2';
NODE_NAME     U4 W43
 '@S9S_MB_2U_LIB.S9S_MB_2U(SCH_1):PAGE173_I110@PURE_QUANTA.EMMITSBURG_REV0P9(CHIPS)':
 'SATA_6_PCIE3_6_USB3_6_RXP': CDS_PINID='SATA_6_PCIE3_6_USB3_6_RXP';
NET_NAME
'P3E_PCH_E1S_RX_DP<3>'
 '@S9S_MB_2U_LIB.S9S_MB_2U(SCH_1):P3E_PCH_E1S_RX_DP'<3>:
 C_SIGNAL='@s9s_mb_2u_lib.s9s_mb_2u(sch_1):p3e_pch_e1s_rx_dp(3)';
NODE_NAME     J90 A27
 '@S9S_MB_2U_LIB.S9S_MB_2U(SCH_1):PAGE297_I318@PURE_QUANTA.SCONN56_123276793(CHIPS)':
 'PER_P3': CDS_PINID='PER_P3';
NODE_NAME     U4 V42
 '@S9S_MB_2U_LIB.S9S_MB_2U(SCH_1):PAGE173_I110@PURE_QUANTA.EMMITSBURG_REV0P9(CHIPS)':
 'SATA_7_PCIE3_7_USB3_7_RXP': CDS_PINID='SATA_7_PCIE3_7_USB3_7_RXP';
NET_NAME
'P3E_PCH_E1S_TX_C_DN<0>'
 '@S9S_MB_2U_LIB.S9S_MB_2U(SCH_1):P3E_PCH_E1S_TX_C_DN'<0>:
 C_SIGNAL='@s9s_mb_2u_lib.s9s_mb_2u(sch_1):p3e_pch_e1s_tx_c_dn(0)';
NODE_NAME     J90 B18
 '@S9S_MB_2U_LIB.S9S_MB_2U(SCH_1):PAGE297_I318@PURE_QUANTA.SCONN56_123276793(CHIPS)':
 'PET_P0': CDS_PINID='PET_P0';
NODE_NAME     C1996 2
 '@S9S_MB_2U_LIB.S9S_MB_2U(SCH_1):PAGE173_I68@PURE_QUANTA.Q_CAP_DIFFBUS(CHIPS)':
 '2': CDS_PINID='\2\';
NET_NAME
'P3E_PCH_E1S_TX_C_DN<1>'
 '@S9S_MB_2U_LIB.S9S_MB_2U(SCH_1):P3E_PCH_E1S_TX_C_DN'<1>:
 C_SIGNAL='@s9s_mb_2u_lib.s9s_mb_2u(sch_1):p3e_pch_e1s_tx_c_dn(1)';
NODE_NAME     J90 B21
 '@S9S_MB_2U_LIB.S9S_MB_2U(SCH_1):PAGE297_I318@PURE_QUANTA.SCONN56_123276793(CHIPS)':
 'PET_P1': CDS_PINID='PET_P1';
NODE_NAME     C1994 2
 '@S9S_MB_2U_LIB.S9S_MB_2U(SCH_1):PAGE173_I70@PURE_QUANTA.Q_CAP_DIFFBUS(CHIPS)':
 '2': CDS_PINID='\2\';
NET_NAME
'P3E_PCH_E1S_TX_C_DN<2>'
 '@S9S_MB_2U_LIB.S9S_MB_2U(SCH_1):P3E_PCH_E1S_TX_C_DN'<2>:
 C_SIGNAL='@s9s_mb_2u_lib.s9s_mb_2u(sch_1):p3e_pch_e1s_tx_c_dn(2)';
NODE_NAME     J90 B23
 '@S9S_MB_2U_LIB.S9S_MB_2U(SCH_1):PAGE297_I318@PURE_QUANTA.SCONN56_123276793(CHIPS)':
 'PET_N2': CDS_PINID='PET_N2';
NODE_NAME     C1992 2
 '@S9S_MB_2U_LIB.S9S_MB_2U(SCH_1):PAGE173_I72@PURE_QUANTA.Q_CAP_DIFFBUS(CHIPS)':
 '2': CDS_PINID='\2\';
NET_NAME
'P3E_PCH_E1S_TX_C_DN<3>'
 '@S9S_MB_2U_LIB.S9S_MB_2U(SCH_1):P3E_PCH_E1S_TX_C_DN'<3>:
 C_SIGNAL='@s9s_mb_2u_lib.s9s_mb_2u(sch_1):p3e_pch_e1s_tx_c_dn(3)';
NODE_NAME     J90 B26
 '@S9S_MB_2U_LIB.S9S_MB_2U(SCH_1):PAGE297_I318@PURE_QUANTA.SCONN56_123276793(CHIPS)':
 'PET_N3': CDS_PINID='PET_N3';
NODE_NAME     C1990 2
 '@S9S_MB_2U_LIB.S9S_MB_2U(SCH_1):PAGE173_I74@PURE_QUANTA.Q_CAP_DIFFBUS(CHIPS)':
 '2': CDS_PINID='\2\';
NET_NAME
'P3E_PCH_E1S_TX_C_DP<0>'
 '@S9S_MB_2U_LIB.S9S_MB_2U(SCH_1):P3E_PCH_E1S_TX_C_DP'<0>:
 C_SIGNAL='@s9s_mb_2u_lib.s9s_mb_2u(sch_1):p3e_pch_e1s_tx_c_dp(0)';
NODE_NAME     J90 B17
 '@S9S_MB_2U_LIB.S9S_MB_2U(SCH_1):PAGE297_I318@PURE_QUANTA.SCONN56_123276793(CHIPS)':
 'PET_N0': CDS_PINID='PET_N0';
NODE_NAME     C1995 2
 '@S9S_MB_2U_LIB.S9S_MB_2U(SCH_1):PAGE173_I69@PURE_QUANTA.Q_CAP_DIFFBUS(CHIPS)':
 '2': CDS_PINID='\2\';
NET_NAME
'P3E_PCH_E1S_TX_C_DP<1>'
 '@S9S_MB_2U_LIB.S9S_MB_2U(SCH_1):P3E_PCH_E1S_TX_C_DP'<1>:
 C_SIGNAL='@s9s_mb_2u_lib.s9s_mb_2u(sch_1):p3e_pch_e1s_tx_c_dp(1)';
NODE_NAME     J90 B20
 '@S9S_MB_2U_LIB.S9S_MB_2U(SCH_1):PAGE297_I318@PURE_QUANTA.SCONN56_123276793(CHIPS)':
 'PET_N1': CDS_PINID='PET_N1';
NODE_NAME     C1993 2
 '@S9S_MB_2U_LIB.S9S_MB_2U(SCH_1):PAGE173_I71@PURE_QUANTA.Q_CAP_DIFFBUS(CHIPS)':
 '2': CDS_PINID='\2\';
NET_NAME
'P3E_PCH_E1S_TX_C_DP<2>'
 '@S9S_MB_2U_LIB.S9S_MB_2U(SCH_1):P3E_PCH_E1S_TX_C_DP'<2>:
 C_SIGNAL='@s9s_mb_2u_lib.s9s_mb_2u(sch_1):p3e_pch_e1s_tx_c_dp(2)';
NODE_NAME     J90 B24
 '@S9S_MB_2U_LIB.S9S_MB_2U(SCH_1):PAGE297_I318@PURE_QUANTA.SCONN56_123276793(CHIPS)':
 'PET_P2': CDS_PINID='PET_P2';
NODE_NAME     C1991 2
 '@S9S_MB_2U_LIB.S9S_MB_2U(SCH_1):PAGE173_I73@PURE_QUANTA.Q_CAP_DIFFBUS(CHIPS)':
 '2': CDS_PINID='\2\';
NET_NAME
'P3E_PCH_E1S_TX_C_DP<3>'
 '@S9S_MB_2U_LIB.S9S_MB_2U(SCH_1):P3E_PCH_E1S_TX_C_DP'<3>:
 C_SIGNAL='@s9s_mb_2u_lib.s9s_mb_2u(sch_1):p3e_pch_e1s_tx_c_dp(3)';
NODE_NAME     J90 B27
 '@S9S_MB_2U_LIB.S9S_MB_2U(SCH_1):PAGE297_I318@PURE_QUANTA.SCONN56_123276793(CHIPS)':
 'PET_P3': CDS_PINID='PET_P3';
NODE_NAME     C1989 2
 '@S9S_MB_2U_LIB.S9S_MB_2U(SCH_1):PAGE173_I75@PURE_QUANTA.Q_CAP_DIFFBUS(CHIPS)':
 '2': CDS_PINID='\2\';
NET_NAME
'P3E_PCH_E1S_TX_DN<0>'
 '@S9S_MB_2U_LIB.S9S_MB_2U(SCH_1):P3E_PCH_E1S_TX_DN'<0>:
 C_SIGNAL='@s9s_mb_2u_lib.s9s_mb_2u(sch_1):p3e_pch_e1s_tx_dn(0)';
NODE_NAME     C1996 1
 '@S9S_MB_2U_LIB.S9S_MB_2U(SCH_1):PAGE173_I68@PURE_QUANTA.Q_CAP_DIFFBUS(CHIPS)':
 '1': CDS_PINID='\1\';
NODE_NAME     U4 AL36
 '@S9S_MB_2U_LIB.S9S_MB_2U(SCH_1):PAGE173_I110@PURE_QUANTA.EMMITSBURG_REV0P9(CHIPS)':
 'SATA_4_PCIE3_4_USB3_4_TXN': CDS_PINID='SATA_4_PCIE3_4_USB3_4_TXN';
NET_NAME
'P3E_PCH_E1S_TX_DN<1>'
 '@S9S_MB_2U_LIB.S9S_MB_2U(SCH_1):P3E_PCH_E1S_TX_DN'<1>:
 C_SIGNAL='@s9s_mb_2u_lib.s9s_mb_2u(sch_1):p3e_pch_e1s_tx_dn(1)';
NODE_NAME     C1994 1
 '@S9S_MB_2U_LIB.S9S_MB_2U(SCH_1):PAGE173_I70@PURE_QUANTA.Q_CAP_DIFFBUS(CHIPS)':
 '1': CDS_PINID='\1\';
NODE_NAME     U4 AH34
 '@S9S_MB_2U_LIB.S9S_MB_2U(SCH_1):PAGE173_I110@PURE_QUANTA.EMMITSBURG_REV0P9(CHIPS)':
 'SATA_5_PCIE3_5_USB3_5_TXN': CDS_PINID='SATA_5_PCIE3_5_USB3_5_TXN';
NET_NAME
'P3E_PCH_E1S_TX_DN<2>'
 '@S9S_MB_2U_LIB.S9S_MB_2U(SCH_1):P3E_PCH_E1S_TX_DN'<2>:
 C_SIGNAL='@s9s_mb_2u_lib.s9s_mb_2u(sch_1):p3e_pch_e1s_tx_dn(2)';
NODE_NAME     C1992 1
 '@S9S_MB_2U_LIB.S9S_MB_2U(SCH_1):PAGE173_I72@PURE_QUANTA.Q_CAP_DIFFBUS(CHIPS)':
 '1': CDS_PINID='\1\';
NODE_NAME     U4 AF37
 '@S9S_MB_2U_LIB.S9S_MB_2U(SCH_1):PAGE173_I110@PURE_QUANTA.EMMITSBURG_REV0P9(CHIPS)':
 'SATA_6_PCIE3_6_USB3_6_TXN': CDS_PINID='SATA_6_PCIE3_6_USB3_6_TXN';
NET_NAME
'P3E_PCH_E1S_TX_DN<3>'
 '@S9S_MB_2U_LIB.S9S_MB_2U(SCH_1):P3E_PCH_E1S_TX_DN'<3>:
 C_SIGNAL='@s9s_mb_2u_lib.s9s_mb_2u(sch_1):p3e_pch_e1s_tx_dn(3)';
NODE_NAME     C1990 1
 '@S9S_MB_2U_LIB.S9S_MB_2U(SCH_1):PAGE173_I74@PURE_QUANTA.Q_CAP_DIFFBUS(CHIPS)':
 '1': CDS_PINID='\1\';
NODE_NAME     U4 AF34
 '@S9S_MB_2U_LIB.S9S_MB_2U(SCH_1):PAGE173_I110@PURE_QUANTA.EMMITSBURG_REV0P9(CHIPS)':
 'SATA_7_PCIE3_7_USB3_7_TXN': CDS_PINID='SATA_7_PCIE3_7_USB3_7_TXN';
NET_NAME
'P3E_PCH_E1S_TX_DP<0>'
 '@S9S_MB_2U_LIB.S9S_MB_2U(SCH_1):P3E_PCH_E1S_TX_DP'<0>:
 C_SIGNAL='@s9s_mb_2u_lib.s9s_mb_2u(sch_1):p3e_pch_e1s_tx_dp(0)';
NODE_NAME     C1995 1
 '@S9S_MB_2U_LIB.S9S_MB_2U(SCH_1):PAGE173_I69@PURE_QUANTA.Q_CAP_DIFFBUS(CHIPS)':
 '1': CDS_PINID='\1\';
NODE_NAME     U4 AM37
 '@S9S_MB_2U_LIB.S9S_MB_2U(SCH_1):PAGE173_I110@PURE_QUANTA.EMMITSBURG_REV0P9(CHIPS)':
 'SATA_4_PCIE3_4_USB3_4_TXP': CDS_PINID='SATA_4_PCIE3_4_USB3_4_TXP';
NET_NAME
'P3E_PCH_E1S_TX_DP<1>'
 '@S9S_MB_2U_LIB.S9S_MB_2U(SCH_1):P3E_PCH_E1S_TX_DP'<1>:
 C_SIGNAL='@s9s_mb_2u_lib.s9s_mb_2u(sch_1):p3e_pch_e1s_tx_dp(1)';
NODE_NAME     C1993 1
 '@S9S_MB_2U_LIB.S9S_MB_2U(SCH_1):PAGE173_I71@PURE_QUANTA.Q_CAP_DIFFBUS(CHIPS)':
 '1': CDS_PINID='\1\';
NODE_NAME     U4 AJ32
 '@S9S_MB_2U_LIB.S9S_MB_2U(SCH_1):PAGE173_I110@PURE_QUANTA.EMMITSBURG_REV0P9(CHIPS)':
 'SATA_5_PCIE3_5_USB3_5_TXP': CDS_PINID='SATA_5_PCIE3_5_USB3_5_TXP';
NET_NAME
'P3E_PCH_E1S_TX_DP<2>'
 '@S9S_MB_2U_LIB.S9S_MB_2U(SCH_1):P3E_PCH_E1S_TX_DP'<2>:
 C_SIGNAL='@s9s_mb_2u_lib.s9s_mb_2u(sch_1):p3e_pch_e1s_tx_dp(2)';
NODE_NAME     C1991 1
 '@S9S_MB_2U_LIB.S9S_MB_2U(SCH_1):PAGE173_I73@PURE_QUANTA.Q_CAP_DIFFBUS(CHIPS)':
 '1': CDS_PINID='\1\';
NODE_NAME     U4 AH37
 '@S9S_MB_2U_LIB.S9S_MB_2U(SCH_1):PAGE173_I110@PURE_QUANTA.EMMITSBURG_REV0P9(CHIPS)':
 'SATA_6_PCIE3_6_USB3_6_TXP': CDS_PINID='SATA_6_PCIE3_6_USB3_6_TXP';
NET_NAME
'P3E_PCH_E1S_TX_DP<3>'
 '@S9S_MB_2U_LIB.S9S_MB_2U(SCH_1):P3E_PCH_E1S_TX_DP'<3>:
 C_SIGNAL='@s9s_mb_2u_lib.s9s_mb_2u(sch_1):p3e_pch_e1s_tx_dp(3)';
NODE_NAME     C1989 1
 '@S9S_MB_2U_LIB.S9S_MB_2U(SCH_1):PAGE173_I75@PURE_QUANTA.Q_CAP_DIFFBUS(CHIPS)':
 '1': CDS_PINID='\1\';
NODE_NAME     U4 AG36
 '@S9S_MB_2U_LIB.S9S_MB_2U(SCH_1):PAGE173_I110@PURE_QUANTA.EMMITSBURG_REV0P9(CHIPS)':
 'SATA_7_PCIE3_7_USB3_7_TXP': CDS_PINID='SATA_7_PCIE3_7_USB3_7_TXP';
NET_NAME
'P3E_PCH_M2_RX_DN<0>'
 '@S9S_MB_2U_LIB.S9S_MB_2U(SCH_1):P3E_PCH_M2_RX_DN'<0>:
 C_SIGNAL='@s9s_mb_2u_lib.s9s_mb_2u(sch_1):p3e_pch_m2_rx_dn(0)';
NODE_NAME     J59 5
 '@S9S_MB_2U_LIB.S9S_MB_2U(SCH_1):PAGE182_I178@PURE_QUANTA.SCONN75K_APCI0155P004A(CHIPS)':
 'PERN3': CDS_PINID='PERN3';
NODE_NAME     U4 AE41
 '@S9S_MB_2U_LIB.S9S_MB_2U(SCH_1):PAGE173_I110@PURE_QUANTA.EMMITSBURG_REV0P9(CHIPS)':
 'SATA_0_PCIE3_0_USB3_0_RXN': CDS_PINID='SATA_0_PCIE3_0_USB3_0_RXN';
NET_NAME
'P3E_PCH_M2_RX_DN<1>'
 '@S9S_MB_2U_LIB.S9S_MB_2U(SCH_1):P3E_PCH_M2_RX_DN'<1>:
 C_SIGNAL='@s9s_mb_2u_lib.s9s_mb_2u(sch_1):p3e_pch_m2_rx_dn(1)';
NODE_NAME     J59 17
 '@S9S_MB_2U_LIB.S9S_MB_2U(SCH_1):PAGE182_I178@PURE_QUANTA.SCONN75K_APCI0155P004A(CHIPS)':
 'PERN2': CDS_PINID='PERN2';
NODE_NAME     U4 AD40
 '@S9S_MB_2U_LIB.S9S_MB_2U(SCH_1):PAGE173_I110@PURE_QUANTA.EMMITSBURG_REV0P9(CHIPS)':
 'SATA_1_PCIE3_1_USB3_1_RXN': CDS_PINID='SATA_1_PCIE3_1_USB3_1_RXN';
NET_NAME
'P3E_PCH_M2_RX_DN<2>'
 '@S9S_MB_2U_LIB.S9S_MB_2U(SCH_1):P3E_PCH_M2_RX_DN'<2>:
 C_SIGNAL='@s9s_mb_2u_lib.s9s_mb_2u(sch_1):p3e_pch_m2_rx_dn(2)';
NODE_NAME     J59 29
 '@S9S_MB_2U_LIB.S9S_MB_2U(SCH_1):PAGE182_I178@PURE_QUANTA.SCONN75K_APCI0155P004A(CHIPS)':
 'PERN1': CDS_PINID='PERN1';
NODE_NAME     U4 AC41
 '@S9S_MB_2U_LIB.S9S_MB_2U(SCH_1):PAGE173_I110@PURE_QUANTA.EMMITSBURG_REV0P9(CHIPS)':
 'SATA_2_PCIE3_2_USB3_2_RXN': CDS_PINID='SATA_2_PCIE3_2_USB3_2_RXN';
NET_NAME
'P3E_PCH_M2_RX_DN<3>'
 '@S9S_MB_2U_LIB.S9S_MB_2U(SCH_1):P3E_PCH_M2_RX_DN'<3>:
 C_SIGNAL='@s9s_mb_2u_lib.s9s_mb_2u(sch_1):p3e_pch_m2_rx_dn(3)';
NODE_NAME     J59 41
 '@S9S_MB_2U_LIB.S9S_MB_2U(SCH_1):PAGE182_I178@PURE_QUANTA.SCONN75K_APCI0155P004A(CHIPS)':
 'PERN0||SATA-B+': CDS_PINID='\pern0||sata-b+\';
NODE_NAME     U4 AB40
 '@S9S_MB_2U_LIB.S9S_MB_2U(SCH_1):PAGE173_I110@PURE_QUANTA.EMMITSBURG_REV0P9(CHIPS)':
 'SATA_3_PCIE3_3_USB3_3_RXN': CDS_PINID='SATA_3_PCIE3_3_USB3_3_RXN';
NET_NAME
'P3E_PCH_M2_RX_DP<0>'
 '@S9S_MB_2U_LIB.S9S_MB_2U(SCH_1):P3E_PCH_M2_RX_DP'<0>:
 C_SIGNAL='@s9s_mb_2u_lib.s9s_mb_2u(sch_1):p3e_pch_m2_rx_dp(0)';
NODE_NAME     J59 7
 '@S9S_MB_2U_LIB.S9S_MB_2U(SCH_1):PAGE182_I178@PURE_QUANTA.SCONN75K_APCI0155P004A(CHIPS)':
 'PERP3': CDS_PINID='PERP3';
NODE_NAME     U4 AE43
 '@S9S_MB_2U_LIB.S9S_MB_2U(SCH_1):PAGE173_I110@PURE_QUANTA.EMMITSBURG_REV0P9(CHIPS)':
 'SATA_0_PCIE3_0_USB3_0_RXP': CDS_PINID='SATA_0_PCIE3_0_USB3_0_RXP';
NET_NAME
'P3E_PCH_M2_RX_DP<1>'
 '@S9S_MB_2U_LIB.S9S_MB_2U(SCH_1):P3E_PCH_M2_RX_DP'<1>:
 C_SIGNAL='@s9s_mb_2u_lib.s9s_mb_2u(sch_1):p3e_pch_m2_rx_dp(1)';
NODE_NAME     J59 19
 '@S9S_MB_2U_LIB.S9S_MB_2U(SCH_1):PAGE182_I178@PURE_QUANTA.SCONN75K_APCI0155P004A(CHIPS)':
 'PERP2': CDS_PINID='PERP2';
NODE_NAME     U4 AD42
 '@S9S_MB_2U_LIB.S9S_MB_2U(SCH_1):PAGE173_I110@PURE_QUANTA.EMMITSBURG_REV0P9(CHIPS)':
 'SATA_1_PCIE3_1_USB3_1_RXP': CDS_PINID='SATA_1_PCIE3_1_USB3_1_RXP';
NET_NAME
'P3E_PCH_M2_RX_DP<2>'
 '@S9S_MB_2U_LIB.S9S_MB_2U(SCH_1):P3E_PCH_M2_RX_DP'<2>:
 C_SIGNAL='@s9s_mb_2u_lib.s9s_mb_2u(sch_1):p3e_pch_m2_rx_dp(2)';
NODE_NAME     J59 31
 '@S9S_MB_2U_LIB.S9S_MB_2U(SCH_1):PAGE182_I178@PURE_QUANTA.SCONN75K_APCI0155P004A(CHIPS)':
 'PERP1': CDS_PINID='PERP1';
NODE_NAME     U4 AC43
 '@S9S_MB_2U_LIB.S9S_MB_2U(SCH_1):PAGE173_I110@PURE_QUANTA.EMMITSBURG_REV0P9(CHIPS)':
 'SATA_2_PCIE3_2_USB3_2_RXP': CDS_PINID='SATA_2_PCIE3_2_USB3_2_RXP';
NET_NAME
'P3E_PCH_M2_RX_DP<3>'
 '@S9S_MB_2U_LIB.S9S_MB_2U(SCH_1):P3E_PCH_M2_RX_DP'<3>:
 C_SIGNAL='@s9s_mb_2u_lib.s9s_mb_2u(sch_1):p3e_pch_m2_rx_dp(3)';
NODE_NAME     J59 43
 '@S9S_MB_2U_LIB.S9S_MB_2U(SCH_1):PAGE182_I178@PURE_QUANTA.SCONN75K_APCI0155P004A(CHIPS)':
 'PERP0||SATA-B-': CDS_PINID='\perp0||sata-b-\';
NODE_NAME     U4 AB42
 '@S9S_MB_2U_LIB.S9S_MB_2U(SCH_1):PAGE173_I110@PURE_QUANTA.EMMITSBURG_REV0P9(CHIPS)':
 'SATA_3_PCIE3_3_USB3_3_RXP': CDS_PINID='SATA_3_PCIE3_3_USB3_3_RXP';
NET_NAME
'P3E_PCH_M2_TX_C_DN<0>'
 '@S9S_MB_2U_LIB.S9S_MB_2U(SCH_1):P3E_PCH_M2_TX_C_DN'<0>:
 C_SIGNAL='@s9s_mb_2u_lib.s9s_mb_2u(sch_1):p3e_pch_m2_tx_c_dn(0)';
NODE_NAME     J59 13
 '@S9S_MB_2U_LIB.S9S_MB_2U(SCH_1):PAGE182_I178@PURE_QUANTA.SCONN75K_APCI0155P004A(CHIPS)':
 'PETP3': CDS_PINID='PETP3';
NODE_NAME     C1105 2
 '@S9S_MB_2U_LIB.S9S_MB_2U(SCH_1):PAGE173_I60@PURE_QUANTA.Q_CAP_DIFFBUS(CHIPS)':
 '2': CDS_PINID='\2\';
NET_NAME
'P3E_PCH_M2_TX_C_DN<1>'
 '@S9S_MB_2U_LIB.S9S_MB_2U(SCH_1):P3E_PCH_M2_TX_C_DN'<1>:
 C_SIGNAL='@s9s_mb_2u_lib.s9s_mb_2u(sch_1):p3e_pch_m2_tx_c_dn(1)';
NODE_NAME     J59 25
 '@S9S_MB_2U_LIB.S9S_MB_2U(SCH_1):PAGE182_I178@PURE_QUANTA.SCONN75K_APCI0155P004A(CHIPS)':
 'PETP2': CDS_PINID='PETP2';
NODE_NAME     C1103 2
 '@S9S_MB_2U_LIB.S9S_MB_2U(SCH_1):PAGE173_I62@PURE_QUANTA.Q_CAP_DIFFBUS(CHIPS)':
 '2': CDS_PINID='\2\';
NET_NAME
'P3E_PCH_M2_TX_C_DN<2>'
 '@S9S_MB_2U_LIB.S9S_MB_2U(SCH_1):P3E_PCH_M2_TX_C_DN'<2>:
 C_SIGNAL='@s9s_mb_2u_lib.s9s_mb_2u(sch_1):p3e_pch_m2_tx_c_dn(2)';
NODE_NAME     J59 37
 '@S9S_MB_2U_LIB.S9S_MB_2U(SCH_1):PAGE182_I178@PURE_QUANTA.SCONN75K_APCI0155P004A(CHIPS)':
 'PETP1': CDS_PINID='PETP1';
NODE_NAME     C1101 2
 '@S9S_MB_2U_LIB.S9S_MB_2U(SCH_1):PAGE173_I65@PURE_QUANTA.Q_CAP_DIFFBUS(CHIPS)':
 '2': CDS_PINID='\2\';
NET_NAME
'P3E_PCH_M2_TX_C_DN<3>'
 '@S9S_MB_2U_LIB.S9S_MB_2U(SCH_1):P3E_PCH_M2_TX_C_DN'<3>:
 C_SIGNAL='@s9s_mb_2u_lib.s9s_mb_2u(sch_1):p3e_pch_m2_tx_c_dn(3)';
NODE_NAME     J59 49
 '@S9S_MB_2U_LIB.S9S_MB_2U(SCH_1):PAGE182_I178@PURE_QUANTA.SCONN75K_APCI0155P004A(CHIPS)':
 'PETP0||SATA-A+': CDS_PINID='\petp0||sata-a+\';
NODE_NAME     C1099 2
 '@S9S_MB_2U_LIB.S9S_MB_2U(SCH_1):PAGE173_I66@PURE_QUANTA.Q_CAP_DIFFBUS(CHIPS)':
 '2': CDS_PINID='\2\';
NET_NAME
'P3E_PCH_M2_TX_C_DP<0>'
 '@S9S_MB_2U_LIB.S9S_MB_2U(SCH_1):P3E_PCH_M2_TX_C_DP'<0>:
 C_SIGNAL='@s9s_mb_2u_lib.s9s_mb_2u(sch_1):p3e_pch_m2_tx_c_dp(0)';
NODE_NAME     J59 11
 '@S9S_MB_2U_LIB.S9S_MB_2U(SCH_1):PAGE182_I178@PURE_QUANTA.SCONN75K_APCI0155P004A(CHIPS)':
 'PETN3': CDS_PINID='PETN3';
NODE_NAME     C1104 2
 '@S9S_MB_2U_LIB.S9S_MB_2U(SCH_1):PAGE173_I61@PURE_QUANTA.Q_CAP_DIFFBUS(CHIPS)':
 '2': CDS_PINID='\2\';
NET_NAME
'P3E_PCH_M2_TX_C_DP<1>'
 '@S9S_MB_2U_LIB.S9S_MB_2U(SCH_1):P3E_PCH_M2_TX_C_DP'<1>:
 C_SIGNAL='@s9s_mb_2u_lib.s9s_mb_2u(sch_1):p3e_pch_m2_tx_c_dp(1)';
NODE_NAME     J59 23
 '@S9S_MB_2U_LIB.S9S_MB_2U(SCH_1):PAGE182_I178@PURE_QUANTA.SCONN75K_APCI0155P004A(CHIPS)':
 'PETN2': CDS_PINID='PETN2';
NODE_NAME     C1102 2
 '@S9S_MB_2U_LIB.S9S_MB_2U(SCH_1):PAGE173_I63@PURE_QUANTA.Q_CAP_DIFFBUS(CHIPS)':
 '2': CDS_PINID='\2\';
NET_NAME
'P3E_PCH_M2_TX_C_DP<2>'
 '@S9S_MB_2U_LIB.S9S_MB_2U(SCH_1):P3E_PCH_M2_TX_C_DP'<2>:
 C_SIGNAL='@s9s_mb_2u_lib.s9s_mb_2u(sch_1):p3e_pch_m2_tx_c_dp(2)';
NODE_NAME     J59 35
 '@S9S_MB_2U_LIB.S9S_MB_2U(SCH_1):PAGE182_I178@PURE_QUANTA.SCONN75K_APCI0155P004A(CHIPS)':
 'PETN1': CDS_PINID='PETN1';
NODE_NAME     C1100 2
 '@S9S_MB_2U_LIB.S9S_MB_2U(SCH_1):PAGE173_I64@PURE_QUANTA.Q_CAP_DIFFBUS(CHIPS)':
 '2': CDS_PINID='\2\';
NET_NAME
'P3E_PCH_M2_TX_C_DP<3>'
 '@S9S_MB_2U_LIB.S9S_MB_2U(SCH_1):P3E_PCH_M2_TX_C_DP'<3>:
 C_SIGNAL='@s9s_mb_2u_lib.s9s_mb_2u(sch_1):p3e_pch_m2_tx_c_dp(3)';
NODE_NAME     J59 47
 '@S9S_MB_2U_LIB.S9S_MB_2U(SCH_1):PAGE182_I178@PURE_QUANTA.SCONN75K_APCI0155P004A(CHIPS)':
 'PETN0||SATA-A-': CDS_PINID='\petn0||sata-a-\';
NODE_NAME     C1098 2
 '@S9S_MB_2U_LIB.S9S_MB_2U(SCH_1):PAGE173_I67@PURE_QUANTA.Q_CAP_DIFFBUS(CHIPS)':
 '2': CDS_PINID='\2\';
NET_NAME
'P3E_PCH_M2_TX_DN<0>'
 '@S9S_MB_2U_LIB.S9S_MB_2U(SCH_1):P3E_PCH_M2_TX_DN'<0>:
 C_SIGNAL='@s9s_mb_2u_lib.s9s_mb_2u(sch_1):p3e_pch_m2_tx_dn(0)';
NODE_NAME     C1105 1
 '@S9S_MB_2U_LIB.S9S_MB_2U(SCH_1):PAGE173_I60@PURE_QUANTA.Q_CAP_DIFFBUS(CHIPS)':
 '1': CDS_PINID='\1\';
NODE_NAME     U4 AL32
 '@S9S_MB_2U_LIB.S9S_MB_2U(SCH_1):PAGE173_I110@PURE_QUANTA.EMMITSBURG_REV0P9(CHIPS)':
 'SATA_0_PCIE3_0_USB3_0_TXN': CDS_PINID='SATA_0_PCIE3_0_USB3_0_TXN';
NET_NAME
'P3E_PCH_M2_TX_DN<1>'
 '@S9S_MB_2U_LIB.S9S_MB_2U(SCH_1):P3E_PCH_M2_TX_DN'<1>:
 C_SIGNAL='@s9s_mb_2u_lib.s9s_mb_2u(sch_1):p3e_pch_m2_tx_dn(1)';
NODE_NAME     C1103 1
 '@S9S_MB_2U_LIB.S9S_MB_2U(SCH_1):PAGE173_I62@PURE_QUANTA.Q_CAP_DIFFBUS(CHIPS)':
 '1': CDS_PINID='\1\';
NODE_NAME     U4 AN36
 '@S9S_MB_2U_LIB.S9S_MB_2U(SCH_1):PAGE173_I110@PURE_QUANTA.EMMITSBURG_REV0P9(CHIPS)':
 'SATA_1_PCIE3_1_USB3_1_TXN': CDS_PINID='SATA_1_PCIE3_1_USB3_1_TXN';
NET_NAME
'P3E_PCH_M2_TX_DN<2>'
 '@S9S_MB_2U_LIB.S9S_MB_2U(SCH_1):P3E_PCH_M2_TX_DN'<2>:
 C_SIGNAL='@s9s_mb_2u_lib.s9s_mb_2u(sch_1):p3e_pch_m2_tx_dn(2)';
NODE_NAME     C1101 1
 '@S9S_MB_2U_LIB.S9S_MB_2U(SCH_1):PAGE173_I65@PURE_QUANTA.Q_CAP_DIFFBUS(CHIPS)':
 '1': CDS_PINID='\1\';
NODE_NAME     U4 AR36
 '@S9S_MB_2U_LIB.S9S_MB_2U(SCH_1):PAGE173_I110@PURE_QUANTA.EMMITSBURG_REV0P9(CHIPS)':
 'SATA_2_PCIE3_2_USB3_2_TXN': CDS_PINID='SATA_2_PCIE3_2_USB3_2_TXN';
NET_NAME
'P3E_PCH_M2_TX_DN<3>'
 '@S9S_MB_2U_LIB.S9S_MB_2U(SCH_1):P3E_PCH_M2_TX_DN'<3>:
 C_SIGNAL='@s9s_mb_2u_lib.s9s_mb_2u(sch_1):p3e_pch_m2_tx_dn(3)';
NODE_NAME     C1099 1
 '@S9S_MB_2U_LIB.S9S_MB_2U(SCH_1):PAGE173_I66@PURE_QUANTA.Q_CAP_DIFFBUS(CHIPS)':
 '1': CDS_PINID='\1\';
NODE_NAME     U4 AK34
 '@S9S_MB_2U_LIB.S9S_MB_2U(SCH_1):PAGE173_I110@PURE_QUANTA.EMMITSBURG_REV0P9(CHIPS)':
 'SATA_3_PCIE3_3_USB3_3_TXN': CDS_PINID='SATA_3_PCIE3_3_USB3_3_TXN';
NET_NAME
'P3E_PCH_M2_TX_DP<0>'
 '@S9S_MB_2U_LIB.S9S_MB_2U(SCH_1):P3E_PCH_M2_TX_DP'<0>:
 C_SIGNAL='@s9s_mb_2u_lib.s9s_mb_2u(sch_1):p3e_pch_m2_tx_dp(0)';
NODE_NAME     C1104 1
 '@S9S_MB_2U_LIB.S9S_MB_2U(SCH_1):PAGE173_I61@PURE_QUANTA.Q_CAP_DIFFBUS(CHIPS)':
 '1': CDS_PINID='\1\';
NODE_NAME     U4 AK31
 '@S9S_MB_2U_LIB.S9S_MB_2U(SCH_1):PAGE173_I110@PURE_QUANTA.EMMITSBURG_REV0P9(CHIPS)':
 'SATA_0_PCIE3_0_USB3_0_TXP': CDS_PINID='SATA_0_PCIE3_0_USB3_0_TXP';
NET_NAME
'P3E_PCH_M2_TX_DP<1>'
 '@S9S_MB_2U_LIB.S9S_MB_2U(SCH_1):P3E_PCH_M2_TX_DP'<1>:
 C_SIGNAL='@s9s_mb_2u_lib.s9s_mb_2u(sch_1):p3e_pch_m2_tx_dp(1)';
NODE_NAME     C1102 1
 '@S9S_MB_2U_LIB.S9S_MB_2U(SCH_1):PAGE173_I63@PURE_QUANTA.Q_CAP_DIFFBUS(CHIPS)':
 '1': CDS_PINID='\1\';
NODE_NAME     U4 AP34
 '@S9S_MB_2U_LIB.S9S_MB_2U(SCH_1):PAGE173_I110@PURE_QUANTA.EMMITSBURG_REV0P9(CHIPS)':
 'SATA_1_PCIE3_1_USB3_1_TXP': CDS_PINID='SATA_1_PCIE3_1_USB3_1_TXP';
NET_NAME
'P3E_PCH_M2_TX_DP<2>'
 '@S9S_MB_2U_LIB.S9S_MB_2U(SCH_1):P3E_PCH_M2_TX_DP'<2>:
 C_SIGNAL='@s9s_mb_2u_lib.s9s_mb_2u(sch_1):p3e_pch_m2_tx_dp(2)';
NODE_NAME     C1100 1
 '@S9S_MB_2U_LIB.S9S_MB_2U(SCH_1):PAGE173_I64@PURE_QUANTA.Q_CAP_DIFFBUS(CHIPS)':
 '1': CDS_PINID='\1\';
NODE_NAME     U4 AT37
 '@S9S_MB_2U_LIB.S9S_MB_2U(SCH_1):PAGE173_I110@PURE_QUANTA.EMMITSBURG_REV0P9(CHIPS)':
 'SATA_2_PCIE3_2_USB3_2_TXP': CDS_PINID='SATA_2_PCIE3_2_USB3_2_TXP';
NET_NAME
'P3E_PCH_M2_TX_DP<3>'
 '@S9S_MB_2U_LIB.S9S_MB_2U(SCH_1):P3E_PCH_M2_TX_DP'<3>:
 C_SIGNAL='@s9s_mb_2u_lib.s9s_mb_2u(sch_1):p3e_pch_m2_tx_dp(3)';
NODE_NAME     C1098 1
 '@S9S_MB_2U_LIB.S9S_MB_2U(SCH_1):PAGE173_I67@PURE_QUANTA.Q_CAP_DIFFBUS(CHIPS)':
 '1': CDS_PINID='\1\';
NODE_NAME     U4 AM34
 '@S9S_MB_2U_LIB.S9S_MB_2U(SCH_1):PAGE173_I110@PURE_QUANTA.EMMITSBURG_REV0P9(CHIPS)':
 'SATA_3_PCIE3_3_USB3_3_TXP': CDS_PINID='SATA_3_PCIE3_3_USB3_3_TXP';
NET_NAME
'P3E_PCH_NVS_RX_DN<0>'
 '@S9S_MB_2U_LIB.S9S_MB_2U(SCH_1):P3E_PCH_NVS_RX_DN'<0>:
 C_SIGNAL='@s9s_mb_2u_lib.s9s_mb_2u(sch_1):p3e_pch_nvs_rx_dn(0)';
NODE_NAME     J112 N8
 '@S9S_MB_2U_LIB.S9S_MB_2U(SCH_1):PAGE149_I75@PURE_QUANTA.CONN160_10131762101LF(CHIPS)':
 'N8': CDS_PINID='N8';
NODE_NAME     U4 M41
 '@S9S_MB_2U_LIB.S9S_MB_2U(SCH_1):PAGE173_I110@PURE_QUANTA.EMMITSBURG_REV0P9(CHIPS)':
 'SATA_10_PCIE3_10_GBE_0_RXN': CDS_PINID='SATA_10_PCIE3_10_GBE_0_RXN';
NET_NAME
'P3E_PCH_NVS_RX_DN<1>'
 '@S9S_MB_2U_LIB.S9S_MB_2U(SCH_1):P3E_PCH_NVS_RX_DN'<1>:
 C_SIGNAL='@s9s_mb_2u_lib.s9s_mb_2u(sch_1):p3e_pch_nvs_rx_dn(1)';
NODE_NAME     J112 O7
 '@S9S_MB_2U_LIB.S9S_MB_2U(SCH_1):PAGE149_I75@PURE_QUANTA.CONN160_10131762101LF(CHIPS)':
 'O7': CDS_PINID='O7';
NODE_NAME     U4 L40
 '@S9S_MB_2U_LIB.S9S_MB_2U(SCH_1):PAGE173_I110@PURE_QUANTA.EMMITSBURG_REV0P9(CHIPS)':
 'SATA_11_PCIE3_11_RXN': CDS_PINID='SATA_11_PCIE3_11_RXN';
NET_NAME
'P3E_PCH_NVS_RX_DP<0>'
 '@S9S_MB_2U_LIB.S9S_MB_2U(SCH_1):P3E_PCH_NVS_RX_DP'<0>:
 C_SIGNAL='@s9s_mb_2u_lib.s9s_mb_2u(sch_1):p3e_pch_nvs_rx_dp(0)';
NODE_NAME     J112 O8
 '@S9S_MB_2U_LIB.S9S_MB_2U(SCH_1):PAGE149_I75@PURE_QUANTA.CONN160_10131762101LF(CHIPS)':
 'O8': CDS_PINID='O8';
NODE_NAME     U4 M43
 '@S9S_MB_2U_LIB.S9S_MB_2U(SCH_1):PAGE173_I110@PURE_QUANTA.EMMITSBURG_REV0P9(CHIPS)':
 'SATA_10_PCIE3_10_GBE_0_RXP': CDS_PINID='SATA_10_PCIE3_10_GBE_0_RXP';
NET_NAME
'P3E_PCH_NVS_RX_DP<1>'
 '@S9S_MB_2U_LIB.S9S_MB_2U(SCH_1):P3E_PCH_NVS_RX_DP'<1>:
 C_SIGNAL='@s9s_mb_2u_lib.s9s_mb_2u(sch_1):p3e_pch_nvs_rx_dp(1)';
NODE_NAME     J112 P7
 '@S9S_MB_2U_LIB.S9S_MB_2U(SCH_1):PAGE149_I75@PURE_QUANTA.CONN160_10131762101LF(CHIPS)':
 'P7': CDS_PINID='P7';
NODE_NAME     U4 L42
 '@S9S_MB_2U_LIB.S9S_MB_2U(SCH_1):PAGE173_I110@PURE_QUANTA.EMMITSBURG_REV0P9(CHIPS)':
 'SATA_11_PCIE3_11_RXP': CDS_PINID='SATA_11_PCIE3_11_RXP';
NET_NAME
'P3E_PCH_NVS_TX_C_DN<0>'
 '@S9S_MB_2U_LIB.S9S_MB_2U(SCH_1):P3E_PCH_NVS_TX_C_DN'<0>:
 C_SIGNAL='@s9s_mb_2u_lib.s9s_mb_2u(sch_1):p3e_pch_nvs_tx_c_dn(0)';
NODE_NAME     J112 Q8
 '@S9S_MB_2U_LIB.S9S_MB_2U(SCH_1):PAGE149_I75@PURE_QUANTA.CONN160_10131762101LF(CHIPS)':
 'Q8': CDS_PINID='Q8';
NODE_NAME     C2076 2
 '@S9S_MB_2U_LIB.S9S_MB_2U(SCH_1):PAGE173_I79@PURE_QUANTA.Q_CAP_DIFFBUS(CHIPS)':
 '2': CDS_PINID='\2\';
NET_NAME
'P3E_PCH_NVS_TX_C_DN<1>'
 '@S9S_MB_2U_LIB.S9S_MB_2U(SCH_1):P3E_PCH_NVS_TX_C_DN'<1>:
 C_SIGNAL='@s9s_mb_2u_lib.s9s_mb_2u(sch_1):p3e_pch_nvs_tx_c_dn(1)';
NODE_NAME     J112 R7
 '@S9S_MB_2U_LIB.S9S_MB_2U(SCH_1):PAGE149_I75@PURE_QUANTA.CONN160_10131762101LF(CHIPS)':
 'R7': CDS_PINID='R7';
NODE_NAME     C2074 2
 '@S9S_MB_2U_LIB.S9S_MB_2U(SCH_1):PAGE173_I82@PURE_QUANTA.Q_CAP_DIFFBUS(CHIPS)':
 '2': CDS_PINID='\2\';
NET_NAME
'P3E_PCH_NVS_TX_C_DP<0>'
 '@S9S_MB_2U_LIB.S9S_MB_2U(SCH_1):P3E_PCH_NVS_TX_C_DP'<0>:
 C_SIGNAL='@s9s_mb_2u_lib.s9s_mb_2u(sch_1):p3e_pch_nvs_tx_c_dp(0)';
NODE_NAME     J112 R8
 '@S9S_MB_2U_LIB.S9S_MB_2U(SCH_1):PAGE149_I75@PURE_QUANTA.CONN160_10131762101LF(CHIPS)':
 'R8': CDS_PINID='R8';
NODE_NAME     C2075 2
 '@S9S_MB_2U_LIB.S9S_MB_2U(SCH_1):PAGE173_I81@PURE_QUANTA.Q_CAP_DIFFBUS(CHIPS)':
 '2': CDS_PINID='\2\';
NET_NAME
'P3E_PCH_NVS_TX_C_DP<1>'
 '@S9S_MB_2U_LIB.S9S_MB_2U(SCH_1):P3E_PCH_NVS_TX_C_DP'<1>:
 C_SIGNAL='@s9s_mb_2u_lib.s9s_mb_2u(sch_1):p3e_pch_nvs_tx_c_dp(1)';
NODE_NAME     J112 S7
 '@S9S_MB_2U_LIB.S9S_MB_2U(SCH_1):PAGE149_I75@PURE_QUANTA.CONN160_10131762101LF(CHIPS)':
 'S7': CDS_PINID='S7';
NODE_NAME     C2073 2
 '@S9S_MB_2U_LIB.S9S_MB_2U(SCH_1):PAGE173_I83@PURE_QUANTA.Q_CAP_DIFFBUS(CHIPS)':
 '2': CDS_PINID='\2\';
NET_NAME
'P3E_PCH_NVS_TX_DN<0>'
 '@S9S_MB_2U_LIB.S9S_MB_2U(SCH_1):P3E_PCH_NVS_TX_DN'<0>:
 C_SIGNAL='@s9s_mb_2u_lib.s9s_mb_2u(sch_1):p3e_pch_nvs_tx_dn(0)';
NODE_NAME     C2076 1
 '@S9S_MB_2U_LIB.S9S_MB_2U(SCH_1):PAGE173_I79@PURE_QUANTA.Q_CAP_DIFFBUS(CHIPS)':
 '1': CDS_PINID='\1\';
NODE_NAME     U4 W36
 '@S9S_MB_2U_LIB.S9S_MB_2U(SCH_1):PAGE173_I110@PURE_QUANTA.EMMITSBURG_REV0P9(CHIPS)':
 'SATA_10_PCIE3_10_GBE_0_TXN': CDS_PINID='SATA_10_PCIE3_10_GBE_0_TXN';
NET_NAME
'P3E_PCH_NVS_TX_DN<1>'
 '@S9S_MB_2U_LIB.S9S_MB_2U(SCH_1):P3E_PCH_NVS_TX_DN'<1>:
 C_SIGNAL='@s9s_mb_2u_lib.s9s_mb_2u(sch_1):p3e_pch_nvs_tx_dn(1)';
NODE_NAME     C2074 1
 '@S9S_MB_2U_LIB.S9S_MB_2U(SCH_1):PAGE173_I82@PURE_QUANTA.Q_CAP_DIFFBUS(CHIPS)':
 '1': CDS_PINID='\1\';
NODE_NAME     U4 T37
 '@S9S_MB_2U_LIB.S9S_MB_2U(SCH_1):PAGE173_I110@PURE_QUANTA.EMMITSBURG_REV0P9(CHIPS)':
 'SATA_11_PCIE3_11_TXN': CDS_PINID='SATA_11_PCIE3_11_TXN';
NET_NAME
'P3E_PCH_NVS_TX_DP<0>'
 '@S9S_MB_2U_LIB.S9S_MB_2U(SCH_1):P3E_PCH_NVS_TX_DP'<0>:
 C_SIGNAL='@s9s_mb_2u_lib.s9s_mb_2u(sch_1):p3e_pch_nvs_tx_dp(0)';
NODE_NAME     C2075 1
 '@S9S_MB_2U_LIB.S9S_MB_2U(SCH_1):PAGE173_I81@PURE_QUANTA.Q_CAP_DIFFBUS(CHIPS)':
 '1': CDS_PINID='\1\';
NODE_NAME     U4 Y37
 '@S9S_MB_2U_LIB.S9S_MB_2U(SCH_1):PAGE173_I110@PURE_QUANTA.EMMITSBURG_REV0P9(CHIPS)':
 'SATA_10_PCIE3_10_GBE_0_TXP': CDS_PINID='SATA_10_PCIE3_10_GBE_0_TXP';
NET_NAME
'P3E_PCH_NVS_TX_DP<1>'
 '@S9S_MB_2U_LIB.S9S_MB_2U(SCH_1):P3E_PCH_NVS_TX_DP'<1>:
 C_SIGNAL='@s9s_mb_2u_lib.s9s_mb_2u(sch_1):p3e_pch_nvs_tx_dp(1)';
NODE_NAME     C2073 1
 '@S9S_MB_2U_LIB.S9S_MB_2U(SCH_1):PAGE173_I83@PURE_QUANTA.Q_CAP_DIFFBUS(CHIPS)':
 '1': CDS_PINID='\1\';
NODE_NAME     U4 V37
 '@S9S_MB_2U_LIB.S9S_MB_2U(SCH_1):PAGE173_I110@PURE_QUANTA.EMMITSBURG_REV0P9(CHIPS)':
 'SATA_11_PCIE3_11_TXP': CDS_PINID='SATA_11_PCIE3_11_TXP';
NET_NAME
'P3V3'
 '@S9S_MB_2U_LIB.S9S_MB_2U(SCH_1):P3V3':
 C_SIGNAL='@s9s_mb_2u_lib.s9s_mb_2u(sch_1):p3v3',
 CDS_GLOBAL_NET='TRUE';
NODE_NAME     L3 1
 '@S9S_MB_2U_LIB.S9S_MB_2U(SCH_1):PAGE195_I170@PURE_QUANTA.Q_INDUCTOR(CHIPS)':
 '1': CDS_PINID='\1\';
NODE_NAME     L4 1
 '@S9S_MB_2U_LIB.S9S_MB_2U(SCH_1):PAGE195_I177@PURE_QUANTA.Q_INDUCTOR(CHIPS)':
 '1': CDS_PINID='\1\';
NODE_NAME     R567 1
 '@S9S_MB_2U_LIB.S9S_MB_2U(SCH_1):PAGE195_I179@PURE_QUANTA.Q_RES(CHIPS)':
 'A': CDS_PINID='A';
NODE_NAME     R569 1
 '@S9S_MB_2U_LIB.S9S_MB_2U(SCH_1):PAGE195_I185@PURE_QUANTA.Q_RES(CHIPS)':
 'A': CDS_PINID='A';
NODE_NAME     R573 1
 '@S9S_MB_2U_LIB.S9S_MB_2U(SCH_1):PAGE195_I194@PURE_QUANTA.Q_RES(CHIPS)':
 'A': CDS_PINID='A';
NODE_NAME     R111 1
 '@S9S_MB_2U_LIB.S9S_MB_2U(SCH_1):PAGE212_I24@PURE_QUANTA.Q_RES(CHIPS)':
 'A': CDS_PINID='A';
NODE_NAME     R1002 1
 '@S9S_MB_2U_LIB.S9S_MB_2U(SCH_1):PAGE223_I34@PURE_QUANTA.Q_RES(CHIPS)':
 'A': CDS_PINID='A';
NODE_NAME     R1003 1
 '@S9S_MB_2U_LIB.S9S_MB_2U(SCH_1):PAGE223_I38@PURE_QUANTA.Q_RES(CHIPS)':
 'A': CDS_PINID='A';
NODE_NAME     R1000 1
 '@S9S_MB_2U_LIB.S9S_MB_2U(SCH_1):PAGE223_I52@PURE_QUANTA.Q_RES(CHIPS)':
 'A': CDS_PINID='A';
NODE_NAME     R1001 1
 '@S9S_MB_2U_LIB.S9S_MB_2U(SCH_1):PAGE223_I55@PURE_QUANTA.Q_RES(CHIPS)':
 'A': CDS_PINID='A';
NODE_NAME     R3100 2
 '@S9S_MB_2U_LIB.S9S_MB_2U(SCH_1):PAGE242_I64@PURE_QUANTA.Q_RES(CHIPS)':
 'B': CDS_PINID='B';
NODE_NAME     C2018 1
 '@S9S_MB_2U_LIB.S9S_MB_2U(SCH_1):PAGE163_I26@PURE_QUANTA.Q_CAP(CHIPS)':
 'A': CDS_PINID='A';
NODE_NAME     R3574 1
 '@S9S_MB_2U_LIB.S9S_MB_2U(SCH_1):PAGE163_I35@PURE_QUANTA.Q_RES(CHIPS)':
 'A': CDS_PINID='A';
NODE_NAME     U264 11
 '@S9S_MB_2U_LIB.S9S_MB_2U(SCH_1):PAGE163_I46@PURE_QUANTA.INA230AIRGTR(CHIPS)':
 'BUS': CDS_PINID='\bus\';
NODE_NAME     R2908 1
 '@S9S_MB_2U_LIB.S9S_MB_2U(SCH_1):PAGE239_I161@PURE_QUANTA.Q_RES(CHIPS)':
 'A': CDS_PINID='A';
NODE_NAME     C2243 1
 '@S9S_MB_2U_LIB.S9S_MB_2U(SCH_1):PAGE321_I85@PURE_QUANTA.Q_CAP(CHIPS)':
 'A': CDS_PINID='A';
NODE_NAME     U301 14
 '@S9S_MB_2U_LIB.S9S_MB_2U(SCH_1):PAGE321_I91@PURE_QUANTA.GTL2014PW(CHIPS)':
 'VCC': CDS_PINID='VCC';
NODE_NAME     U306 14
 '@S9S_MB_2U_LIB.S9S_MB_2U(SCH_1):PAGE322_I80@PURE_QUANTA.GTL2014PW(CHIPS)':
 'VCC': CDS_PINID='VCC';
NODE_NAME     C2248 1
 '@S9S_MB_2U_LIB.S9S_MB_2U(SCH_1):PAGE322_I83@PURE_QUANTA.Q_CAP(CHIPS)':
 'A': CDS_PINID='A';
NODE_NAME     D7 1
 '@S9S_MB_2U_LIB.S9S_MB_2U(SCH_1):PAGE246_I32@PURE_QUANTA.BAT547F(CHIPS)':
 '1': CDS_PINID='\1\';
NODE_NAME     Q56 1
 '@S9S_MB_2U_LIB.S9S_MB_2U(SCH_1):PAGE246_I51@PURE_QUANTA.MOSFET_NCH_1D3S(CHIPS)':
 '1': CDS_PINID='\1\';
NODE_NAME     Q56 2
 '@S9S_MB_2U_LIB.S9S_MB_2U(SCH_1):PAGE246_I51@PURE_QUANTA.MOSFET_NCH_1D3S(CHIPS)':
 '2': CDS_PINID='\2\';
NODE_NAME     Q56 3
 '@S9S_MB_2U_LIB.S9S_MB_2U(SCH_1):PAGE246_I51@PURE_QUANTA.MOSFET_NCH_1D3S(CHIPS)':
 '3': CDS_PINID='\3\';
NODE_NAME     C1339 1
 '@S9S_MB_2U_LIB.S9S_MB_2U(SCH_1):PAGE246_I58@PURE_QUANTA.Q_CAP(CHIPS)':
 'A': CDS_PINID='A';
NODE_NAME     C1340 1
 '@S9S_MB_2U_LIB.S9S_MB_2U(SCH_1):PAGE246_I61@PURE_QUANTA.Q_CAP(CHIPS)':
 'A': CDS_PINID='A';
NODE_NAME     PR633 1
 '@S9S_MB_2U_LIB.S9S_MB_2U(SCH_1):PAGE257_I22@PURE_QUANTA.Q_RES(CHIPS)':
 'A': CDS_PINID='A';
NODE_NAME     PR703 1
 '@S9S_MB_2U_LIB.S9S_MB_2U(SCH_1):PAGE275_I34@PURE_QUANTA.Q_RES(CHIPS)':
 'A': CDS_PINID='A';
NODE_NAME     R4016 1
 '@S9S_MB_2U_LIB.S9S_MB_2U(SCH_1):PAGE321_I97@PURE_QUANTA.Q_RES(CHIPS)':
 'A': CDS_PINID='A';
NODE_NAME     R4038 1
 '@S9S_MB_2U_LIB.S9S_MB_2U(SCH_1):PAGE322_I182@PURE_QUANTA.Q_RES(CHIPS)':
 'A': CDS_PINID='A';
NODE_NAME     R4489 1
 '@S9S_MB_2U_LIB.S9S_MB_2U(SCH_1):PAGE200_I30@PURE_QUANTA.Q_RES(CHIPS)':
 'A': CDS_PINID='A';
NODE_NAME     R4491 1
 '@S9S_MB_2U_LIB.S9S_MB_2U(SCH_1):PAGE200_I48@PURE_QUANTA.Q_RES(CHIPS)':
 'A': CDS_PINID='A';
NODE_NAME     R4494 2
 '@S9S_MB_2U_LIB.S9S_MB_2U(SCH_1):PAGE200_I69@PURE_QUANTA.Q_RES(CHIPS)':
 'B': CDS_PINID='B';
NODE_NAME     C2338 1
 '@S9S_MB_2U_LIB.S9S_MB_2U(SCH_1):PAGE225_I8@PURE_QUANTA.Q_CAP(CHIPS)':
 'A': CDS_PINID='A';
NODE_NAME     R4498 1
 '@S9S_MB_2U_LIB.S9S_MB_2U(SCH_1):PAGE225_I11@PURE_QUANTA.Q_RES(CHIPS)':
 'A': CDS_PINID='A';
NODE_NAME     R4499 1
 '@S9S_MB_2U_LIB.S9S_MB_2U(SCH_1):PAGE225_I12@PURE_QUANTA.Q_RES(CHIPS)':
 'A': CDS_PINID='A';
NODE_NAME     U315 8
 '@S9S_MB_2U_LIB.S9S_MB_2U(SCH_1):PAGE225_I17@PURE_QUANTA.PCA9617ADP(CHIPS)':
 'VCCB': CDS_PINID='VCCB';
NODE_NAME     R4500 1
 '@S9S_MB_2U_LIB.S9S_MB_2U(SCH_1):PAGE225_I32@PURE_QUANTA.Q_RES(CHIPS)':
 'A': CDS_PINID='A';
NODE_NAME     R4516 1
 '@S9S_MB_2U_LIB.S9S_MB_2U(SCH_1):PAGE195_I539@PURE_QUANTA.Q_RES(CHIPS)':
 'A': CDS_PINID='A';
NODE_NAME     R4517 1
 '@S9S_MB_2U_LIB.S9S_MB_2U(SCH_1):PAGE195_I540@PURE_QUANTA.Q_RES(CHIPS)':
 'A': CDS_PINID='A';
NODE_NAME     R4518 1
 '@S9S_MB_2U_LIB.S9S_MB_2U(SCH_1):PAGE200_I77@PURE_QUANTA.Q_RES(CHIPS)':
 'A': CDS_PINID='A';
NODE_NAME     R4519 1
 '@S9S_MB_2U_LIB.S9S_MB_2U(SCH_1):PAGE200_I78@PURE_QUANTA.Q_RES(CHIPS)':
 'A': CDS_PINID='A';
NODE_NAME     R4520 1
 '@S9S_MB_2U_LIB.S9S_MB_2U(SCH_1):PAGE200_I79@PURE_QUANTA.Q_RES(CHIPS)':
 'A': CDS_PINID='A';
NODE_NAME     L19 1
 '@S9S_MB_2U_LIB.S9S_MB_2U(SCH_1):PAGE200_I81@PURE_QUANTA.Q_INDUCTOR(CHIPS)':
 '1': CDS_PINID='\1\';
NODE_NAME     L20 1
 '@S9S_MB_2U_LIB.S9S_MB_2U(SCH_1):PAGE200_I82@PURE_QUANTA.Q_INDUCTOR(CHIPS)':
 '1': CDS_PINID='\1\';
NODE_NAME     PR704 1
 '@S9S_MB_2U_LIB.S9S_MB_2U(SCH_1):PAGE275_I17@PURE_QUANTA.Q_RES(CHIPS)':
 'A': CDS_PINID='A';
NODE_NAME     PR443 1
 '@S9S_MB_2U_LIB.S9S_MB_2U(SCH_1):PAGE262_I22@PURE_QUANTA.Q_RES(CHIPS)':
 'A': CDS_PINID='A';
NODE_NAME     PR403 1
 '@S9S_MB_2U_LIB.S9S_MB_2U(SCH_1):PAGE253_I42@PURE_QUANTA.Q_RES(CHIPS)':
 'A': CDS_PINID='A';
NODE_NAME     PR632 1
 '@S9S_MB_2U_LIB.S9S_MB_2U(SCH_1):PAGE257_I40@PURE_QUANTA.Q_RES(CHIPS)':
 'A': CDS_PINID='A';
NODE_NAME     PR640 1
 '@S9S_MB_2U_LIB.S9S_MB_2U(SCH_1):PAGE271_I41@PURE_QUANTA.Q_RES(CHIPS)':
 'A': CDS_PINID='A';
NODE_NAME     PR699 1
 '@S9S_MB_2U_LIB.S9S_MB_2U(SCH_1):PAGE280_I16@PURE_QUANTA.Q_RES(CHIPS)':
 'A': CDS_PINID='A';
NODE_NAME     R1706 1
 '@S9S_MB_2U_LIB.S9S_MB_2U(SCH_1):PAGE246_I89@PURE_QUANTA.Q_RES(CHIPS)':
 'A': CDS_PINID='A';
NODE_NAME     U330 3
 '@S9S_MB_2U_LIB.S9S_MB_2U(SCH_1):PAGE246_I105@PURE_QUANTA.APX80929SAG7(CHIPS)':
 'VCC': CDS_PINID='VCC';
NODE_NAME     C2360 1
 '@S9S_MB_2U_LIB.S9S_MB_2U(SCH_1):PAGE246_I107@PURE_QUANTA.Q_CAP(CHIPS)':
 'A': CDS_PINID='A';
NODE_NAME     R3634 2
 '@S9S_MB_2U_LIB.S9S_MB_2U(SCH_1):PAGE163_I128@PURE_QUANTA.Q_RES(CHIPS)':
 'B': CDS_PINID='B';
NODE_NAME     R242 1
 '@S9S_MB_2U_LIB.S9S_MB_2U(SCH_1):PAGE121_I26@PURE_QUANTA.Q_RES(CHIPS)':
 'A': CDS_PINID='A';
NODE_NAME     R241 1
 '@S9S_MB_2U_LIB.S9S_MB_2U(SCH_1):PAGE121_I33@PURE_QUANTA.Q_RES(CHIPS)':
 'A': CDS_PINID='A';
NODE_NAME     R4406 1
 '@S9S_MB_2U_LIB.S9S_MB_2U(SCH_1):PAGE122_I24@PURE_QUANTA.Q_RES(CHIPS)':
 'A': CDS_PINID='A';
NODE_NAME     R4405 1
 '@S9S_MB_2U_LIB.S9S_MB_2U(SCH_1):PAGE122_I27@PURE_QUANTA.Q_RES(CHIPS)':
 'A': CDS_PINID='A';
NODE_NAME     R4412 1
 '@S9S_MB_2U_LIB.S9S_MB_2U(SCH_1):PAGE123_I29@PURE_QUANTA.Q_RES(CHIPS)':
 'A': CDS_PINID='A';
NODE_NAME     R4411 1
 '@S9S_MB_2U_LIB.S9S_MB_2U(SCH_1):PAGE123_I32@PURE_QUANTA.Q_RES(CHIPS)':
 'A': CDS_PINID='A';
NET_NAME
'P3V3_9ZXL045'
 '@S9S_MB_2U_LIB.S9S_MB_2U(SCH_1):P3V3_9ZXL045':
 C_SIGNAL='@s9s_mb_2u_lib.s9s_mb_2u(sch_1):p3v3_9zxl045';
NODE_NAME     R4475 1
 '@S9S_MB_2U_LIB.S9S_MB_2U(SCH_1):PAGE200_I11@PURE_QUANTA.Q_RES(CHIPS)':
 'A': CDS_PINID='A';
NODE_NAME     R4493 1
 '@S9S_MB_2U_LIB.S9S_MB_2U(SCH_1):PAGE200_I4@PURE_QUANTA.Q_RES(CHIPS)':
 'A': CDS_PINID='A';
NODE_NAME     L19 2
 '@S9S_MB_2U_LIB.S9S_MB_2U(SCH_1):PAGE200_I81@PURE_QUANTA.Q_INDUCTOR(CHIPS)':
 '2': CDS_PINID='\2\';
NET_NAME
'P3V3_9ZXL045_VDD'
 '@S9S_MB_2U_LIB.S9S_MB_2U(SCH_1):P3V3_9ZXL045_VDD':
 C_SIGNAL='@s9s_mb_2u_lib.s9s_mb_2u(sch_1):p3v3_9zxl045_vdd',
 CDS_GLOBAL_NET='TRUE';
NODE_NAME     U314 12
 '@S9S_MB_2U_LIB.S9S_MB_2U(SCH_1):PAGE200_I1@PURE_QUANTA.9ZXL0451EKILFT(CHIPS)':
 'VDD0': CDS_PINID='VDD0';
NODE_NAME     U314 16
 '@S9S_MB_2U_LIB.S9S_MB_2U(SCH_1):PAGE200_I1@PURE_QUANTA.9ZXL0451EKILFT(CHIPS)':
 'VDD1': CDS_PINID='VDD1';
NODE_NAME     U314 21
 '@S9S_MB_2U_LIB.S9S_MB_2U(SCH_1):PAGE200_I1@PURE_QUANTA.9ZXL0451EKILFT(CHIPS)':
 'VDD2': CDS_PINID='VDD2';
NODE_NAME     U314 25
 '@S9S_MB_2U_LIB.S9S_MB_2U(SCH_1):PAGE200_I1@PURE_QUANTA.9ZXL0451EKILFT(CHIPS)':
 'VDD3': CDS_PINID='VDD3';
NODE_NAME     U314 29
 '@S9S_MB_2U_LIB.S9S_MB_2U(SCH_1):PAGE200_I1@PURE_QUANTA.9ZXL0451EKILFT(CHIPS)':
 'VDD4': CDS_PINID='VDD4';
NODE_NAME     C2328 1
 '@S9S_MB_2U_LIB.S9S_MB_2U(SCH_1):PAGE200_I17@PURE_QUANTA.Q_CAP(CHIPS)':
 'A': CDS_PINID='A';
NODE_NAME     C2329 1
 '@S9S_MB_2U_LIB.S9S_MB_2U(SCH_1):PAGE200_I54@PURE_QUANTA.Q_CAP(CHIPS)':
 'A': CDS_PINID='A';
NODE_NAME     C2330 1
 '@S9S_MB_2U_LIB.S9S_MB_2U(SCH_1):PAGE200_I55@PURE_QUANTA.Q_CAP(CHIPS)':
 'A': CDS_PINID='A';
NODE_NAME     C2333 1
 '@S9S_MB_2U_LIB.S9S_MB_2U(SCH_1):PAGE200_I56@PURE_QUANTA.Q_CAP(CHIPS)':
 'A': CDS_PINID='A';
NODE_NAME     C2336 1
 '@S9S_MB_2U_LIB.S9S_MB_2U(SCH_1):PAGE200_I57@PURE_QUANTA.Q_CAP(CHIPS)':
 'A': CDS_PINID='A';
NODE_NAME     C2339 1
 '@S9S_MB_2U_LIB.S9S_MB_2U(SCH_1):PAGE200_I71@PURE_QUANTA.Q_CAP(CHIPS)':
 'A': CDS_PINID='A';
NODE_NAME     L20 2
 '@S9S_MB_2U_LIB.S9S_MB_2U(SCH_1):PAGE200_I82@PURE_QUANTA.Q_INDUCTOR(CHIPS)':
 '2': CDS_PINID='\2\';
NET_NAME
'P3V3_9ZXL045_VDDA'
 '@S9S_MB_2U_LIB.S9S_MB_2U(SCH_1):P3V3_9ZXL045_VDDA':
 C_SIGNAL='@s9s_mb_2u_lib.s9s_mb_2u(sch_1):p3v3_9zxl045_vdda',
 CDS_GLOBAL_NET='TRUE';
NODE_NAME     C2331 1
 '@S9S_MB_2U_LIB.S9S_MB_2U(SCH_1):PAGE200_I5@PURE_QUANTA.Q_CAP(CHIPS)':
 'A': CDS_PINID='A';
NODE_NAME     U314 31
 '@S9S_MB_2U_LIB.S9S_MB_2U(SCH_1):PAGE200_I1@PURE_QUANTA.9ZXL0451EKILFT(CHIPS)':
 'VDDA': CDS_PINID='VDDA';
NODE_NAME     R4493 2
 '@S9S_MB_2U_LIB.S9S_MB_2U(SCH_1):PAGE200_I4@PURE_QUANTA.Q_RES(CHIPS)':
 'B': CDS_PINID='B';
NODE_NAME     C2334 1
 '@S9S_MB_2U_LIB.S9S_MB_2U(SCH_1):PAGE200_I58@PURE_QUANTA.Q_CAP(CHIPS)':
 'A': CDS_PINID='A';
NET_NAME
'P3V3_9ZXL045_VDDR'
 '@S9S_MB_2U_LIB.S9S_MB_2U(SCH_1):P3V3_9ZXL045_VDDR':
 C_SIGNAL='@s9s_mb_2u_lib.s9s_mb_2u(sch_1):p3v3_9zxl045_vddr',
 CDS_GLOBAL_NET='TRUE';
NODE_NAME     C2332 1
 '@S9S_MB_2U_LIB.S9S_MB_2U(SCH_1):PAGE200_I10@PURE_QUANTA.Q_CAP(CHIPS)':
 'A': CDS_PINID='A';
NODE_NAME     R4475 2
 '@S9S_MB_2U_LIB.S9S_MB_2U(SCH_1):PAGE200_I11@PURE_QUANTA.Q_RES(CHIPS)':
 'B': CDS_PINID='B';
NODE_NAME     U314 2
 '@S9S_MB_2U_LIB.S9S_MB_2U(SCH_1):PAGE200_I1@PURE_QUANTA.9ZXL0451EKILFT(CHIPS)':
 'VDDR': CDS_PINID='VDDR';
NODE_NAME     C2335 1
 '@S9S_MB_2U_LIB.S9S_MB_2U(SCH_1):PAGE200_I59@PURE_QUANTA.Q_CAP(CHIPS)':
 'A': CDS_PINID='A';
NET_NAME
'P3V3_ADC'
 '@S9S_MB_2U_LIB.S9S_MB_2U(SCH_1):P3V3_ADC':
 C_SIGNAL='@s9s_mb_2u_lib.s9s_mb_2u(sch_1):p3v3_adc';
NODE_NAME     R2908 2
 '@S9S_MB_2U_LIB.S9S_MB_2U(SCH_1):PAGE239_I161@PURE_QUANTA.Q_RES(CHIPS)':
 'B': CDS_PINID='B';
NODE_NAME     R2843 1
 '@S9S_MB_2U_LIB.S9S_MB_2U(SCH_1):PAGE239_I162@PURE_QUANTA.Q_RES(CHIPS)':
 'A': CDS_PINID='A';
NODE_NAME     R3683 1
 '@S9S_MB_2U_LIB.S9S_MB_2U(SCH_1):PAGE239_I199@PURE_QUANTA.Q_RES(CHIPS)':
 'A': CDS_PINID='A';
NODE_NAME     R3684 1
 '@S9S_MB_2U_LIB.S9S_MB_2U(SCH_1):PAGE239_I200@PURE_QUANTA.Q_RES(CHIPS)':
 'A': CDS_PINID='A';
NET_NAME
'P3V3_ADC128_VCC'
 '@S9S_MB_2U_LIB.S9S_MB_2U(SCH_1):P3V3_ADC128_VCC':
 C_SIGNAL='@s9s_mb_2u_lib.s9s_mb_2u(sch_1):p3v3_adc128_vcc';
NODE_NAME     U269 5
 '@S9S_MB_2U_LIB.S9S_MB_2U(SCH_1):PAGE239_I103@PURE_QUANTA.ADC128D818CIMTXNOPB(CHIPS)':
 'V+': CDS_PINID='\v+\';
NODE_NAME     L16 2
 '@S9S_MB_2U_LIB.S9S_MB_2U(SCH_1):PAGE239_I118@PURE_QUANTA.Q_INDUCTOR(CHIPS)':
 '2': CDS_PINID='\2\';
NODE_NAME     C2051 1
 '@S9S_MB_2U_LIB.S9S_MB_2U(SCH_1):PAGE239_I127@PURE_QUANTA.Q_CAP(CHIPS)':
 'A': CDS_PINID='A';
NODE_NAME     C2052 1
 '@S9S_MB_2U_LIB.S9S_MB_2U(SCH_1):PAGE239_I128@PURE_QUANTA.Q_CAP(CHIPS)':
 'A': CDS_PINID='A';
NODE_NAME     R3689 1
 '@S9S_MB_2U_LIB.S9S_MB_2U(SCH_1):PAGE239_I129@PURE_QUANTA.Q_RES(CHIPS)':
 'A': CDS_PINID='A';
NET_NAME
'P3V3_ADC_MAM'
 '@S9S_MB_2U_LIB.S9S_MB_2U(SCH_1):P3V3_ADC_MAM':
 C_SIGNAL='@s9s_mb_2u_lib.s9s_mb_2u(sch_1):p3v3_adc_mam';
NODE_NAME     U193 9
 '@S9S_MB_2U_LIB.S9S_MB_2U(SCH_1):PAGE239_I57@PURE_QUANTA.MAX11617EEET(CHIPS)':
 'AIN4': CDS_PINID='AIN4';
NODE_NAME     C2043 1
 '@S9S_MB_2U_LIB.S9S_MB_2U(SCH_1):PAGE239_I196@PURE_QUANTA.Q_CAP(CHIPS)':
 'A': CDS_PINID='A';
NODE_NAME     R3683 2
 '@S9S_MB_2U_LIB.S9S_MB_2U(SCH_1):PAGE239_I199@PURE_QUANTA.Q_RES(CHIPS)':
 'B': CDS_PINID='B';
NET_NAME
'P3V3_ADC_TIC'
 '@S9S_MB_2U_LIB.S9S_MB_2U(SCH_1):P3V3_ADC_TIC':
 C_SIGNAL='@s9s_mb_2u_lib.s9s_mb_2u(sch_1):p3v3_adc_tic';
NODE_NAME     U269 12
 '@S9S_MB_2U_LIB.S9S_MB_2U(SCH_1):PAGE239_I103@PURE_QUANTA.ADC128D818CIMTXNOPB(CHIPS)':
 'IN4': CDS_PINID='IN4';
NODE_NAME     C2048 1
 '@S9S_MB_2U_LIB.S9S_MB_2U(SCH_1):PAGE239_I197@PURE_QUANTA.Q_CAP(CHIPS)':
 'A': CDS_PINID='A';
NODE_NAME     R3684 2
 '@S9S_MB_2U_LIB.S9S_MB_2U(SCH_1):PAGE239_I200@PURE_QUANTA.Q_RES(CHIPS)':
 'B': CDS_PINID='B';
NET_NAME
'P3V3_AUX'
 '@S9S_MB_2U_LIB.S9S_MB_2U(SCH_1):P3V3_AUX':
 C_SIGNAL='@s9s_mb_2u_lib.s9s_mb_2u(sch_1):p3v3_aux',
 PHYS_NET_NAME='P3V3_AUX',
 CDS_GLOBAL_NET='TRUE';
NODE_NAME     U2 BC21
 '@S9S_MB_2U_LIB.S9S_MB_2U(SCH_1):PAGE37_I8@PURE_QUANTA.SOCKET4677_AZIF0045P001C01CS(CHIPS)':
 'VCC_3P3_AUX0': CDS_PINID='VCC_3P3_AUX0';
NODE_NAME     U2 BA21
 '@S9S_MB_2U_LIB.S9S_MB_2U(SCH_1):PAGE37_I8@PURE_QUANTA.SOCKET4677_AZIF0045P001C01CS(CHIPS)':
 'VCC_3P3_AUX1': CDS_PINID='VCC_3P3_AUX1';
NODE_NAME     C1 1
 '@S9S_MB_2U_LIB.S9S_MB_2U(SCH_1):PAGE37_I15@PURE_QUANTA.Q_CAP(CHIPS)':
 'A': CDS_PINID='A';
NODE_NAME     C71 1
 '@S9S_MB_2U_LIB.S9S_MB_2U(SCH_1):PAGE68_I4@PURE_QUANTA.Q_CAP(CHIPS)':
 'A': CDS_PINID='A';
NODE_NAME     U1 BC21
 '@S9S_MB_2U_LIB.S9S_MB_2U(SCH_1):PAGE68_I8@PURE_QUANTA.SOCKET4677_AZIF0045P001C01CS(CHIPS)':
 'VCC_3P3_AUX0': CDS_PINID='VCC_3P3_AUX0';
NODE_NAME     U1 BA21
 '@S9S_MB_2U_LIB.S9S_MB_2U(SCH_1):PAGE68_I8@PURE_QUANTA.SOCKET4677_AZIF0045P001C01CS(CHIPS)':
 'VCC_3P3_AUX1': CDS_PINID='VCC_3P3_AUX1';
NODE_NAME     R319 1
 '@S9S_MB_2U_LIB.S9S_MB_2U(SCH_1):PAGE80_I8@PURE_QUANTA.Q_RES(CHIPS)':
 'A': CDS_PINID='A';
NODE_NAME     C2 1
 '@S9S_MB_2U_LIB.S9S_MB_2U(SCH_1):PAGE82_I192@PURE_QUANTA.Q_CAP(CHIPS)':
 'A': CDS_PINID='A';
NODE_NAME     J1 3
 '@S9S_MB_2U_LIB.S9S_MB_2U(SCH_1):PAGE82_I198@PURE_QUANTA.SCONN288_ADR50017P130CC(CHIPS)':
 'VIN_MGMT': CDS_PINID='VIN_MGMT';
NODE_NAME     C5 1
 '@S9S_MB_2U_LIB.S9S_MB_2U(SCH_1):PAGE83_I120@PURE_QUANTA.Q_CAP(CHIPS)':
 'A': CDS_PINID='A';
NODE_NAME     J2 3
 '@S9S_MB_2U_LIB.S9S_MB_2U(SCH_1):PAGE83_I177@PURE_QUANTA.SCONN288_ADR50017P087CC(CHIPS)':
 'VIN_MGMT': CDS_PINID='VIN_MGMT';
NODE_NAME     C8 1
 '@S9S_MB_2U_LIB.S9S_MB_2U(SCH_1):PAGE84_I121@PURE_QUANTA.Q_CAP(CHIPS)':
 'A': CDS_PINID='A';
NODE_NAME     J4 3
 '@S9S_MB_2U_LIB.S9S_MB_2U(SCH_1):PAGE85_I23@PURE_QUANTA.SCONN288_ADR50017P087CC(CHIPS)':
 'VIN_MGMT': CDS_PINID='VIN_MGMT';
NODE_NAME     C11 1
 '@S9S_MB_2U_LIB.S9S_MB_2U(SCH_1):PAGE85_I121@PURE_QUANTA.Q_CAP(CHIPS)':
 'A': CDS_PINID='A';
NODE_NAME     J5 3
 '@S9S_MB_2U_LIB.S9S_MB_2U(SCH_1):PAGE86_I24@PURE_QUANTA.SCONN288_ADR50017P130CC(CHIPS)':
 'VIN_MGMT': CDS_PINID='VIN_MGMT';
NODE_NAME     C14 1
 '@S9S_MB_2U_LIB.S9S_MB_2U(SCH_1):PAGE86_I120@PURE_QUANTA.Q_CAP(CHIPS)':
 'A': CDS_PINID='A';
NODE_NAME     J6 3
 '@S9S_MB_2U_LIB.S9S_MB_2U(SCH_1):PAGE87_I46@PURE_QUANTA.SCONN288_ADR50017P087CC(CHIPS)':
 'VIN_MGMT': CDS_PINID='VIN_MGMT';
NODE_NAME     C17 1
 '@S9S_MB_2U_LIB.S9S_MB_2U(SCH_1):PAGE87_I120@PURE_QUANTA.Q_CAP(CHIPS)':
 'A': CDS_PINID='A';
NODE_NAME     J7 3
 '@S9S_MB_2U_LIB.S9S_MB_2U(SCH_1):PAGE88_I12@PURE_QUANTA.SCONN288_ADR50017P130CC(CHIPS)':
 'VIN_MGMT': CDS_PINID='VIN_MGMT';
NODE_NAME     C20 1
 '@S9S_MB_2U_LIB.S9S_MB_2U(SCH_1):PAGE88_I123@PURE_QUANTA.Q_CAP(CHIPS)':
 'A': CDS_PINID='A';
NODE_NAME     J8 3
 '@S9S_MB_2U_LIB.S9S_MB_2U(SCH_1):PAGE89_I50@PURE_QUANTA.SCONN288_ADR50017P087CC(CHIPS)':
 'VIN_MGMT': CDS_PINID='VIN_MGMT';
NODE_NAME     C23 1
 '@S9S_MB_2U_LIB.S9S_MB_2U(SCH_1):PAGE89_I121@PURE_QUANTA.Q_CAP(CHIPS)':
 'A': CDS_PINID='A';
NODE_NAME     J9 3
 '@S9S_MB_2U_LIB.S9S_MB_2U(SCH_1):PAGE90_I12@PURE_QUANTA.SCONN288_ADR50017P130CC(CHIPS)':
 'VIN_MGMT': CDS_PINID='VIN_MGMT';
NODE_NAME     C26 1
 '@S9S_MB_2U_LIB.S9S_MB_2U(SCH_1):PAGE90_I122@PURE_QUANTA.Q_CAP(CHIPS)':
 'A': CDS_PINID='A';
NODE_NAME     J10 3
 '@S9S_MB_2U_LIB.S9S_MB_2U(SCH_1):PAGE91_I13@PURE_QUANTA.SCONN288_ADR50017P087CC(CHIPS)':
 'VIN_MGMT': CDS_PINID='VIN_MGMT';
NODE_NAME     C29 1
 '@S9S_MB_2U_LIB.S9S_MB_2U(SCH_1):PAGE91_I123@PURE_QUANTA.Q_CAP(CHIPS)':
 'A': CDS_PINID='A';
NODE_NAME     J11 3
 '@S9S_MB_2U_LIB.S9S_MB_2U(SCH_1):PAGE92_I25@PURE_QUANTA.SCONN288_ADR50017P130CC(CHIPS)':
 'VIN_MGMT': CDS_PINID='VIN_MGMT';
NODE_NAME     C32 1
 '@S9S_MB_2U_LIB.S9S_MB_2U(SCH_1):PAGE92_I122@PURE_QUANTA.Q_CAP(CHIPS)':
 'A': CDS_PINID='A';
NODE_NAME     J12 3
 '@S9S_MB_2U_LIB.S9S_MB_2U(SCH_1):PAGE93_I24@PURE_QUANTA.SCONN288_ADR50017P087CC(CHIPS)':
 'VIN_MGMT': CDS_PINID='VIN_MGMT';
NODE_NAME     C35 1
 '@S9S_MB_2U_LIB.S9S_MB_2U(SCH_1):PAGE93_I122@PURE_QUANTA.Q_CAP(CHIPS)':
 'A': CDS_PINID='A';
NODE_NAME     J13 3
 '@S9S_MB_2U_LIB.S9S_MB_2U(SCH_1):PAGE94_I11@PURE_QUANTA.SCONN288_ADR50017P130CC(CHIPS)':
 'VIN_MGMT': CDS_PINID='VIN_MGMT';
NODE_NAME     C38 1
 '@S9S_MB_2U_LIB.S9S_MB_2U(SCH_1):PAGE94_I123@PURE_QUANTA.Q_CAP(CHIPS)':
 'A': CDS_PINID='A';
NODE_NAME     J14 3
 '@S9S_MB_2U_LIB.S9S_MB_2U(SCH_1):PAGE95_I47@PURE_QUANTA.SCONN288_ADR50017P087CC(CHIPS)':
 'VIN_MGMT': CDS_PINID='VIN_MGMT';
NODE_NAME     C41 1
 '@S9S_MB_2U_LIB.S9S_MB_2U(SCH_1):PAGE95_I121@PURE_QUANTA.Q_CAP(CHIPS)':
 'A': CDS_PINID='A';
NODE_NAME     J15 3
 '@S9S_MB_2U_LIB.S9S_MB_2U(SCH_1):PAGE96_I48@PURE_QUANTA.SCONN288_ADR50017P130CC(CHIPS)':
 'VIN_MGMT': CDS_PINID='VIN_MGMT';
NODE_NAME     C44 1
 '@S9S_MB_2U_LIB.S9S_MB_2U(SCH_1):PAGE96_I121@PURE_QUANTA.Q_CAP(CHIPS)':
 'A': CDS_PINID='A';
NODE_NAME     J16 3
 '@S9S_MB_2U_LIB.S9S_MB_2U(SCH_1):PAGE97_I6@PURE_QUANTA.SCONN288_ADR50017P087CC(CHIPS)':
 'VIN_MGMT': CDS_PINID='VIN_MGMT';
NODE_NAME     C47 1
 '@S9S_MB_2U_LIB.S9S_MB_2U(SCH_1):PAGE97_I56@PURE_QUANTA.Q_CAP(CHIPS)':
 'A': CDS_PINID='A';
NODE_NAME     J17 3
 '@S9S_MB_2U_LIB.S9S_MB_2U(SCH_1):PAGE98_I12@PURE_QUANTA.SCONN288_ADR50017P130CC(CHIPS)':
 'VIN_MGMT': CDS_PINID='VIN_MGMT';
NODE_NAME     C50 1
 '@S9S_MB_2U_LIB.S9S_MB_2U(SCH_1):PAGE98_I122@PURE_QUANTA.Q_CAP(CHIPS)':
 'A': CDS_PINID='A';
NODE_NAME     J18 3
 '@S9S_MB_2U_LIB.S9S_MB_2U(SCH_1):PAGE99_I24@PURE_QUANTA.SCONN288_ADR50017P087CC(CHIPS)':
 'VIN_MGMT': CDS_PINID='VIN_MGMT';
NODE_NAME     C53 1
 '@S9S_MB_2U_LIB.S9S_MB_2U(SCH_1):PAGE99_I122@PURE_QUANTA.Q_CAP(CHIPS)':
 'A': CDS_PINID='A';
NODE_NAME     J19 3
 '@S9S_MB_2U_LIB.S9S_MB_2U(SCH_1):PAGE100_I25@PURE_QUANTA.SCONN288_ADR50017P130CC(CHIPS)':
 'VIN_MGMT': CDS_PINID='VIN_MGMT';
NODE_NAME     C56 1
 '@S9S_MB_2U_LIB.S9S_MB_2U(SCH_1):PAGE100_I121@PURE_QUANTA.Q_CAP(CHIPS)':
 'A': CDS_PINID='A';
NODE_NAME     J20 3
 '@S9S_MB_2U_LIB.S9S_MB_2U(SCH_1):PAGE101_I47@PURE_QUANTA.SCONN288_ADR50017P087CC(CHIPS)':
 'VIN_MGMT': CDS_PINID='VIN_MGMT';
NODE_NAME     C59 1
 '@S9S_MB_2U_LIB.S9S_MB_2U(SCH_1):PAGE101_I121@PURE_QUANTA.Q_CAP(CHIPS)':
 'A': CDS_PINID='A';
NODE_NAME     J21 3
 '@S9S_MB_2U_LIB.S9S_MB_2U(SCH_1):PAGE102_I13@PURE_QUANTA.SCONN288_ADR50017P130CC(CHIPS)':
 'VIN_MGMT': CDS_PINID='VIN_MGMT';
NODE_NAME     C62 1
 '@S9S_MB_2U_LIB.S9S_MB_2U(SCH_1):PAGE102_I124@PURE_QUANTA.Q_CAP(CHIPS)':
 'A': CDS_PINID='A';
NODE_NAME     J22 3
 '@S9S_MB_2U_LIB.S9S_MB_2U(SCH_1):PAGE103_I51@PURE_QUANTA.SCONN288_ADR50017P087CC(CHIPS)':
 'VIN_MGMT': CDS_PINID='VIN_MGMT';
NODE_NAME     C65 1
 '@S9S_MB_2U_LIB.S9S_MB_2U(SCH_1):PAGE103_I122@PURE_QUANTA.Q_CAP(CHIPS)':
 'A': CDS_PINID='A';
NODE_NAME     J23 3
 '@S9S_MB_2U_LIB.S9S_MB_2U(SCH_1):PAGE104_I25@PURE_QUANTA.SCONN288_ADR50017P130CC(CHIPS)':
 'VIN_MGMT': CDS_PINID='VIN_MGMT';
NODE_NAME     C68 1
 '@S9S_MB_2U_LIB.S9S_MB_2U(SCH_1):PAGE104_I122@PURE_QUANTA.Q_CAP(CHIPS)':
 'A': CDS_PINID='A';
NODE_NAME     C96 1
 '@S9S_MB_2U_LIB.S9S_MB_2U(SCH_1):PAGE105_I123@PURE_QUANTA.Q_CAP(CHIPS)':
 'A': CDS_PINID='A';
NODE_NAME     J24 3
 '@S9S_MB_2U_LIB.S9S_MB_2U(SCH_1):PAGE105_I178@PURE_QUANTA.SCONN288_ADR50017P087CC(CHIPS)':
 'VIN_MGMT': CDS_PINID='VIN_MGMT';
NODE_NAME     C93 1
 '@S9S_MB_2U_LIB.S9S_MB_2U(SCH_1):PAGE106_I122@PURE_QUANTA.Q_CAP(CHIPS)':
 'A': CDS_PINID='A';
NODE_NAME     J25 3
 '@S9S_MB_2U_LIB.S9S_MB_2U(SCH_1):PAGE106_I180@PURE_QUANTA.SCONN288_ADR50017P130CC(CHIPS)':
 'VIN_MGMT': CDS_PINID='VIN_MGMT';
NODE_NAME     C90 1
 '@S9S_MB_2U_LIB.S9S_MB_2U(SCH_1):PAGE107_I122@PURE_QUANTA.Q_CAP(CHIPS)':
 'A': CDS_PINID='A';
NODE_NAME     J26 3
 '@S9S_MB_2U_LIB.S9S_MB_2U(SCH_1):PAGE107_I180@PURE_QUANTA.SCONN288_ADR50017P087CC(CHIPS)':
 'VIN_MGMT': CDS_PINID='VIN_MGMT';
NODE_NAME     C87 1
 '@S9S_MB_2U_LIB.S9S_MB_2U(SCH_1):PAGE108_I121@PURE_QUANTA.Q_CAP(CHIPS)':
 'A': CDS_PINID='A';
NODE_NAME     J27 3
 '@S9S_MB_2U_LIB.S9S_MB_2U(SCH_1):PAGE108_I179@PURE_QUANTA.SCONN288_ADR50017P130CC(CHIPS)':
 'VIN_MGMT': CDS_PINID='VIN_MGMT';
NODE_NAME     J28 3
 '@S9S_MB_2U_LIB.S9S_MB_2U(SCH_1):PAGE109_I47@PURE_QUANTA.SCONN288_ADR50017P087CC(CHIPS)':
 'VIN_MGMT': CDS_PINID='VIN_MGMT';
NODE_NAME     C84 1
 '@S9S_MB_2U_LIB.S9S_MB_2U(SCH_1):PAGE109_I121@PURE_QUANTA.Q_CAP(CHIPS)':
 'A': CDS_PINID='A';
NODE_NAME     C81 1
 '@S9S_MB_2U_LIB.S9S_MB_2U(SCH_1):PAGE110_I120@PURE_QUANTA.Q_CAP(CHIPS)':
 'A': CDS_PINID='A';
NODE_NAME     J29 3
 '@S9S_MB_2U_LIB.S9S_MB_2U(SCH_1):PAGE110_I179@PURE_QUANTA.SCONN288_ADR50017P130CC(CHIPS)':
 'VIN_MGMT': CDS_PINID='VIN_MGMT';
NODE_NAME     C78 1
 '@S9S_MB_2U_LIB.S9S_MB_2U(SCH_1):PAGE111_I54@PURE_QUANTA.Q_CAP(CHIPS)':
 'A': CDS_PINID='A';
NODE_NAME     J30 3
 '@S9S_MB_2U_LIB.S9S_MB_2U(SCH_1):PAGE111_I179@PURE_QUANTA.SCONN288_ADR50017P087CC(CHIPS)':
 'VIN_MGMT': CDS_PINID='VIN_MGMT';
NODE_NAME     C75 1
 '@S9S_MB_2U_LIB.S9S_MB_2U(SCH_1):PAGE112_I124@PURE_QUANTA.Q_CAP(CHIPS)':
 'A': CDS_PINID='A';
NODE_NAME     J31 3
 '@S9S_MB_2U_LIB.S9S_MB_2U(SCH_1):PAGE112_I180@PURE_QUANTA.SCONN288_ADR50017P130CC(CHIPS)':
 'VIN_MGMT': CDS_PINID='VIN_MGMT';
NODE_NAME     C72 1
 '@S9S_MB_2U_LIB.S9S_MB_2U(SCH_1):PAGE113_I116@PURE_QUANTA.Q_CAP(CHIPS)':
 'A': CDS_PINID='A';
NODE_NAME     J32 3
 '@S9S_MB_2U_LIB.S9S_MB_2U(SCH_1):PAGE113_I179@PURE_QUANTA.SCONN288_ADR50017P087CC(CHIPS)':
 'VIN_MGMT': CDS_PINID='VIN_MGMT';
NODE_NAME     R274 1
 '@S9S_MB_2U_LIB.S9S_MB_2U(SCH_1):PAGE119_I88@PURE_QUANTA.Q_RES(CHIPS)':
 'A': CDS_PINID='A';
NODE_NAME     R273 1
 '@S9S_MB_2U_LIB.S9S_MB_2U(SCH_1):PAGE119_I89@PURE_QUANTA.Q_RES(CHIPS)':
 'A': CDS_PINID='A';
NODE_NAME     R272 1
 '@S9S_MB_2U_LIB.S9S_MB_2U(SCH_1):PAGE119_I90@PURE_QUANTA.Q_RES(CHIPS)':
 'A': CDS_PINID='A';
NODE_NAME     R271 1
 '@S9S_MB_2U_LIB.S9S_MB_2U(SCH_1):PAGE119_I92@PURE_QUANTA.Q_RES(CHIPS)':
 'A': CDS_PINID='A';
NODE_NAME     R270 1
 '@S9S_MB_2U_LIB.S9S_MB_2U(SCH_1):PAGE119_I93@PURE_QUANTA.Q_RES(CHIPS)':
 'A': CDS_PINID='A';
NODE_NAME     R283 1
 '@S9S_MB_2U_LIB.S9S_MB_2U(SCH_1):PAGE119_I147@PURE_QUANTA.Q_RES(CHIPS)':
 'A': CDS_PINID='A';
NODE_NAME     R284 1
 '@S9S_MB_2U_LIB.S9S_MB_2U(SCH_1):PAGE119_I148@PURE_QUANTA.Q_RES(CHIPS)':
 'A': CDS_PINID='A';
NODE_NAME     R285 1
 '@S9S_MB_2U_LIB.S9S_MB_2U(SCH_1):PAGE119_I150@PURE_QUANTA.Q_RES(CHIPS)':
 'A': CDS_PINID='A';
NODE_NAME     R286 1
 '@S9S_MB_2U_LIB.S9S_MB_2U(SCH_1):PAGE119_I151@PURE_QUANTA.Q_RES(CHIPS)':
 'A': CDS_PINID='A';
NODE_NAME     R287 1
 '@S9S_MB_2U_LIB.S9S_MB_2U(SCH_1):PAGE119_I152@PURE_QUANTA.Q_RES(CHIPS)':
 'A': CDS_PINID='A';
NODE_NAME     R335 1
 '@S9S_MB_2U_LIB.S9S_MB_2U(SCH_1):PAGE127_I5@PURE_QUANTA.Q_RES(CHIPS)':
 'A': CDS_PINID='A';
NODE_NAME     R333 1
 '@S9S_MB_2U_LIB.S9S_MB_2U(SCH_1):PAGE127_I6@PURE_QUANTA.Q_RES(CHIPS)':
 'A': CDS_PINID='A';
NODE_NAME     R629 1
 '@S9S_MB_2U_LIB.S9S_MB_2U(SCH_1):PAGE127_I13@PURE_QUANTA.Q_RES(CHIPS)':
 'A': CDS_PINID='A';
NODE_NAME     R627 1
 '@S9S_MB_2U_LIB.S9S_MB_2U(SCH_1):PAGE127_I14@PURE_QUANTA.Q_RES(CHIPS)':
 'A': CDS_PINID='A';
NODE_NAME     R331 1
 '@S9S_MB_2U_LIB.S9S_MB_2U(SCH_1):PAGE127_I20@PURE_QUANTA.Q_RES(CHIPS)':
 'A': CDS_PINID='A';
NODE_NAME     R625 1
 '@S9S_MB_2U_LIB.S9S_MB_2U(SCH_1):PAGE127_I24@PURE_QUANTA.Q_RES(CHIPS)':
 'A': CDS_PINID='A';
NODE_NAME     R650 1
 '@S9S_MB_2U_LIB.S9S_MB_2U(SCH_1):PAGE127_I32@PURE_QUANTA.Q_RES(CHIPS)':
 'A': CDS_PINID='A';
NODE_NAME     R1004 1
 '@S9S_MB_2U_LIB.S9S_MB_2U(SCH_1):PAGE127_I35@PURE_QUANTA.Q_RES(CHIPS)':
 'A': CDS_PINID='A';
NODE_NAME     R778 1
 '@S9S_MB_2U_LIB.S9S_MB_2U(SCH_1):PAGE133_I15@PURE_QUANTA.Q_RES(CHIPS)':
 'A': CDS_PINID='A';
NODE_NAME     J42 52
 '@S9S_MB_2U_LIB.S9S_MB_2U(SCH_1):PAGE133_I44@PURE_QUANTA.SCONN60_ASP21410801(CHIPS)':
 '52': CDS_PINID='\52\';
NODE_NAME     C551 1
 '@S9S_MB_2U_LIB.S9S_MB_2U(SCH_1):PAGE133_I105@PURE_QUANTA.Q_CAP(CHIPS)':
 'A': CDS_PINID='A';
NODE_NAME     R766 1
 '@S9S_MB_2U_LIB.S9S_MB_2U(SCH_1):PAGE133_I111@PURE_QUANTA.Q_RES(CHIPS)':
 'A': CDS_PINID='A';
NODE_NAME     R768 1
 '@S9S_MB_2U_LIB.S9S_MB_2U(SCH_1):PAGE133_I112@PURE_QUANTA.Q_RES(CHIPS)':
 'A': CDS_PINID='A';
NODE_NAME     R767 1
 '@S9S_MB_2U_LIB.S9S_MB_2U(SCH_1):PAGE133_I113@PURE_QUANTA.Q_RES(CHIPS)':
 'A': CDS_PINID='A';
NODE_NAME     U17 14
 '@S9S_MB_2U_LIB.S9S_MB_2U(SCH_1):PAGE134_I80@PURE_QUANTA.74CBTLV3126PW(CHIPS)':
 'VCC': CDS_PINID='VCC';
NODE_NAME     C545 1
 '@S9S_MB_2U_LIB.S9S_MB_2U(SCH_1):PAGE134_I93@PURE_QUANTA.Q_CAP(CHIPS)':
 'A': CDS_PINID='A';
NODE_NAME     U18 14
 '@S9S_MB_2U_LIB.S9S_MB_2U(SCH_1):PAGE134_I129@PURE_QUANTA.74CBTLV3126PW(CHIPS)':
 'VCC': CDS_PINID='VCC';
NODE_NAME     C546 1
 '@S9S_MB_2U_LIB.S9S_MB_2U(SCH_1):PAGE134_I135@PURE_QUANTA.Q_CAP(CHIPS)':
 'A': CDS_PINID='A';
NODE_NAME     U21 5
 '@S9S_MB_2U_LIB.S9S_MB_2U(SCH_1):PAGE135_I58@PURE_QUANTA.NC7SB3157(CHIPS)':
 'VCC': CDS_PINID='VCC';
NODE_NAME     C541 1
 '@S9S_MB_2U_LIB.S9S_MB_2U(SCH_1):PAGE135_I61@PURE_QUANTA.Q_CAP(CHIPS)':
 'A': CDS_PINID='A';
NODE_NAME     C539 1
 '@S9S_MB_2U_LIB.S9S_MB_2U(SCH_1):PAGE135_I70@PURE_QUANTA.Q_CAP(CHIPS)':
 'A': CDS_PINID='A';
NODE_NAME     U22 5
 '@S9S_MB_2U_LIB.S9S_MB_2U(SCH_1):PAGE135_I71@PURE_QUANTA.NC7SB3157(CHIPS)':
 'VCC': CDS_PINID='VCC';
NODE_NAME     C542 1
 '@S9S_MB_2U_LIB.S9S_MB_2U(SCH_1):PAGE135_I80@PURE_QUANTA.Q_CAP(CHIPS)':
 'A': CDS_PINID='A';
NODE_NAME     C540 1
 '@S9S_MB_2U_LIB.S9S_MB_2U(SCH_1):PAGE135_I81@PURE_QUANTA.Q_CAP(CHIPS)':
 'A': CDS_PINID='A';
NODE_NAME     C544 1
 '@S9S_MB_2U_LIB.S9S_MB_2U(SCH_1):PAGE135_I94@PURE_QUANTA.Q_CAP(CHIPS)':
 'A': CDS_PINID='A';
NODE_NAME     U23 5
 '@S9S_MB_2U_LIB.S9S_MB_2U(SCH_1):PAGE135_I96@PURE_QUANTA.74LVC1G02GW(CHIPS)':
 'VCC': CDS_PINID='VCC';
NODE_NAME     C543 1
 '@S9S_MB_2U_LIB.S9S_MB_2U(SCH_1):PAGE135_I100@PURE_QUANTA.Q_CAP(CHIPS)':
 'A': CDS_PINID='A';
NODE_NAME     R740 1
 '@S9S_MB_2U_LIB.S9S_MB_2U(SCH_1):PAGE135_I107@PURE_QUANTA.Q_RES(CHIPS)':
 'A': CDS_PINID='A';
NODE_NAME     R739 1
 '@S9S_MB_2U_LIB.S9S_MB_2U(SCH_1):PAGE135_I109@PURE_QUANTA.Q_RES(CHIPS)':
 'A': CDS_PINID='A';
NODE_NAME     U86 14
 '@S9S_MB_2U_LIB.S9S_MB_2U(SCH_1):PAGE137_I84@PURE_QUANTA.74CBTLV3126PW(CHIPS)':
 'VCC': CDS_PINID='VCC';
NODE_NAME     C1292 1
 '@S9S_MB_2U_LIB.S9S_MB_2U(SCH_1):PAGE137_I90@PURE_QUANTA.Q_CAP(CHIPS)':
 'A': CDS_PINID='A';
NODE_NAME     R1370 1
 '@S9S_MB_2U_LIB.S9S_MB_2U(SCH_1):PAGE137_I98@PURE_QUANTA.Q_RES(CHIPS)':
 'A': CDS_PINID='A';
NODE_NAME     U85 5
 '@S9S_MB_2U_LIB.S9S_MB_2U(SCH_1):PAGE137_I109@PURE_QUANTA.NC7SB3157(CHIPS)':
 'VCC': CDS_PINID='VCC';
NODE_NAME     C1289 1
 '@S9S_MB_2U_LIB.S9S_MB_2U(SCH_1):PAGE137_I110@PURE_QUANTA.Q_CAP(CHIPS)':
 'A': CDS_PINID='A';
NODE_NAME     C1288 1
 '@S9S_MB_2U_LIB.S9S_MB_2U(SCH_1):PAGE137_I112@PURE_QUANTA.Q_CAP(CHIPS)':
 'A': CDS_PINID='A';
NODE_NAME     U75 5
 '@S9S_MB_2U_LIB.S9S_MB_2U(SCH_1):PAGE152_I1@PURE_QUANTA.74LVC1G17GW(CHIPS)':
 'VCC': CDS_PINID='VCC';
NODE_NAME     C1173 1
 '@S9S_MB_2U_LIB.S9S_MB_2U(SCH_1):PAGE152_I4@PURE_QUANTA.Q_CAP(CHIPS)':
 'A': CDS_PINID='A';
NODE_NAME     C1175 1
 '@S9S_MB_2U_LIB.S9S_MB_2U(SCH_1):PAGE152_I24@PURE_QUANTA.Q_CAP(CHIPS)':
 'A': CDS_PINID='A';
NODE_NAME     R1593 1
 '@S9S_MB_2U_LIB.S9S_MB_2U(SCH_1):PAGE152_I42@PURE_QUANTA.Q_RES(CHIPS)':
 'A': CDS_PINID='A';
NODE_NAME     C188 1
 '@S9S_MB_2U_LIB.S9S_MB_2U(SCH_1):PAGE152_I44@PURE_QUANTA.Q_CAP(CHIPS)':
 'A': CDS_PINID='A';
NODE_NAME     U90 6
 '@S9S_MB_2U_LIB.S9S_MB_2U(SCH_1):PAGE152_I46@PURE_QUANTA.PI6CV304LE(CHIPS)':
 'VDD': CDS_PINID='VDD';
NODE_NAME     C1275 1
 '@S9S_MB_2U_LIB.S9S_MB_2U(SCH_1):PAGE152_I49@PURE_QUANTA.Q_CAP(CHIPS)':
 'A': CDS_PINID='A';
NODE_NAME     C1274 1
 '@S9S_MB_2U_LIB.S9S_MB_2U(SCH_1):PAGE152_I59@PURE_QUANTA.Q_CAP(CHIPS)':
 'A': CDS_PINID='A';
NODE_NAME     R1138 1
 '@S9S_MB_2U_LIB.S9S_MB_2U(SCH_1):PAGE152_I61@PURE_QUANTA.Q_RES(CHIPS)':
 'A': CDS_PINID='A';
NODE_NAME     U104 5
 '@S9S_MB_2U_LIB.S9S_MB_2U(SCH_1):PAGE152_I63@PURE_QUANTA.74LVC1G07GV(CHIPS)':
 'VCC': CDS_PINID='VCC';
NODE_NAME     U157 5
 '@S9S_MB_2U_LIB.S9S_MB_2U(SCH_1):PAGE152_I65@PURE_QUANTA.74LVC1G07GV(CHIPS)':
 'VCC': CDS_PINID='VCC';
NODE_NAME     C1663 1
 '@S9S_MB_2U_LIB.S9S_MB_2U(SCH_1):PAGE152_I68@PURE_QUANTA.Q_CAP(CHIPS)':
 'A': CDS_PINID='A';
NODE_NAME     R2487 1
 '@S9S_MB_2U_LIB.S9S_MB_2U(SCH_1):PAGE152_I71@PURE_QUANTA.Q_RES(CHIPS)':
 'A': CDS_PINID='A';
NODE_NAME     R2488 1
 '@S9S_MB_2U_LIB.S9S_MB_2U(SCH_1):PAGE152_I74@PURE_QUANTA.Q_RES(CHIPS)':
 'A': CDS_PINID='A';
NODE_NAME     R1127 1
 '@S9S_MB_2U_LIB.S9S_MB_2U(SCH_1):PAGE154_I133@PURE_QUANTA.Q_RES(CHIPS)':
 'A': CDS_PINID='A';
NODE_NAME     R3037 1
 '@S9S_MB_2U_LIB.S9S_MB_2U(SCH_1):PAGE154_I134@PURE_QUANTA.Q_RES(CHIPS)':
 'A': CDS_PINID='A';
NODE_NAME     R1123 1
 '@S9S_MB_2U_LIB.S9S_MB_2U(SCH_1):PAGE154_I142@PURE_QUANTA.Q_RES(CHIPS)':
 'A': CDS_PINID='A';
NODE_NAME     C581 1
 '@S9S_MB_2U_LIB.S9S_MB_2U(SCH_1):PAGE154_I148@PURE_QUANTA.Q_CAP(CHIPS)':
 'A': CDS_PINID='A';
NODE_NAME     C578 1
 '@S9S_MB_2U_LIB.S9S_MB_2U(SCH_1):PAGE154_I169@PURE_QUANTA.Q_CAP(CHIPS)':
 'A': CDS_PINID='A';
NODE_NAME     R1129 1
 '@S9S_MB_2U_LIB.S9S_MB_2U(SCH_1):PAGE154_I172@PURE_QUANTA.Q_RES(CHIPS)':
 'A': CDS_PINID='A';
NODE_NAME     R1198 1
 '@S9S_MB_2U_LIB.S9S_MB_2U(SCH_1):PAGE174_I48@PURE_QUANTA.Q_RES(CHIPS)':
 'A': CDS_PINID='A';
NODE_NAME     R696 1
 '@S9S_MB_2U_LIB.S9S_MB_2U(SCH_1):PAGE174_I63@PURE_QUANTA.Q_RES(CHIPS)':
 'A': CDS_PINID='A';
NODE_NAME     R453 1
 '@S9S_MB_2U_LIB.S9S_MB_2U(SCH_1):PAGE174_I77@PURE_QUANTA.Q_RES(CHIPS)':
 'A': CDS_PINID='A';
NODE_NAME     R1675 2
 '@S9S_MB_2U_LIB.S9S_MB_2U(SCH_1):PAGE174_I82@PURE_QUANTA.Q_RES(CHIPS)':
 'B': CDS_PINID='B';
NODE_NAME     R1451 2
 '@S9S_MB_2U_LIB.S9S_MB_2U(SCH_1):PAGE175_I109@PURE_QUANTA.Q_RES(CHIPS)':
 'B': CDS_PINID='B';
NODE_NAME     R1452 2
 '@S9S_MB_2U_LIB.S9S_MB_2U(SCH_1):PAGE175_I112@PURE_QUANTA.Q_RES(CHIPS)':
 'B': CDS_PINID='B';
NODE_NAME     R1453 2
 '@S9S_MB_2U_LIB.S9S_MB_2U(SCH_1):PAGE175_I120@PURE_QUANTA.Q_RES(CHIPS)':
 'B': CDS_PINID='B';
NODE_NAME     R1454 2
 '@S9S_MB_2U_LIB.S9S_MB_2U(SCH_1):PAGE175_I121@PURE_QUANTA.Q_RES(CHIPS)':
 'B': CDS_PINID='B';
NODE_NAME     R1545 2
 '@S9S_MB_2U_LIB.S9S_MB_2U(SCH_1):PAGE175_I137@PURE_QUANTA.Q_RES(CHIPS)':
 'B': CDS_PINID='B';
NODE_NAME     R1546 2
 '@S9S_MB_2U_LIB.S9S_MB_2U(SCH_1):PAGE175_I138@PURE_QUANTA.Q_RES(CHIPS)':
 'B': CDS_PINID='B';
NODE_NAME     R1582 2
 '@S9S_MB_2U_LIB.S9S_MB_2U(SCH_1):PAGE175_I141@PURE_QUANTA.Q_RES(CHIPS)':
 'B': CDS_PINID='B';
NODE_NAME     R1581 2
 '@S9S_MB_2U_LIB.S9S_MB_2U(SCH_1):PAGE175_I142@PURE_QUANTA.Q_RES(CHIPS)':
 'B': CDS_PINID='B';
NODE_NAME     R1583 2
 '@S9S_MB_2U_LIB.S9S_MB_2U(SCH_1):PAGE175_I144@PURE_QUANTA.Q_RES(CHIPS)':
 'B': CDS_PINID='B';
NODE_NAME     R1601 2
 '@S9S_MB_2U_LIB.S9S_MB_2U(SCH_1):PAGE175_I151@PURE_QUANTA.Q_RES(CHIPS)':
 'B': CDS_PINID='B';
NODE_NAME     R1659 2
 '@S9S_MB_2U_LIB.S9S_MB_2U(SCH_1):PAGE175_I181@PURE_QUANTA.Q_RES(CHIPS)':
 'B': CDS_PINID='B';
NODE_NAME     R1828 2
 '@S9S_MB_2U_LIB.S9S_MB_2U(SCH_1):PAGE175_I188@PURE_QUANTA.Q_RES(CHIPS)':
 'B': CDS_PINID='B';
NODE_NAME     R635 2
 '@S9S_MB_2U_LIB.S9S_MB_2U(SCH_1):PAGE175_I234@PURE_QUANTA.Q_RES(CHIPS)':
 'B': CDS_PINID='B';
NODE_NAME     R727 2
 '@S9S_MB_2U_LIB.S9S_MB_2U(SCH_1):PAGE175_I236@PURE_QUANTA.Q_RES(CHIPS)':
 'B': CDS_PINID='B';
NODE_NAME     R770 2
 '@S9S_MB_2U_LIB.S9S_MB_2U(SCH_1):PAGE175_I239@PURE_QUANTA.Q_RES(CHIPS)':
 'B': CDS_PINID='B';
NODE_NAME     R913 2
 '@S9S_MB_2U_LIB.S9S_MB_2U(SCH_1):PAGE175_I241@PURE_QUANTA.Q_RES(CHIPS)':
 'B': CDS_PINID='B';
NODE_NAME     R2508 1
 '@S9S_MB_2U_LIB.S9S_MB_2U(SCH_1):PAGE176_I173@PURE_QUANTA.Q_RES(CHIPS)':
 'A': CDS_PINID='A';
NODE_NAME     R2510 1
 '@S9S_MB_2U_LIB.S9S_MB_2U(SCH_1):PAGE176_I175@PURE_QUANTA.Q_RES(CHIPS)':
 'A': CDS_PINID='A';
NODE_NAME     R498 1
 '@S9S_MB_2U_LIB.S9S_MB_2U(SCH_1):PAGE177_I24@PURE_QUANTA.Q_RES(CHIPS)':
 'A': CDS_PINID='A';
NODE_NAME     U62 2
 '@S9S_MB_2U_LIB.S9S_MB_2U(SCH_1):PAGE177_I64@PURE_QUANTA.BAS70057F(CHIPS)':
 'A': CDS_PINID='A';
NODE_NAME     U4 AF17
 '@S9S_MB_2U_LIB.S9S_MB_2U(SCH_1):PAGE178_I11@PURE_QUANTA.EMMITSBURG_REV0P9(CHIPS)':
 'VCCP_3P3_AF17': CDS_PINID='VCCP_3P3_AF17';
NODE_NAME     U4 AG17
 '@S9S_MB_2U_LIB.S9S_MB_2U(SCH_1):PAGE178_I11@PURE_QUANTA.EMMITSBURG_REV0P9(CHIPS)':
 'VCCP_3P3_AG17': CDS_PINID='VCCP_3P3_AG17';
NODE_NAME     U4 AJ17
 '@S9S_MB_2U_LIB.S9S_MB_2U(SCH_1):PAGE178_I11@PURE_QUANTA.EMMITSBURG_REV0P9(CHIPS)':
 'VCCP_3P3_AJ17': CDS_PINID='VCCP_3P3_AJ17';
NODE_NAME     U4 AK15
 '@S9S_MB_2U_LIB.S9S_MB_2U(SCH_1):PAGE178_I11@PURE_QUANTA.EMMITSBURG_REV0P9(CHIPS)':
 'VCCP_3P3_AK15': CDS_PINID='VCCP_3P3_AK15';
NODE_NAME     U4 AL17
 '@S9S_MB_2U_LIB.S9S_MB_2U(SCH_1):PAGE178_I11@PURE_QUANTA.EMMITSBURG_REV0P9(CHIPS)':
 'VCCP_3P3_AL17': CDS_PINID='VCCP_3P3_AL17';
NODE_NAME     U4 AD15
 '@S9S_MB_2U_LIB.S9S_MB_2U(SCH_1):PAGE178_I11@PURE_QUANTA.EMMITSBURG_REV0P9(CHIPS)':
 'VCCP_3P3_DSW_AD15': CDS_PINID='VCCP_3P3_DSW_AD15';
NODE_NAME     U4 V15
 '@S9S_MB_2U_LIB.S9S_MB_2U(SCH_1):PAGE178_I11@PURE_QUANTA.EMMITSBURG_REV0P9(CHIPS)':
 'VCCP_3P3_DSW_V15': CDS_PINID='VCCP_3P3_DSW_V15';
NODE_NAME     U4 P21
 '@S9S_MB_2U_LIB.S9S_MB_2U(SCH_1):PAGE178_I11@PURE_QUANTA.EMMITSBURG_REV0P9(CHIPS)':
 'VCCP_3P3_P21': CDS_PINID='VCCP_3P3_P21';
NODE_NAME     U4 T15
 '@S9S_MB_2U_LIB.S9S_MB_2U(SCH_1):PAGE178_I11@PURE_QUANTA.EMMITSBURG_REV0P9(CHIPS)':
 'VCCP_GPPD_1P8_3P3': CDS_PINID='VCCP_GPPD_1P8_3P3';
NODE_NAME     U4 AN20
 '@S9S_MB_2U_LIB.S9S_MB_2U(SCH_1):PAGE178_I11@PURE_QUANTA.EMMITSBURG_REV0P9(CHIPS)':
 'VCCP_GPPE_1P8_3P3': CDS_PINID='VCCP_GPPE_1P8_3P3';
NODE_NAME     U4 AD17
 '@S9S_MB_2U_LIB.S9S_MB_2U(SCH_1):PAGE178_I11@PURE_QUANTA.EMMITSBURG_REV0P9(CHIPS)':
 'VCCP_GPPI_1P8_3P3': CDS_PINID='VCCP_GPPI_1P8_3P3';
NODE_NAME     C1206 1
 '@S9S_MB_2U_LIB.S9S_MB_2U(SCH_1):PAGE181_I78@PURE_QUANTA.Q_CAP(CHIPS)':
 'A': CDS_PINID='A';
NODE_NAME     C1201 1
 '@S9S_MB_2U_LIB.S9S_MB_2U(SCH_1):PAGE181_I87@PURE_QUANTA.Q_CAP(CHIPS)':
 'A': CDS_PINID='A';
NODE_NAME     C1191 1
 '@S9S_MB_2U_LIB.S9S_MB_2U(SCH_1):PAGE181_I89@PURE_QUANTA.Q_CAP(CHIPS)':
 'A': CDS_PINID='A';
NODE_NAME     C1184 1
 '@S9S_MB_2U_LIB.S9S_MB_2U(SCH_1):PAGE181_I91@PURE_QUANTA.Q_CAP(CHIPS)':
 'A': CDS_PINID='A';
NODE_NAME     R1396 2
 '@S9S_MB_2U_LIB.S9S_MB_2U(SCH_1):PAGE182_I167@PURE_QUANTA.Q_RES(CHIPS)':
 'B': CDS_PINID='B';
NODE_NAME     R487 1
 '@S9S_MB_2U_LIB.S9S_MB_2U(SCH_1):PAGE182_I173@PURE_QUANTA.Q_RES(CHIPS)':
 'A': CDS_PINID='A';
NODE_NAME     R478 1
 '@S9S_MB_2U_LIB.S9S_MB_2U(SCH_1):PAGE182_I176@PURE_QUANTA.Q_RES(CHIPS)':
 'A': CDS_PINID='A';
NODE_NAME     R1271 1
 '@S9S_MB_2U_LIB.S9S_MB_2U(SCH_1):PAGE183_I5@PURE_QUANTA.Q_RES(CHIPS)':
 'A': CDS_PINID='A';
NODE_NAME     C1305 1
 '@S9S_MB_2U_LIB.S9S_MB_2U(SCH_1):PAGE183_I52@PURE_QUANTA.Q_CAP(CHIPS)':
 'A': CDS_PINID='A';
NODE_NAME     R1700 1
 '@S9S_MB_2U_LIB.S9S_MB_2U(SCH_1):PAGE183_I72@PURE_QUANTA.Q_RES(CHIPS)':
 'A': CDS_PINID='A';
NODE_NAME     U142 5
 '@S9S_MB_2U_LIB.S9S_MB_2U(SCH_1):PAGE185_I35@PURE_QUANTA.NC7SB3157(CHIPS)':
 'VCC': CDS_PINID='VCC';
NODE_NAME     C1612 1
 '@S9S_MB_2U_LIB.S9S_MB_2U(SCH_1):PAGE185_I36@PURE_QUANTA.Q_CAP(CHIPS)':
 'A': CDS_PINID='A';
NODE_NAME     R2253 1
 '@S9S_MB_2U_LIB.S9S_MB_2U(SCH_1):PAGE185_I39@PURE_QUANTA.Q_RES(CHIPS)':
 'A': CDS_PINID='A';
NODE_NAME     R367 1
 '@S9S_MB_2U_LIB.S9S_MB_2U(SCH_1):PAGE186_I11@PURE_QUANTA.Q_RES(CHIPS)':
 'A': CDS_PINID='A';
NODE_NAME     R369 1
 '@S9S_MB_2U_LIB.S9S_MB_2U(SCH_1):PAGE186_I16@PURE_QUANTA.Q_RES(CHIPS)':
 'A': CDS_PINID='A';
NODE_NAME     R371 1
 '@S9S_MB_2U_LIB.S9S_MB_2U(SCH_1):PAGE186_I45@PURE_QUANTA.Q_RES(CHIPS)':
 'A': CDS_PINID='A';
NODE_NAME     R374 1
 '@S9S_MB_2U_LIB.S9S_MB_2U(SCH_1):PAGE186_I60@PURE_QUANTA.Q_RES(CHIPS)':
 'A': CDS_PINID='A';
NODE_NAME     R502 1
 '@S9S_MB_2U_LIB.S9S_MB_2U(SCH_1):PAGE186_I68@PURE_QUANTA.Q_RES(CHIPS)':
 'A': CDS_PINID='A';
NODE_NAME     R378 1
 '@S9S_MB_2U_LIB.S9S_MB_2U(SCH_1):PAGE186_I77@PURE_QUANTA.Q_RES(CHIPS)':
 'A': CDS_PINID='A';
NODE_NAME     R380 1
 '@S9S_MB_2U_LIB.S9S_MB_2U(SCH_1):PAGE186_I78@PURE_QUANTA.Q_RES(CHIPS)':
 'A': CDS_PINID='A';
NODE_NAME     R1809 1
 '@S9S_MB_2U_LIB.S9S_MB_2U(SCH_1):PAGE186_I89@PURE_QUANTA.Q_RES(CHIPS)':
 'A': CDS_PINID='A';
NODE_NAME     R623 1
 '@S9S_MB_2U_LIB.S9S_MB_2U(SCH_1):PAGE187_I13@PURE_QUANTA.Q_RES(CHIPS)':
 'A': CDS_PINID='A';
NODE_NAME     R613 1
 '@S9S_MB_2U_LIB.S9S_MB_2U(SCH_1):PAGE187_I18@PURE_QUANTA.Q_RES(CHIPS)':
 'A': CDS_PINID='A';
NODE_NAME     R607 1
 '@S9S_MB_2U_LIB.S9S_MB_2U(SCH_1):PAGE187_I21@PURE_QUANTA.Q_RES(CHIPS)':
 'A': CDS_PINID='A';
NODE_NAME     R609 1
 '@S9S_MB_2U_LIB.S9S_MB_2U(SCH_1):PAGE187_I39@PURE_QUANTA.Q_RES(CHIPS)':
 'A': CDS_PINID='A';
NODE_NAME     R611 1
 '@S9S_MB_2U_LIB.S9S_MB_2U(SCH_1):PAGE187_I43@PURE_QUANTA.Q_RES(CHIPS)':
 'A': CDS_PINID='A';
NODE_NAME     R619 1
 '@S9S_MB_2U_LIB.S9S_MB_2U(SCH_1):PAGE187_I48@PURE_QUANTA.Q_RES(CHIPS)':
 'A': CDS_PINID='A';
NODE_NAME     R615 1
 '@S9S_MB_2U_LIB.S9S_MB_2U(SCH_1):PAGE187_I51@PURE_QUANTA.Q_RES(CHIPS)':
 'A': CDS_PINID='A';
NODE_NAME     R617 1
 '@S9S_MB_2U_LIB.S9S_MB_2U(SCH_1):PAGE187_I54@PURE_QUANTA.Q_RES(CHIPS)':
 'A': CDS_PINID='A';
NODE_NAME     R621 1
 '@S9S_MB_2U_LIB.S9S_MB_2U(SCH_1):PAGE187_I55@PURE_QUANTA.Q_RES(CHIPS)':
 'A': CDS_PINID='A';
NODE_NAME     R1475 1
 '@S9S_MB_2U_LIB.S9S_MB_2U(SCH_1):PAGE188_I44@PURE_QUANTA.Q_RES(CHIPS)':
 'A': CDS_PINID='A';
NODE_NAME     R1477 1
 '@S9S_MB_2U_LIB.S9S_MB_2U(SCH_1):PAGE188_I47@PURE_QUANTA.Q_RES(CHIPS)':
 'A': CDS_PINID='A';
NODE_NAME     R3038 1
 '@S9S_MB_2U_LIB.S9S_MB_2U(SCH_1):PAGE188_I57@PURE_QUANTA.Q_RES(CHIPS)':
 'A': CDS_PINID='A';
NODE_NAME     R1220 1
 '@S9S_MB_2U_LIB.S9S_MB_2U(SCH_1):PAGE188_I63@PURE_QUANTA.Q_RES(CHIPS)':
 'A': CDS_PINID='A';
NODE_NAME     R1496 1
 '@S9S_MB_2U_LIB.S9S_MB_2U(SCH_1):PAGE188_I71@PURE_QUANTA.Q_RES(CHIPS)':
 'A': CDS_PINID='A';
NODE_NAME     C1647 1
 '@S9S_MB_2U_LIB.S9S_MB_2U(SCH_1):PAGE190_I84@PURE_QUANTA.Q_CAP(CHIPS)':
 'A': CDS_PINID='A';
NODE_NAME     R2451 1
 '@S9S_MB_2U_LIB.S9S_MB_2U(SCH_1):PAGE190_I94@PURE_QUANTA.Q_RES(CHIPS)':
 'A': CDS_PINID='A';
NODE_NAME     R1820 1
 '@S9S_MB_2U_LIB.S9S_MB_2U(SCH_1):PAGE191_I35@PURE_QUANTA.Q_RES(CHIPS)':
 'A': CDS_PINID='A';
NODE_NAME     R3040 1
 '@S9S_MB_2U_LIB.S9S_MB_2U(SCH_1):PAGE192_I1@PURE_QUANTA.Q_RES(CHIPS)':
 'A': CDS_PINID='A';
NODE_NAME     R1257 1
 '@S9S_MB_2U_LIB.S9S_MB_2U(SCH_1):PAGE192_I4@PURE_QUANTA.Q_RES(CHIPS)':
 'A': CDS_PINID='A';
NODE_NAME     R3041 1
 '@S9S_MB_2U_LIB.S9S_MB_2U(SCH_1):PAGE192_I6@PURE_QUANTA.Q_RES(CHIPS)':
 'A': CDS_PINID='A';
NODE_NAME     R1259 1
 '@S9S_MB_2U_LIB.S9S_MB_2U(SCH_1):PAGE192_I8@PURE_QUANTA.Q_RES(CHIPS)':
 'A': CDS_PINID='A';
NODE_NAME     R1449 1
 '@S9S_MB_2U_LIB.S9S_MB_2U(SCH_1):PAGE192_I41@PURE_QUANTA.Q_RES(CHIPS)':
 'A': CDS_PINID='A';
NODE_NAME     R1450 1
 '@S9S_MB_2U_LIB.S9S_MB_2U(SCH_1):PAGE192_I42@PURE_QUANTA.Q_RES(CHIPS)':
 'A': CDS_PINID='A';
NODE_NAME     R1458 1
 '@S9S_MB_2U_LIB.S9S_MB_2U(SCH_1):PAGE192_I50@PURE_QUANTA.Q_RES(CHIPS)':
 'A': CDS_PINID='A';
NODE_NAME     R1459 1
 '@S9S_MB_2U_LIB.S9S_MB_2U(SCH_1):PAGE192_I51@PURE_QUANTA.Q_RES(CHIPS)':
 'A': CDS_PINID='A';
NODE_NAME     R8 1
 '@S9S_MB_2U_LIB.S9S_MB_2U(SCH_1):PAGE192_I59@PURE_QUANTA.Q_RES(CHIPS)':
 'A': CDS_PINID='A';
NODE_NAME     R71 1
 '@S9S_MB_2U_LIB.S9S_MB_2U(SCH_1):PAGE192_I60@PURE_QUANTA.Q_RES(CHIPS)':
 'A': CDS_PINID='A';
NODE_NAME     R1554 1
 '@S9S_MB_2U_LIB.S9S_MB_2U(SCH_1):PAGE192_I62@PURE_QUANTA.Q_RES(CHIPS)':
 'A': CDS_PINID='A';
NODE_NAME     R456 1
 '@S9S_MB_2U_LIB.S9S_MB_2U(SCH_1):PAGE192_I66@PURE_QUANTA.Q_RES(CHIPS)':
 'A': CDS_PINID='A';
NODE_NAME     R401 1
 '@S9S_MB_2U_LIB.S9S_MB_2U(SCH_1):PAGE192_I69@PURE_QUANTA.Q_RES(CHIPS)':
 'A': CDS_PINID='A';
NODE_NAME     R1955 1
 '@S9S_MB_2U_LIB.S9S_MB_2U(SCH_1):PAGE192_I72@PURE_QUANTA.Q_RES(CHIPS)':
 'A': CDS_PINID='A';
NODE_NAME     R2342 1
 '@S9S_MB_2U_LIB.S9S_MB_2U(SCH_1):PAGE192_I75@PURE_QUANTA.Q_RES(CHIPS)':
 'A': CDS_PINID='A';
NODE_NAME     R1483 1
 '@S9S_MB_2U_LIB.S9S_MB_2U(SCH_1):PAGE197_I265@PURE_QUANTA.Q_RES(CHIPS)':
 'A': CDS_PINID='A';
NODE_NAME     R1471 1
 '@S9S_MB_2U_LIB.S9S_MB_2U(SCH_1):PAGE197_I267@PURE_QUANTA.Q_RES(CHIPS)':
 'A': CDS_PINID='A';
NODE_NAME     R1305 1
 '@S9S_MB_2U_LIB.S9S_MB_2U(SCH_1):PAGE197_I272@PURE_QUANTA.Q_RES(CHIPS)':
 'A': CDS_PINID='A';
NODE_NAME     R1204 1
 '@S9S_MB_2U_LIB.S9S_MB_2U(SCH_1):PAGE197_I273@PURE_QUANTA.Q_RES(CHIPS)':
 'A': CDS_PINID='A';
NODE_NAME     R1194 1
 '@S9S_MB_2U_LIB.S9S_MB_2U(SCH_1):PAGE197_I277@PURE_QUANTA.Q_RES(CHIPS)':
 'A': CDS_PINID='A';
NODE_NAME     R912 1
 '@S9S_MB_2U_LIB.S9S_MB_2U(SCH_1):PAGE197_I278@PURE_QUANTA.Q_RES(CHIPS)':
 'A': CDS_PINID='A';
NODE_NAME     R2481 1
 '@S9S_MB_2U_LIB.S9S_MB_2U(SCH_1):PAGE197_I280@PURE_QUANTA.Q_RES(CHIPS)':
 'A': CDS_PINID='A';
NODE_NAME     R1958 1
 '@S9S_MB_2U_LIB.S9S_MB_2U(SCH_1):PAGE197_I303@PURE_QUANTA.Q_RES(CHIPS)':
 'A': CDS_PINID='A';
NODE_NAME     L1 1
 '@S9S_MB_2U_LIB.S9S_MB_2U(SCH_1):PAGE199_I20@PURE_QUANTA.Q_INDUCTOR(CHIPS)':
 '1': CDS_PINID='\1\';
NODE_NAME     L13 1
 '@S9S_MB_2U_LIB.S9S_MB_2U(SCH_1):PAGE199_I41@PURE_QUANTA.Q_INDUCTOR(CHIPS)':
 '1': CDS_PINID='\1\';
NODE_NAME     L14 1
 '@S9S_MB_2U_LIB.S9S_MB_2U(SCH_1):PAGE199_I60@PURE_QUANTA.Q_INDUCTOR(CHIPS)':
 '1': CDS_PINID='\1\';
NODE_NAME     R929 1
 '@S9S_MB_2U_LIB.S9S_MB_2U(SCH_1):PAGE210_I59@PURE_QUANTA.Q_RES(CHIPS)':
 'A': CDS_PINID='A';
NODE_NAME     R928 1
 '@S9S_MB_2U_LIB.S9S_MB_2U(SCH_1):PAGE210_I60@PURE_QUANTA.Q_RES(CHIPS)':
 'A': CDS_PINID='A';
NODE_NAME     R927 1
 '@S9S_MB_2U_LIB.S9S_MB_2U(SCH_1):PAGE210_I61@PURE_QUANTA.Q_RES(CHIPS)':
 'A': CDS_PINID='A';
NODE_NAME     R919 1
 '@S9S_MB_2U_LIB.S9S_MB_2U(SCH_1):PAGE210_I75@PURE_QUANTA.Q_RES(CHIPS)':
 'A': CDS_PINID='A';
NODE_NAME     R538 1
 '@S9S_MB_2U_LIB.S9S_MB_2U(SCH_1):PAGE219_I9@PURE_QUANTA.Q_RES(CHIPS)':
 'A': CDS_PINID='A';
NODE_NAME     R540 1
 '@S9S_MB_2U_LIB.S9S_MB_2U(SCH_1):PAGE219_I10@PURE_QUANTA.Q_RES(CHIPS)':
 'A': CDS_PINID='A';
NODE_NAME     C561 1
 '@S9S_MB_2U_LIB.S9S_MB_2U(SCH_1):PAGE223_I18@PURE_QUANTA.Q_CAP(CHIPS)':
 'A': CDS_PINID='A';
NODE_NAME     C562 1
 '@S9S_MB_2U_LIB.S9S_MB_2U(SCH_1):PAGE223_I31@PURE_QUANTA.Q_CAP(CHIPS)':
 'A': CDS_PINID='A';
NODE_NAME     U28 8
 '@S9S_MB_2U_LIB.S9S_MB_2U(SCH_1):PAGE223_I39@PURE_QUANTA.PCA9617ADP(CHIPS)':
 'VCCB': CDS_PINID='VCCB';
NODE_NAME     U29 8
 '@S9S_MB_2U_LIB.S9S_MB_2U(SCH_1):PAGE223_I43@PURE_QUANTA.PCA9617ADP(CHIPS)':
 'VCCB': CDS_PINID='VCCB';
NODE_NAME     R968 1
 '@S9S_MB_2U_LIB.S9S_MB_2U(SCH_1):PAGE223_I81@PURE_QUANTA.Q_RES(CHIPS)':
 'A': CDS_PINID='A';
NODE_NAME     R966 1
 '@S9S_MB_2U_LIB.S9S_MB_2U(SCH_1):PAGE223_I82@PURE_QUANTA.Q_RES(CHIPS)':
 'A': CDS_PINID='A';
NODE_NAME     R965 1
 '@S9S_MB_2U_LIB.S9S_MB_2U(SCH_1):PAGE223_I93@PURE_QUANTA.Q_RES(CHIPS)':
 'A': CDS_PINID='A';
NODE_NAME     R967 1
 '@S9S_MB_2U_LIB.S9S_MB_2U(SCH_1):PAGE223_I94@PURE_QUANTA.Q_RES(CHIPS)':
 'A': CDS_PINID='A';
NODE_NAME     R979 1
 '@S9S_MB_2U_LIB.S9S_MB_2U(SCH_1):PAGE224_I6@PURE_QUANTA.Q_RES(CHIPS)':
 'A': CDS_PINID='A';
NODE_NAME     R977 1
 '@S9S_MB_2U_LIB.S9S_MB_2U(SCH_1):PAGE224_I8@PURE_QUANTA.Q_RES(CHIPS)':
 'A': CDS_PINID='A';
NODE_NAME     R980 1
 '@S9S_MB_2U_LIB.S9S_MB_2U(SCH_1):PAGE224_I14@PURE_QUANTA.Q_RES(CHIPS)':
 'A': CDS_PINID='A';
NODE_NAME     R978 1
 '@S9S_MB_2U_LIB.S9S_MB_2U(SCH_1):PAGE224_I16@PURE_QUANTA.Q_RES(CHIPS)':
 'A': CDS_PINID='A';
NODE_NAME     C569 1
 '@S9S_MB_2U_LIB.S9S_MB_2U(SCH_1):PAGE224_I22@PURE_QUANTA.Q_CAP(CHIPS)':
 'A': CDS_PINID='A';
NODE_NAME     U30 8
 '@S9S_MB_2U_LIB.S9S_MB_2U(SCH_1):PAGE224_I28@PURE_QUANTA.PCA9517AD(CHIPS)':
 'VCCB': CDS_PINID='VCCB';
NODE_NAME     C570 1
 '@S9S_MB_2U_LIB.S9S_MB_2U(SCH_1):PAGE224_I33@PURE_QUANTA.Q_CAP(CHIPS)':
 'A': CDS_PINID='A';
NODE_NAME     U31 8
 '@S9S_MB_2U_LIB.S9S_MB_2U(SCH_1):PAGE224_I37@PURE_QUANTA.PCA9517AD(CHIPS)':
 'VCCB': CDS_PINID='VCCB';
NODE_NAME     C1613 1
 '@S9S_MB_2U_LIB.S9S_MB_2U(SCH_1):PAGE224_I68@PURE_QUANTA.Q_CAP(CHIPS)':
 'A': CDS_PINID='A';
NODE_NAME     R2310 1
 '@S9S_MB_2U_LIB.S9S_MB_2U(SCH_1):PAGE224_I83@PURE_QUANTA.Q_RES(CHIPS)':
 'A': CDS_PINID='A';
NODE_NAME     R2308 1
 '@S9S_MB_2U_LIB.S9S_MB_2U(SCH_1):PAGE224_I84@PURE_QUANTA.Q_RES(CHIPS)':
 'A': CDS_PINID='A';
NODE_NAME     R2312 1
 '@S9S_MB_2U_LIB.S9S_MB_2U(SCH_1):PAGE224_I101@PURE_QUANTA.Q_RES(CHIPS)':
 'A': CDS_PINID='A';
NODE_NAME     R2315 1
 '@S9S_MB_2U_LIB.S9S_MB_2U(SCH_1):PAGE224_I103@PURE_QUANTA.Q_RES(CHIPS)':
 'A': CDS_PINID='A';
NODE_NAME     R1383 1
 '@S9S_MB_2U_LIB.S9S_MB_2U(SCH_1):PAGE226_I1@PURE_QUANTA.Q_RES(CHIPS)':
 'A': CDS_PINID='A';
NODE_NAME     R1381 1
 '@S9S_MB_2U_LIB.S9S_MB_2U(SCH_1):PAGE226_I7@PURE_QUANTA.Q_RES(CHIPS)':
 'A': CDS_PINID='A';
NODE_NAME     R3055 1
 '@S9S_MB_2U_LIB.S9S_MB_2U(SCH_1):PAGE226_I11@PURE_QUANTA.Q_RES(CHIPS)':
 'A': CDS_PINID='A';
NODE_NAME     C1291 1
 '@S9S_MB_2U_LIB.S9S_MB_2U(SCH_1):PAGE226_I16@PURE_QUANTA.Q_CAP(CHIPS)':
 'A': CDS_PINID='A';
NODE_NAME     U84 14
 '@S9S_MB_2U_LIB.S9S_MB_2U(SCH_1):PAGE226_I18@PURE_QUANTA.GTL2014PW(CHIPS)':
 'VCC': CDS_PINID='VCC';
NODE_NAME     R1382 1
 '@S9S_MB_2U_LIB.S9S_MB_2U(SCH_1):PAGE226_I20@PURE_QUANTA.Q_RES(CHIPS)':
 'A': CDS_PINID='A';
NODE_NAME     C1322 1
 '@S9S_MB_2U_LIB.S9S_MB_2U(SCH_1):PAGE226_I27@PURE_QUANTA.Q_CAP(CHIPS)':
 'A': CDS_PINID='A';
NODE_NAME     R1380 1
 '@S9S_MB_2U_LIB.S9S_MB_2U(SCH_1):PAGE226_I31@PURE_QUANTA.Q_RES(CHIPS)':
 'A': CDS_PINID='A';
NODE_NAME     U97 10
 '@S9S_MB_2U_LIB.S9S_MB_2U(SCH_1):PAGE226_I38@PURE_QUANTA.NX3L2267GM(CHIPS)':
 'VCC': CDS_PINID='VCC';
NODE_NAME     C1290 1
 '@S9S_MB_2U_LIB.S9S_MB_2U(SCH_1):PAGE226_I43@PURE_QUANTA.Q_CAP(CHIPS)':
 'A': CDS_PINID='A';
NODE_NAME     U83 14
 '@S9S_MB_2U_LIB.S9S_MB_2U(SCH_1):PAGE226_I45@PURE_QUANTA.GTL2014PW(CHIPS)':
 'VCC': CDS_PINID='VCC';
NODE_NAME     C1321 1
 '@S9S_MB_2U_LIB.S9S_MB_2U(SCH_1):PAGE226_I55@PURE_QUANTA.Q_CAP(CHIPS)':
 'A': CDS_PINID='A';
NODE_NAME     U96 10
 '@S9S_MB_2U_LIB.S9S_MB_2U(SCH_1):PAGE226_I68@PURE_QUANTA.NX3L2267GM(CHIPS)':
 'VCC': CDS_PINID='VCC';
NODE_NAME     R1813 1
 '@S9S_MB_2U_LIB.S9S_MB_2U(SCH_1):PAGE226_I79@PURE_QUANTA.Q_RES(CHIPS)':
 'A': CDS_PINID='A';
NODE_NAME     R2506 1
 '@S9S_MB_2U_LIB.S9S_MB_2U(SCH_1):PAGE226_I87@PURE_QUANTA.Q_RES(CHIPS)':
 'A': CDS_PINID='A';
NODE_NAME     R2507 1
 '@S9S_MB_2U_LIB.S9S_MB_2U(SCH_1):PAGE226_I88@PURE_QUANTA.Q_RES(CHIPS)':
 'A': CDS_PINID='A';
NODE_NAME     R1319 2
 '@S9S_MB_2U_LIB.S9S_MB_2U(SCH_1):PAGE228_I2@PURE_QUANTA.Q_RES(CHIPS)':
 'B': CDS_PINID='B';
NODE_NAME     R3062 2
 '@S9S_MB_2U_LIB.S9S_MB_2U(SCH_1):PAGE228_I3@PURE_QUANTA.Q_RES(CHIPS)':
 'B': CDS_PINID='B';
NODE_NAME     R1384 2
 '@S9S_MB_2U_LIB.S9S_MB_2U(SCH_1):PAGE228_I4@PURE_QUANTA.Q_RES(CHIPS)':
 'B': CDS_PINID='B';
NODE_NAME     R1385 2
 '@S9S_MB_2U_LIB.S9S_MB_2U(SCH_1):PAGE228_I5@PURE_QUANTA.Q_RES(CHIPS)':
 'B': CDS_PINID='B';
NODE_NAME     R1386 2
 '@S9S_MB_2U_LIB.S9S_MB_2U(SCH_1):PAGE228_I6@PURE_QUANTA.Q_RES(CHIPS)':
 'B': CDS_PINID='B';
NODE_NAME     R1387 2
 '@S9S_MB_2U_LIB.S9S_MB_2U(SCH_1):PAGE228_I7@PURE_QUANTA.Q_RES(CHIPS)':
 'B': CDS_PINID='B';
NODE_NAME     R601 2
 '@S9S_MB_2U_LIB.S9S_MB_2U(SCH_1):PAGE228_I172@PURE_QUANTA.Q_RES(CHIPS)':
 'B': CDS_PINID='B';
NODE_NAME     R592 2
 '@S9S_MB_2U_LIB.S9S_MB_2U(SCH_1):PAGE228_I173@PURE_QUANTA.Q_RES(CHIPS)':
 'B': CDS_PINID='B';
NODE_NAME     R1460 2
 '@S9S_MB_2U_LIB.S9S_MB_2U(SCH_1):PAGE228_I176@PURE_QUANTA.Q_RES(CHIPS)':
 'B': CDS_PINID='B';
NODE_NAME     R1336 2
 '@S9S_MB_2U_LIB.S9S_MB_2U(SCH_1):PAGE228_I177@PURE_QUANTA.Q_RES(CHIPS)':
 'B': CDS_PINID='B';
NODE_NAME     R2212 2
 '@S9S_MB_2U_LIB.S9S_MB_2U(SCH_1):PAGE228_I202@PURE_QUANTA.Q_RES(CHIPS)':
 'B': CDS_PINID='B';
NODE_NAME     R2213 2
 '@S9S_MB_2U_LIB.S9S_MB_2U(SCH_1):PAGE228_I203@PURE_QUANTA.Q_RES(CHIPS)':
 'B': CDS_PINID='B';
NODE_NAME     U64 8
 '@S9S_MB_2U_LIB.S9S_MB_2U(SCH_1):PAGE231_I35@PURE_QUANTA.M24128BWMN6TP(CHIPS)':
 'VCC': CDS_PINID='VCC';
NODE_NAME     R717 1
 '@S9S_MB_2U_LIB.S9S_MB_2U(SCH_1):PAGE231_I45@PURE_QUANTA.Q_RES(CHIPS)':
 'A': CDS_PINID='A';
NODE_NAME     R713 1
 '@S9S_MB_2U_LIB.S9S_MB_2U(SCH_1):PAGE231_I47@PURE_QUANTA.Q_RES(CHIPS)':
 'A': CDS_PINID='A';
NODE_NAME     C629 1
 '@S9S_MB_2U_LIB.S9S_MB_2U(SCH_1):PAGE231_I55@PURE_QUANTA.Q_CAP(CHIPS)':
 'A': CDS_PINID='A';
NODE_NAME     R721 1
 '@S9S_MB_2U_LIB.S9S_MB_2U(SCH_1):PAGE231_I62@PURE_QUANTA.Q_RES(CHIPS)':
 'A': CDS_PINID='A';
NODE_NAME     R1332 1
 '@S9S_MB_2U_LIB.S9S_MB_2U(SCH_1):PAGE231_I93@PURE_QUANTA.Q_RES(CHIPS)':
 'A': CDS_PINID='A';
NODE_NAME     R1331 1
 '@S9S_MB_2U_LIB.S9S_MB_2U(SCH_1):PAGE231_I95@PURE_QUANTA.Q_RES(CHIPS)':
 'A': CDS_PINID='A';
NODE_NAME     R1691 1
 '@S9S_MB_2U_LIB.S9S_MB_2U(SCH_1):PAGE232_I4@PURE_QUANTA.Q_RES(CHIPS)':
 'A': CDS_PINID='A';
NODE_NAME     R1694 1
 '@S9S_MB_2U_LIB.S9S_MB_2U(SCH_1):PAGE232_I33@PURE_QUANTA.Q_RES(CHIPS)':
 'A': CDS_PINID='A';
NODE_NAME     R1765 2
 '@S9S_MB_2U_LIB.S9S_MB_2U(SCH_1):PAGE243_I13@PURE_QUANTA.Q_RES(CHIPS)':
 'B': CDS_PINID='B';
NODE_NAME     R2375 1
 '@S9S_MB_2U_LIB.S9S_MB_2U(SCH_1):PAGE252_I19@PURE_QUANTA.Q_RES(CHIPS)':
 'A': CDS_PINID='A';
NODE_NAME     R2383 1
 '@S9S_MB_2U_LIB.S9S_MB_2U(SCH_1):PAGE260_I59@PURE_QUANTA.Q_RES(CHIPS)':
 'A': CDS_PINID='A';
NODE_NAME     R361 1
 '@S9S_MB_2U_LIB.S9S_MB_2U(SCH_1):PAGE264_I46@PURE_QUANTA.Q_RES(CHIPS)':
 'A': CDS_PINID='A';
NODE_NAME     C1708 1
 '@S9S_MB_2U_LIB.S9S_MB_2U(SCH_1):PAGE222_I34@PURE_QUANTA.Q_CAP(CHIPS)':
 'A': CDS_PINID='A';
NODE_NAME     R2835 1
 '@S9S_MB_2U_LIB.S9S_MB_2U(SCH_1):PAGE145_I14@PURE_QUANTA.Q_RES(CHIPS)':
 'A': CDS_PINID='A';
NODE_NAME     R2834 1
 '@S9S_MB_2U_LIB.S9S_MB_2U(SCH_1):PAGE145_I18@PURE_QUANTA.Q_RES(CHIPS)':
 'A': CDS_PINID='A';
NODE_NAME     R2836 1
 '@S9S_MB_2U_LIB.S9S_MB_2U(SCH_1):PAGE145_I19@PURE_QUANTA.Q_RES(CHIPS)':
 'A': CDS_PINID='A';
NODE_NAME     R2841 1
 '@S9S_MB_2U_LIB.S9S_MB_2U(SCH_1):PAGE145_I24@PURE_QUANTA.Q_RES(CHIPS)':
 'A': CDS_PINID='A';
NODE_NAME     R2842 1
 '@S9S_MB_2U_LIB.S9S_MB_2U(SCH_1):PAGE145_I30@PURE_QUANTA.Q_RES(CHIPS)':
 'A': CDS_PINID='A';
NODE_NAME     R2828 1
 '@S9S_MB_2U_LIB.S9S_MB_2U(SCH_1):PAGE145_I66@PURE_QUANTA.Q_RES(CHIPS)':
 'A': CDS_PINID='A';
NODE_NAME     R2832 1
 '@S9S_MB_2U_LIB.S9S_MB_2U(SCH_1):PAGE145_I67@PURE_QUANTA.Q_RES(CHIPS)':
 'A': CDS_PINID='A';
NODE_NAME     R2830 1
 '@S9S_MB_2U_LIB.S9S_MB_2U(SCH_1):PAGE145_I68@PURE_QUANTA.Q_RES(CHIPS)':
 'A': CDS_PINID='A';
NODE_NAME     C1766 1
 '@S9S_MB_2U_LIB.S9S_MB_2U(SCH_1):PAGE222_I66@PURE_QUANTA.Q_CAP(CHIPS)':
 'A': CDS_PINID='A';
NODE_NAME     L15 2
 '@S9S_MB_2U_LIB.S9S_MB_2U(SCH_1):PAGE239_I62@PURE_QUANTA.Q_INDUCTOR(CHIPS)':
 '2': CDS_PINID='\2\';
NODE_NAME     U210 5
 '@S9S_MB_2U_LIB.S9S_MB_2U(SCH_1):PAGE154_I189@PURE_QUANTA.74LVC1G08W57(CHIPS)':
 'VCC': CDS_PINID='VCC';
NODE_NAME     U208 5
 '@S9S_MB_2U_LIB.S9S_MB_2U(SCH_1):PAGE154_I190@PURE_QUANTA.74LVC1G08W57(CHIPS)':
 'VCC': CDS_PINID='VCC';
NODE_NAME     R2837 1
 '@S9S_MB_2U_LIB.S9S_MB_2U(SCH_1):PAGE145_I80@PURE_QUANTA.Q_RES(CHIPS)':
 'A': CDS_PINID='A';
NODE_NAME     U181 24
 '@S9S_MB_2U_LIB.S9S_MB_2U(SCH_1):PAGE214_I66@PURE_QUANTA.PCA9539RPW(CHIPS)':
 'VDD': CDS_PINID='VDD';
NODE_NAME     R2695 1
 '@S9S_MB_2U_LIB.S9S_MB_2U(SCH_1):PAGE214_I74@PURE_QUANTA.Q_RES(CHIPS)':
 'A': CDS_PINID='A';
NODE_NAME     R2693 1
 '@S9S_MB_2U_LIB.S9S_MB_2U(SCH_1):PAGE214_I76@PURE_QUANTA.Q_RES(CHIPS)':
 'A': CDS_PINID='A';
NODE_NAME     C1713 1
 '@S9S_MB_2U_LIB.S9S_MB_2U(SCH_1):PAGE214_I87@PURE_QUANTA.Q_CAP(CHIPS)':
 'A': CDS_PINID='A';
NODE_NAME     R2923 1
 '@S9S_MB_2U_LIB.S9S_MB_2U(SCH_1):PAGE214_I90@PURE_QUANTA.Q_RES(CHIPS)':
 'A': CDS_PINID='A';
NODE_NAME     R2921 1
 '@S9S_MB_2U_LIB.S9S_MB_2U(SCH_1):PAGE214_I93@PURE_QUANTA.Q_RES(CHIPS)':
 'A': CDS_PINID='A';
NODE_NAME     U195 5
 '@S9S_MB_2U_LIB.S9S_MB_2U(SCH_1):PAGE140_I65@PURE_QUANTA.74LVC2G17GW(CHIPS)':
 'VCC': CDS_PINID='VCC';
NODE_NAME     R2815 1
 '@S9S_MB_2U_LIB.S9S_MB_2U(SCH_1):PAGE140_I68@PURE_QUANTA.Q_RES(CHIPS)':
 'A': CDS_PINID='A';
NODE_NAME     R2820 1
 '@S9S_MB_2U_LIB.S9S_MB_2U(SCH_1):PAGE140_I78@PURE_QUANTA.Q_RES(CHIPS)':
 'A': CDS_PINID='A';
NODE_NAME     C1769 1
 '@S9S_MB_2U_LIB.S9S_MB_2U(SCH_1):PAGE140_I89@PURE_QUANTA.Q_CAP(CHIPS)':
 'A': CDS_PINID='A';
NODE_NAME     U196 5
 '@S9S_MB_2U_LIB.S9S_MB_2U(SCH_1):PAGE140_I127@PURE_QUANTA.74LVC2G17GW(CHIPS)':
 'VCC': CDS_PINID='VCC';
NODE_NAME     C1770 1
 '@S9S_MB_2U_LIB.S9S_MB_2U(SCH_1):PAGE140_I140@PURE_QUANTA.Q_CAP(CHIPS)':
 'A': CDS_PINID='A';
NODE_NAME     R2912 1
 '@S9S_MB_2U_LIB.S9S_MB_2U(SCH_1):PAGE140_I147@PURE_QUANTA.Q_RES(CHIPS)':
 'A': CDS_PINID='A';
NODE_NAME     R2911 1
 '@S9S_MB_2U_LIB.S9S_MB_2U(SCH_1):PAGE140_I153@PURE_QUANTA.Q_RES(CHIPS)':
 'A': CDS_PINID='A';
NODE_NAME     R2920 1
 '@S9S_MB_2U_LIB.S9S_MB_2U(SCH_1):PAGE145_I84@PURE_QUANTA.Q_RES(CHIPS)':
 'A': CDS_PINID='A';
NODE_NAME     R2919 1
 '@S9S_MB_2U_LIB.S9S_MB_2U(SCH_1):PAGE145_I91@PURE_QUANTA.Q_RES(CHIPS)':
 'A': CDS_PINID='A';
NODE_NAME     R2933 1
 '@S9S_MB_2U_LIB.S9S_MB_2U(SCH_1):PAGE145_I97@PURE_QUANTA.Q_RES(CHIPS)':
 'A': CDS_PINID='A';
NODE_NAME     R2934 1
 '@S9S_MB_2U_LIB.S9S_MB_2U(SCH_1):PAGE145_I101@PURE_QUANTA.Q_RES(CHIPS)':
 'A': CDS_PINID='A';
NODE_NAME     R2935 1
 '@S9S_MB_2U_LIB.S9S_MB_2U(SCH_1):PAGE145_I109@PURE_QUANTA.Q_RES(CHIPS)':
 'A': CDS_PINID='A';
NODE_NAME     R2936 1
 '@S9S_MB_2U_LIB.S9S_MB_2U(SCH_1):PAGE140_I162@PURE_QUANTA.Q_RES(CHIPS)':
 'A': CDS_PINID='A';
NODE_NAME     C1775 1
 '@S9S_MB_2U_LIB.S9S_MB_2U(SCH_1):PAGE230_I14@PURE_QUANTA.Q_CAP(CHIPS)':
 'A': CDS_PINID='A';
NODE_NAME     R2946 1
 '@S9S_MB_2U_LIB.S9S_MB_2U(SCH_1):PAGE230_I25@PURE_QUANTA.Q_RES(CHIPS)':
 'A': CDS_PINID='A';
NODE_NAME     R2940 1
 '@S9S_MB_2U_LIB.S9S_MB_2U(SCH_1):PAGE230_I28@PURE_QUANTA.Q_RES(CHIPS)':
 'A': CDS_PINID='A';
NODE_NAME     U5201 12
 '@S9S_MB_2U_LIB.S9S_MB_2U(SCH_1):PAGE155_I84@PURE_QUANTA.TUSB211IRWBR(CHIPS)':
 'VCC': CDS_PINID='VCC';
NODE_NAME     C5229 1
 '@S9S_MB_2U_LIB.S9S_MB_2U(SCH_1):PAGE155_I88@PURE_QUANTA.Q_CAP(CHIPS)':
 'A': CDS_PINID='A';
NODE_NAME     C5234 1
 '@S9S_MB_2U_LIB.S9S_MB_2U(SCH_1):PAGE155_I92@PURE_QUANTA.Q_CAP(CHIPS)':
 'A': CDS_PINID='A';
NODE_NAME     R3004 2
 '@S9S_MB_2U_LIB.S9S_MB_2U(SCH_1):PAGE228_I230@PURE_QUANTA.Q_RES(CHIPS)':
 'B': CDS_PINID='B';
NODE_NAME     R2999 2
 '@S9S_MB_2U_LIB.S9S_MB_2U(SCH_1):PAGE228_I231@PURE_QUANTA.Q_RES(CHIPS)':
 'B': CDS_PINID='B';
NODE_NAME     R3035 1
 '@S9S_MB_2U_LIB.S9S_MB_2U(SCH_1):PAGE145_I127@PURE_QUANTA.Q_RES(CHIPS)':
 'A': CDS_PINID='A';
NODE_NAME     R3034 1
 '@S9S_MB_2U_LIB.S9S_MB_2U(SCH_1):PAGE145_I129@PURE_QUANTA.Q_RES(CHIPS)':
 'A': CDS_PINID='A';
NODE_NAME     R3029 1
 '@S9S_MB_2U_LIB.S9S_MB_2U(SCH_1):PAGE145_I144@PURE_QUANTA.Q_RES(CHIPS)':
 'A': CDS_PINID='A';
NODE_NAME     R3030 1
 '@S9S_MB_2U_LIB.S9S_MB_2U(SCH_1):PAGE145_I146@PURE_QUANTA.Q_RES(CHIPS)':
 'A': CDS_PINID='A';
NODE_NAME     R1371 2
 '@S9S_MB_2U_LIB.S9S_MB_2U(SCH_1):PAGE304_I49@PURE_QUANTA.Q_RES(CHIPS)':
 'B': CDS_PINID='B';
NODE_NAME     R3080 2
 '@S9S_MB_2U_LIB.S9S_MB_2U(SCH_1):PAGE304_I50@PURE_QUANTA.Q_RES(CHIPS)':
 'B': CDS_PINID='B';
NODE_NAME     R3079 2
 '@S9S_MB_2U_LIB.S9S_MB_2U(SCH_1):PAGE304_I51@PURE_QUANTA.Q_RES(CHIPS)':
 'B': CDS_PINID='B';
NODE_NAME     R3081 2
 '@S9S_MB_2U_LIB.S9S_MB_2U(SCH_1):PAGE304_I52@PURE_QUANTA.Q_RES(CHIPS)':
 'B': CDS_PINID='B';
NODE_NAME     R3084 2
 '@S9S_MB_2U_LIB.S9S_MB_2U(SCH_1):PAGE304_I53@PURE_QUANTA.Q_RES(CHIPS)':
 'B': CDS_PINID='B';
NODE_NAME     R3082 2
 '@S9S_MB_2U_LIB.S9S_MB_2U(SCH_1):PAGE304_I54@PURE_QUANTA.Q_RES(CHIPS)':
 'B': CDS_PINID='B';
NODE_NAME     R3083 2
 '@S9S_MB_2U_LIB.S9S_MB_2U(SCH_1):PAGE304_I57@PURE_QUANTA.Q_RES(CHIPS)':
 'B': CDS_PINID='B';
NODE_NAME     R3086 2
 '@S9S_MB_2U_LIB.S9S_MB_2U(SCH_1):PAGE305_I49@PURE_QUANTA.Q_RES(CHIPS)':
 'B': CDS_PINID='B';
NODE_NAME     R3087 2
 '@S9S_MB_2U_LIB.S9S_MB_2U(SCH_1):PAGE305_I50@PURE_QUANTA.Q_RES(CHIPS)':
 'B': CDS_PINID='B';
NODE_NAME     R3089 2
 '@S9S_MB_2U_LIB.S9S_MB_2U(SCH_1):PAGE305_I51@PURE_QUANTA.Q_RES(CHIPS)':
 'B': CDS_PINID='B';
NODE_NAME     R3088 2
 '@S9S_MB_2U_LIB.S9S_MB_2U(SCH_1):PAGE305_I52@PURE_QUANTA.Q_RES(CHIPS)':
 'B': CDS_PINID='B';
NODE_NAME     R3091 2
 '@S9S_MB_2U_LIB.S9S_MB_2U(SCH_1):PAGE305_I53@PURE_QUANTA.Q_RES(CHIPS)':
 'B': CDS_PINID='B';
NODE_NAME     R3090 2
 '@S9S_MB_2U_LIB.S9S_MB_2U(SCH_1):PAGE305_I54@PURE_QUANTA.Q_RES(CHIPS)':
 'B': CDS_PINID='B';
NODE_NAME     R3092 2
 '@S9S_MB_2U_LIB.S9S_MB_2U(SCH_1):PAGE305_I55@PURE_QUANTA.Q_RES(CHIPS)':
 'B': CDS_PINID='B';
NODE_NAME     R3095 2
 '@S9S_MB_2U_LIB.S9S_MB_2U(SCH_1):PAGE306_I12@PURE_QUANTA.Q_RES(CHIPS)':
 'B': CDS_PINID='B';
NODE_NAME     R3096 2
 '@S9S_MB_2U_LIB.S9S_MB_2U(SCH_1):PAGE306_I15@PURE_QUANTA.Q_RES(CHIPS)':
 'B': CDS_PINID='B';
NODE_NAME     R3094 2
 '@S9S_MB_2U_LIB.S9S_MB_2U(SCH_1):PAGE306_I16@PURE_QUANTA.Q_RES(CHIPS)':
 'B': CDS_PINID='B';
NODE_NAME     R3093 2
 '@S9S_MB_2U_LIB.S9S_MB_2U(SCH_1):PAGE306_I20@PURE_QUANTA.Q_RES(CHIPS)':
 'B': CDS_PINID='B';
NODE_NAME     R3098 2
 '@S9S_MB_2U_LIB.S9S_MB_2U(SCH_1):PAGE306_I37@PURE_QUANTA.Q_RES(CHIPS)':
 'B': CDS_PINID='B';
NODE_NAME     R3097 2
 '@S9S_MB_2U_LIB.S9S_MB_2U(SCH_1):PAGE306_I38@PURE_QUANTA.Q_RES(CHIPS)':
 'B': CDS_PINID='B';
NODE_NAME     R3099 2
 '@S9S_MB_2U_LIB.S9S_MB_2U(SCH_1):PAGE306_I41@PURE_QUANTA.Q_RES(CHIPS)':
 'B': CDS_PINID='B';
NODE_NAME     R3068 2
 '@S9S_MB_2U_LIB.S9S_MB_2U(SCH_1):PAGE241_I38@PURE_QUANTA.Q_RES(CHIPS)':
 'B': CDS_PINID='B';
NODE_NAME     R3069 2
 '@S9S_MB_2U_LIB.S9S_MB_2U(SCH_1):PAGE241_I39@PURE_QUANTA.Q_RES(CHIPS)':
 'B': CDS_PINID='B';
NODE_NAME     R1044 2
 '@S9S_MB_2U_LIB.S9S_MB_2U(SCH_1):PAGE241_I40@PURE_QUANTA.Q_RES(CHIPS)':
 'B': CDS_PINID='B';
NODE_NAME     R3070 2
 '@S9S_MB_2U_LIB.S9S_MB_2U(SCH_1):PAGE241_I41@PURE_QUANTA.Q_RES(CHIPS)':
 'B': CDS_PINID='B';
NODE_NAME     R3073 2
 '@S9S_MB_2U_LIB.S9S_MB_2U(SCH_1):PAGE242_I12@PURE_QUANTA.Q_RES(CHIPS)':
 'B': CDS_PINID='B';
NODE_NAME     R3074 2
 '@S9S_MB_2U_LIB.S9S_MB_2U(SCH_1):PAGE242_I14@PURE_QUANTA.Q_RES(CHIPS)':
 'B': CDS_PINID='B';
NODE_NAME     R3072 2
 '@S9S_MB_2U_LIB.S9S_MB_2U(SCH_1):PAGE242_I15@PURE_QUANTA.Q_RES(CHIPS)':
 'B': CDS_PINID='B';
NODE_NAME     R3071 2
 '@S9S_MB_2U_LIB.S9S_MB_2U(SCH_1):PAGE242_I19@PURE_QUANTA.Q_RES(CHIPS)':
 'B': CDS_PINID='B';
NODE_NAME     R3075 2
 '@S9S_MB_2U_LIB.S9S_MB_2U(SCH_1):PAGE242_I37@PURE_QUANTA.Q_RES(CHIPS)':
 'B': CDS_PINID='B';
NODE_NAME     R3078 2
 '@S9S_MB_2U_LIB.S9S_MB_2U(SCH_1):PAGE242_I41@PURE_QUANTA.Q_RES(CHIPS)':
 'B': CDS_PINID='B';
NODE_NAME     R3085 2
 '@S9S_MB_2U_LIB.S9S_MB_2U(SCH_1):PAGE304_I62@PURE_QUANTA.Q_RES(CHIPS)':
 'B': CDS_PINID='B';
NODE_NAME     OSC1 4
 '@S9S_MB_2U_LIB.S9S_MB_2U(SCH_1):PAGE152_I76@PURE_QUANTA.Q_OSC4P(CHIPS)':
 'VDD': CDS_PINID='VDD';
NODE_NAME     J3 3
 '@S9S_MB_2U_LIB.S9S_MB_2U(SCH_1):PAGE84_I180@PURE_QUANTA.SCONN288_ADR50017P130CC(CHIPS)':
 'VIN_MGMT': CDS_PINID='VIN_MGMT';
NODE_NAME     C579 1
 '@S9S_MB_2U_LIB.S9S_MB_2U(SCH_1):PAGE154_I192@PURE_QUANTA.Q_CAP(CHIPS)':
 'A': CDS_PINID='A';
NODE_NAME     U143 20
 '@S9S_MB_2U_LIB.S9S_MB_2U(SCH_1):PAGE224_I106@PURE_QUANTA.PCA9545APW(CHIPS)':
 'VDD': CDS_PINID='VDD';
NODE_NAME     R3127 1
 '@S9S_MB_2U_LIB.S9S_MB_2U(SCH_1):PAGE224_I109@PURE_QUANTA.Q_RES(CHIPS)':
 'A': CDS_PINID='A';
NODE_NAME     R3130 1
 '@S9S_MB_2U_LIB.S9S_MB_2U(SCH_1):PAGE224_I110@PURE_QUANTA.Q_RES(CHIPS)':
 'A': CDS_PINID='A';
NODE_NAME     R3131 1
 '@S9S_MB_2U_LIB.S9S_MB_2U(SCH_1):PAGE224_I111@PURE_QUANTA.Q_RES(CHIPS)':
 'A': CDS_PINID='A';
NODE_NAME     C1809 1
 '@S9S_MB_2U_LIB.S9S_MB_2U(SCH_1):PAGE131_I26@PURE_QUANTA.Q_CAP(CHIPS)':
 'A': CDS_PINID='A';
NODE_NAME     R3155 1
 '@S9S_MB_2U_LIB.S9S_MB_2U(SCH_1):PAGE132_I7@PURE_QUANTA.Q_RES(CHIPS)':
 'A': CDS_PINID='A';
NODE_NAME     U50 5
 '@S9S_MB_2U_LIB.S9S_MB_2U(SCH_1):PAGE132_I9@PURE_QUANTA.74LVC1G08W57(CHIPS)':
 'VCC': CDS_PINID='VCC';
NODE_NAME     C1818 1
 '@S9S_MB_2U_LIB.S9S_MB_2U(SCH_1):PAGE132_I15@PURE_QUANTA.Q_CAP(CHIPS)':
 'A': CDS_PINID='A';
NODE_NAME     R3149 1
 '@S9S_MB_2U_LIB.S9S_MB_2U(SCH_1):PAGE132_I29@PURE_QUANTA.Q_RES(CHIPS)':
 'A': CDS_PINID='A';
NODE_NAME     R3153 1
 '@S9S_MB_2U_LIB.S9S_MB_2U(SCH_1):PAGE132_I32@PURE_QUANTA.Q_RES(CHIPS)':
 'A': CDS_PINID='A';
NODE_NAME     U53 5
 '@S9S_MB_2U_LIB.S9S_MB_2U(SCH_1):PAGE132_I56@PURE_QUANTA.74LVC1G08W57(CHIPS)':
 'VCC': CDS_PINID='VCC';
NODE_NAME     R3151 1
 '@S9S_MB_2U_LIB.S9S_MB_2U(SCH_1):PAGE132_I31@PURE_QUANTA.Q_RES(CHIPS)':
 'A': CDS_PINID='A';
NODE_NAME     C1817 1
 '@S9S_MB_2U_LIB.S9S_MB_2U(SCH_1):PAGE132_I39@PURE_QUANTA.Q_CAP(CHIPS)':
 'A': CDS_PINID='A';
NODE_NAME     C1820 1
 '@S9S_MB_2U_LIB.S9S_MB_2U(SCH_1):PAGE132_I58@PURE_QUANTA.Q_CAP(CHIPS)':
 'A': CDS_PINID='A';
NODE_NAME     C1821 1
 '@S9S_MB_2U_LIB.S9S_MB_2U(SCH_1):PAGE156_I12@PURE_QUANTA.Q_CAP(CHIPS)':
 'A': CDS_PINID='A';
NODE_NAME     C1822 1
 '@S9S_MB_2U_LIB.S9S_MB_2U(SCH_1):PAGE156_I27@PURE_QUANTA.Q_CAP(CHIPS)':
 'A': CDS_PINID='A';
NODE_NAME     R3184 1
 '@S9S_MB_2U_LIB.S9S_MB_2U(SCH_1):PAGE156_I28@PURE_QUANTA.Q_RES(CHIPS)':
 'A': CDS_PINID='A';
NODE_NAME     U218 5
 '@S9S_MB_2U_LIB.S9S_MB_2U(SCH_1):PAGE156_I31@PURE_QUANTA.74LVC1G07GV(CHIPS)':
 'VCC': CDS_PINID='VCC';
NODE_NAME     C1823 1
 '@S9S_MB_2U_LIB.S9S_MB_2U(SCH_1):PAGE156_I33@PURE_QUANTA.Q_CAP(CHIPS)':
 'A': CDS_PINID='A';
NODE_NAME     U207 5
 '@S9S_MB_2U_LIB.S9S_MB_2U(SCH_1):PAGE156_I35@PURE_QUANTA.74LVC1G17GW(CHIPS)':
 'VCC': CDS_PINID='VCC';
NODE_NAME     R3190 1
 '@S9S_MB_2U_LIB.S9S_MB_2U(SCH_1):PAGE156_I42@PURE_QUANTA.Q_RES(CHIPS)':
 'A': CDS_PINID='A';
NODE_NAME     C1824 1
 '@S9S_MB_2U_LIB.S9S_MB_2U(SCH_1):PAGE156_I47@PURE_QUANTA.Q_CAP(CHIPS)':
 'A': CDS_PINID='A';
NODE_NAME     R3192 1
 '@S9S_MB_2U_LIB.S9S_MB_2U(SCH_1):PAGE156_I59@PURE_QUANTA.Q_RES(CHIPS)':
 'A': CDS_PINID='A';
NODE_NAME     U219 5
 '@S9S_MB_2U_LIB.S9S_MB_2U(SCH_1):PAGE156_I61@PURE_QUANTA.74LVC1G07GV(CHIPS)':
 'VCC': CDS_PINID='VCC';
NODE_NAME     C1825 1
 '@S9S_MB_2U_LIB.S9S_MB_2U(SCH_1):PAGE307_I17@PURE_QUANTA.Q_CAP(CHIPS)':
 'A': CDS_PINID='A';
NODE_NAME     U222 14
 '@S9S_MB_2U_LIB.S9S_MB_2U(SCH_1):PAGE307_I32@PURE_QUANTA.74CBTLV3126PW(CHIPS)':
 'VCC': CDS_PINID='VCC';
NODE_NAME     C1826 1
 '@S9S_MB_2U_LIB.S9S_MB_2U(SCH_1):PAGE307_I33@PURE_QUANTA.Q_CAP(CHIPS)':
 'A': CDS_PINID='A';
NODE_NAME     C1827 1
 '@S9S_MB_2U_LIB.S9S_MB_2U(SCH_1):PAGE307_I77@PURE_QUANTA.Q_CAP(CHIPS)':
 'A': CDS_PINID='A';
NODE_NAME     U223 14
 '@S9S_MB_2U_LIB.S9S_MB_2U(SCH_1):PAGE307_I78@PURE_QUANTA.74CBTLV3126PW(CHIPS)':
 'VCC': CDS_PINID='VCC';
NODE_NAME     R3227 2
 '@S9S_MB_2U_LIB.S9S_MB_2U(SCH_1):PAGE228_I250@PURE_QUANTA.Q_RES(CHIPS)':
 'B': CDS_PINID='B';
NODE_NAME     R3226 2
 '@S9S_MB_2U_LIB.S9S_MB_2U(SCH_1):PAGE228_I251@PURE_QUANTA.Q_RES(CHIPS)':
 'B': CDS_PINID='B';
NODE_NAME     R3225 2
 '@S9S_MB_2U_LIB.S9S_MB_2U(SCH_1):PAGE224_I130@PURE_QUANTA.Q_RES(CHIPS)':
 'B': CDS_PINID='B';
NODE_NAME     R3224 2
 '@S9S_MB_2U_LIB.S9S_MB_2U(SCH_1):PAGE224_I131@PURE_QUANTA.Q_RES(CHIPS)':
 'B': CDS_PINID='B';
NODE_NAME     R3222 2
 '@S9S_MB_2U_LIB.S9S_MB_2U(SCH_1):PAGE224_I132@PURE_QUANTA.Q_RES(CHIPS)':
 'B': CDS_PINID='B';
NODE_NAME     R3223 2
 '@S9S_MB_2U_LIB.S9S_MB_2U(SCH_1):PAGE224_I133@PURE_QUANTA.Q_RES(CHIPS)':
 'B': CDS_PINID='B';
NODE_NAME     C1841 1
 '@S9S_MB_2U_LIB.S9S_MB_2U(SCH_1):PAGE156_I65@PURE_QUANTA.Q_CAP(CHIPS)':
 'A': CDS_PINID='A';
NODE_NAME     R3241 2
 '@S9S_MB_2U_LIB.S9S_MB_2U(SCH_1):PAGE228_I258@PURE_QUANTA.Q_RES(CHIPS)':
 'B': CDS_PINID='B';
NODE_NAME     R3240 2
 '@S9S_MB_2U_LIB.S9S_MB_2U(SCH_1):PAGE228_I259@PURE_QUANTA.Q_RES(CHIPS)':
 'B': CDS_PINID='B';
NODE_NAME     R3242 2
 '@S9S_MB_2U_LIB.S9S_MB_2U(SCH_1):PAGE228_I260@PURE_QUANTA.Q_RES(CHIPS)':
 'B': CDS_PINID='B';
NODE_NAME     R3243 2
 '@S9S_MB_2U_LIB.S9S_MB_2U(SCH_1):PAGE228_I261@PURE_QUANTA.Q_RES(CHIPS)':
 'B': CDS_PINID='B';
NODE_NAME     U235 1
 '@S9S_MB_2U_LIB.S9S_MB_2U(SCH_1):PAGE216_I5@PURE_QUANTA.PCA9617ADP(CHIPS)':
 'VCCA': CDS_PINID='VCCA';
NODE_NAME     C1859 1
 '@S9S_MB_2U_LIB.S9S_MB_2U(SCH_1):PAGE216_I10@PURE_QUANTA.Q_CAP(CHIPS)':
 'A': CDS_PINID='A';
NODE_NAME     C1860 1
 '@S9S_MB_2U_LIB.S9S_MB_2U(SCH_1):PAGE216_I17@PURE_QUANTA.Q_CAP(CHIPS)':
 'A': CDS_PINID='A';
NODE_NAME     U236 1
 '@S9S_MB_2U_LIB.S9S_MB_2U(SCH_1):PAGE216_I28@PURE_QUANTA.PCA9617ADP(CHIPS)':
 'VCCA': CDS_PINID='VCCA';
NODE_NAME     R3277 1
 '@S9S_MB_2U_LIB.S9S_MB_2U(SCH_1):PAGE136_I16@PURE_QUANTA.Q_RES(CHIPS)':
 'A': CDS_PINID='A';
NODE_NAME     C1867 1
 '@S9S_MB_2U_LIB.S9S_MB_2U(SCH_1):PAGE136_I48@PURE_QUANTA.Q_CAP(CHIPS)':
 'A': CDS_PINID='A';
NODE_NAME     R3289 1
 '@S9S_MB_2U_LIB.S9S_MB_2U(SCH_1):PAGE136_I69@PURE_QUANTA.Q_RES(CHIPS)':
 'A': CDS_PINID='A';
NODE_NAME     U241 8
 '@S9S_MB_2U_LIB.S9S_MB_2U(SCH_1):PAGE170_I1@PURE_QUANTA.74LVC2G08DP(CHIPS)':
 'VCC': CDS_PINID='VCC';
NODE_NAME     U240 8
 '@S9S_MB_2U_LIB.S9S_MB_2U(SCH_1):PAGE170_I11@PURE_QUANTA.74LVC2G08DP(CHIPS)':
 'VCC': CDS_PINID='VCC';
NODE_NAME     U242 8
 '@S9S_MB_2U_LIB.S9S_MB_2U(SCH_1):PAGE170_I13@PURE_QUANTA.74LVC2G08DP(CHIPS)':
 'VCC': CDS_PINID='VCC';
NODE_NAME     U243 5
 '@S9S_MB_2U_LIB.S9S_MB_2U(SCH_1):PAGE170_I15@PURE_QUANTA.NC7SB3157(CHIPS)':
 'VCC': CDS_PINID='VCC';
NODE_NAME     U244 5
 '@S9S_MB_2U_LIB.S9S_MB_2U(SCH_1):PAGE170_I16@PURE_QUANTA.NC7SB3157(CHIPS)':
 'VCC': CDS_PINID='VCC';
NODE_NAME     U246 5
 '@S9S_MB_2U_LIB.S9S_MB_2U(SCH_1):PAGE170_I17@PURE_QUANTA.NC7SB3157(CHIPS)':
 'VCC': CDS_PINID='VCC';
NODE_NAME     U245 5
 '@S9S_MB_2U_LIB.S9S_MB_2U(SCH_1):PAGE170_I18@PURE_QUANTA.NC7SB3157(CHIPS)':
 'VCC': CDS_PINID='VCC';
NODE_NAME     C1875 1
 '@S9S_MB_2U_LIB.S9S_MB_2U(SCH_1):PAGE170_I21@PURE_QUANTA.Q_CAP(CHIPS)':
 'A': CDS_PINID='A';
NODE_NAME     C1874 1
 '@S9S_MB_2U_LIB.S9S_MB_2U(SCH_1):PAGE170_I22@PURE_QUANTA.Q_CAP(CHIPS)':
 'A': CDS_PINID='A';
NODE_NAME     C1880 1
 '@S9S_MB_2U_LIB.S9S_MB_2U(SCH_1):PAGE170_I27@PURE_QUANTA.Q_CAP(CHIPS)':
 'A': CDS_PINID='A';
NODE_NAME     C1879 1
 '@S9S_MB_2U_LIB.S9S_MB_2U(SCH_1):PAGE170_I31@PURE_QUANTA.Q_CAP(CHIPS)':
 'A': CDS_PINID='A';
NODE_NAME     C1877 1
 '@S9S_MB_2U_LIB.S9S_MB_2U(SCH_1):PAGE170_I34@PURE_QUANTA.Q_CAP(CHIPS)':
 'A': CDS_PINID='A';
NODE_NAME     C1878 1
 '@S9S_MB_2U_LIB.S9S_MB_2U(SCH_1):PAGE170_I37@PURE_QUANTA.Q_CAP(CHIPS)':
 'A': CDS_PINID='A';
NODE_NAME     C1876 1
 '@S9S_MB_2U_LIB.S9S_MB_2U(SCH_1):PAGE170_I41@PURE_QUANTA.Q_CAP(CHIPS)':
 'A': CDS_PINID='A';
NODE_NAME     R2133 1
 '@S9S_MB_2U_LIB.S9S_MB_2U(SCH_1):PAGE189_I86@PURE_QUANTA.Q_RES(CHIPS)':
 'A': CDS_PINID='A';
NODE_NAME     R1320 1
 '@S9S_MB_2U_LIB.S9S_MB_2U(SCH_1):PAGE189_I89@PURE_QUANTA.Q_RES(CHIPS)':
 'A': CDS_PINID='A';
NODE_NAME     R1325 1
 '@S9S_MB_2U_LIB.S9S_MB_2U(SCH_1):PAGE189_I93@PURE_QUANTA.Q_RES(CHIPS)':
 'A': CDS_PINID='A';
NODE_NAME     R1339 1
 '@S9S_MB_2U_LIB.S9S_MB_2U(SCH_1):PAGE189_I100@PURE_QUANTA.Q_RES(CHIPS)':
 'A': CDS_PINID='A';
NODE_NAME     R3321 1
 '@S9S_MB_2U_LIB.S9S_MB_2U(SCH_1):PAGE145_I158@PURE_QUANTA.Q_RES(CHIPS)':
 'A': CDS_PINID='A';
NODE_NAME     R3320 1
 '@S9S_MB_2U_LIB.S9S_MB_2U(SCH_1):PAGE145_I162@PURE_QUANTA.Q_RES(CHIPS)':
 'A': CDS_PINID='A';
NODE_NAME     C1803 1
 '@S9S_MB_2U_LIB.S9S_MB_2U(SCH_1):PAGE140_I166@PURE_QUANTA.Q_CAP(CHIPS)':
 'A': CDS_PINID='A';
NODE_NAME     R3318 1
 '@S9S_MB_2U_LIB.S9S_MB_2U(SCH_1):PAGE145_I171@PURE_QUANTA.Q_RES(CHIPS)':
 'A': CDS_PINID='A';
NODE_NAME     C1882 1
 '@S9S_MB_2U_LIB.S9S_MB_2U(SCH_1):PAGE201_I80@PURE_QUANTA.Q_CAP(CHIPS)':
 'A': CDS_PINID='A';
NODE_NAME     C1320 1
 '@S9S_MB_2U_LIB.S9S_MB_2U(SCH_1):PAGE313_I126@PURE_QUANTA.Q_CAP(CHIPS)':
 'A': CDS_PINID='A';
NODE_NAME     OSC2 4
 '@S9S_MB_2U_LIB.S9S_MB_2U(SCH_1):PAGE313_I127@PURE_QUANTA.Q_OSC4P(CHIPS)':
 'VDD': CDS_PINID='VDD';
NODE_NAME     R1099 1
 '@S9S_MB_2U_LIB.S9S_MB_2U(SCH_1):PAGE313_I129@PURE_QUANTA.Q_RES(CHIPS)':
 'A': CDS_PINID='A';
NODE_NAME     R1465 1
 '@S9S_MB_2U_LIB.S9S_MB_2U(SCH_1):PAGE312_I3@PURE_QUANTA.Q_RES(CHIPS)':
 'A': CDS_PINID='A';
NODE_NAME     R1106 1
 '@S9S_MB_2U_LIB.S9S_MB_2U(SCH_1):PAGE312_I5@PURE_QUANTA.Q_RES(CHIPS)':
 'A': CDS_PINID='A';
NODE_NAME     R1823 1
 '@S9S_MB_2U_LIB.S9S_MB_2U(SCH_1):PAGE311_I4@PURE_QUANTA.Q_RES(CHIPS)':
 'A': CDS_PINID='A';
NODE_NAME     R3249 1
 '@S9S_MB_2U_LIB.S9S_MB_2U(SCH_1):PAGE311_I29@PURE_QUANTA.Q_RES(CHIPS)':
 'A': CDS_PINID='A';
NODE_NAME     R3349 1
 '@S9S_MB_2U_LIB.S9S_MB_2U(SCH_1):PAGE202_I60@PURE_QUANTA.Q_RES(CHIPS)':
 'A': CDS_PINID='A';
NODE_NAME     R3346 1
 '@S9S_MB_2U_LIB.S9S_MB_2U(SCH_1):PAGE202_I63@PURE_QUANTA.Q_RES(CHIPS)':
 'A': CDS_PINID='A';
NODE_NAME     R3348 1
 '@S9S_MB_2U_LIB.S9S_MB_2U(SCH_1):PAGE202_I67@PURE_QUANTA.Q_RES(CHIPS)':
 'A': CDS_PINID='A';
NODE_NAME     R3347 1
 '@S9S_MB_2U_LIB.S9S_MB_2U(SCH_1):PAGE202_I72@PURE_QUANTA.Q_RES(CHIPS)':
 'A': CDS_PINID='A';
NODE_NAME     R3345 1
 '@S9S_MB_2U_LIB.S9S_MB_2U(SCH_1):PAGE202_I81@PURE_QUANTA.Q_RES(CHIPS)':
 'A': CDS_PINID='A';
NODE_NAME     R3344 1
 '@S9S_MB_2U_LIB.S9S_MB_2U(SCH_1):PAGE202_I108@PURE_QUANTA.Q_RES(CHIPS)':
 'A': CDS_PINID='A';
NODE_NAME     R2524 1
 '@S9S_MB_2U_LIB.S9S_MB_2U(SCH_1):PAGE270_I17@PURE_QUANTA.Q_RES(CHIPS)':
 'A': CDS_PINID='A';
NODE_NAME     R2525 1
 '@S9S_MB_2U_LIB.S9S_MB_2U(SCH_1):PAGE270_I18@PURE_QUANTA.Q_RES(CHIPS)':
 'A': CDS_PINID='A';
NODE_NAME     R2365 1
 '@S9S_MB_2U_LIB.S9S_MB_2U(SCH_1):PAGE252_I50@PURE_QUANTA.Q_RES(CHIPS)':
 'A': CDS_PINID='A';
NODE_NAME     R3458 1
 '@S9S_MB_2U_LIB.S9S_MB_2U(SCH_1):PAGE202_I119@PURE_QUANTA.Q_RES(CHIPS)':
 'A': CDS_PINID='A';
NODE_NAME     R4645 1
 '@S9S_MB_2U_LIB.S9S_MB_2U(SCH_1):PAGE159_I16@PURE_QUANTA.Q_RES(CHIPS)':
 'A': CDS_PINID='A';
NODE_NAME     R4655 1
 '@S9S_MB_2U_LIB.S9S_MB_2U(SCH_1):PAGE159_I62@PURE_QUANTA.Q_RES(CHIPS)':
 'A': CDS_PINID='A';
NODE_NAME     R4656 1
 '@S9S_MB_2U_LIB.S9S_MB_2U(SCH_1):PAGE159_I66@PURE_QUANTA.Q_RES(CHIPS)':
 'A': CDS_PINID='A';
NODE_NAME     R3386 1
 '@S9S_MB_2U_LIB.S9S_MB_2U(SCH_1):PAGE159_I81@PURE_QUANTA.Q_RES(CHIPS)':
 'A': CDS_PINID='A';
NODE_NAME     U328 15
 '@S9S_MB_2U_LIB.S9S_MB_2U(SCH_1):PAGE159_I95@PURE_QUANTA.DS125BR111RTWR(CHIPS)':
 'VIN': CDS_PINID='VIN';
NODE_NAME     R3435 1
 '@S9S_MB_2U_LIB.S9S_MB_2U(SCH_1):PAGE299_I23@PURE_QUANTA.Q_RES(CHIPS)':
 'A': CDS_PINID='A';
NODE_NAME     R3437 1
 '@S9S_MB_2U_LIB.S9S_MB_2U(SCH_1):PAGE299_I27@PURE_QUANTA.Q_RES(CHIPS)':
 'A': CDS_PINID='A';
NODE_NAME     R3434 1
 '@S9S_MB_2U_LIB.S9S_MB_2U(SCH_1):PAGE299_I39@PURE_QUANTA.Q_RES(CHIPS)':
 'A': CDS_PINID='A';
NODE_NAME     R3436 1
 '@S9S_MB_2U_LIB.S9S_MB_2U(SCH_1):PAGE299_I45@PURE_QUANTA.Q_RES(CHIPS)':
 'A': CDS_PINID='A';
NODE_NAME     R3433 1
 '@S9S_MB_2U_LIB.S9S_MB_2U(SCH_1):PAGE299_I49@PURE_QUANTA.Q_RES(CHIPS)':
 'A': CDS_PINID='A';
NODE_NAME     R3432 1
 '@S9S_MB_2U_LIB.S9S_MB_2U(SCH_1):PAGE299_I53@PURE_QUANTA.Q_RES(CHIPS)':
 'A': CDS_PINID='A';
NODE_NAME     R3438 1
 '@S9S_MB_2U_LIB.S9S_MB_2U(SCH_1):PAGE299_I55@PURE_QUANTA.Q_RES(CHIPS)':
 'A': CDS_PINID='A';
NODE_NAME     R3439 1
 '@S9S_MB_2U_LIB.S9S_MB_2U(SCH_1):PAGE299_I59@PURE_QUANTA.Q_RES(CHIPS)':
 'A': CDS_PINID='A';
NODE_NAME     U253 5
 '@S9S_MB_2U_LIB.S9S_MB_2U(SCH_1):PAGE160_I26@PURE_QUANTA.74LVC2G17GW(CHIPS)':
 'VCC': CDS_PINID='VCC';
NODE_NAME     C1958 1
 '@S9S_MB_2U_LIB.S9S_MB_2U(SCH_1):PAGE160_I29@PURE_QUANTA.Q_CAP(CHIPS)':
 'A': CDS_PINID='A';
NODE_NAME     R3456 1
 '@S9S_MB_2U_LIB.S9S_MB_2U(SCH_1):PAGE160_I124@PURE_QUANTA.Q_RES(CHIPS)':
 'A': CDS_PINID='A';
NODE_NAME     R3451 1
 '@S9S_MB_2U_LIB.S9S_MB_2U(SCH_1):PAGE160_I127@PURE_QUANTA.Q_RES(CHIPS)':
 'A': CDS_PINID='A';
NODE_NAME     R3429 1
 '@S9S_MB_2U_LIB.S9S_MB_2U(SCH_1):PAGE299_I130@PURE_QUANTA.Q_RES(CHIPS)':
 'A': CDS_PINID='A';
NODE_NAME     R3465 1
 '@S9S_MB_2U_LIB.S9S_MB_2U(SCH_1):PAGE299_I132@PURE_QUANTA.Q_RES(CHIPS)':
 'A': CDS_PINID='A';
NODE_NAME     R3464 1
 '@S9S_MB_2U_LIB.S9S_MB_2U(SCH_1):PAGE299_I134@PURE_QUANTA.Q_RES(CHIPS)':
 'A': CDS_PINID='A';
NODE_NAME     C1957 1
 '@S9S_MB_2U_LIB.S9S_MB_2U(SCH_1):PAGE160_I148@PURE_QUANTA.Q_CAP(CHIPS)':
 'A': CDS_PINID='A';
NODE_NAME     U252 5
 '@S9S_MB_2U_LIB.S9S_MB_2U(SCH_1):PAGE160_I153@PURE_QUANTA.74LVC2G17GW(CHIPS)':
 'VCC': CDS_PINID='VCC';
NODE_NAME     C1963 1
 '@S9S_MB_2U_LIB.S9S_MB_2U(SCH_1):PAGE296_I13@PURE_QUANTA.Q_CAP(CHIPS)':
 'A': CDS_PINID='A';
NODE_NAME     U255 5
 '@S9S_MB_2U_LIB.S9S_MB_2U(SCH_1):PAGE296_I16@PURE_QUANTA.74LVC2G07DW7(CHIPS)':
 'VCC': CDS_PINID='VCC';
NODE_NAME     R3459 1
 '@S9S_MB_2U_LIB.S9S_MB_2U(SCH_1):PAGE296_I29@PURE_QUANTA.Q_RES(CHIPS)':
 'A': CDS_PINID='A';
NODE_NAME     R3461 1
 '@S9S_MB_2U_LIB.S9S_MB_2U(SCH_1):PAGE296_I35@PURE_QUANTA.Q_RES(CHIPS)':
 'A': CDS_PINID='A';
NODE_NAME     R3453 1
 '@S9S_MB_2U_LIB.S9S_MB_2U(SCH_1):PAGE160_I164@PURE_QUANTA.Q_RES(CHIPS)':
 'A': CDS_PINID='A';
NODE_NAME     R3448 1
 '@S9S_MB_2U_LIB.S9S_MB_2U(SCH_1):PAGE160_I168@PURE_QUANTA.Q_RES(CHIPS)':
 'A': CDS_PINID='A';
NODE_NAME     U256 5
 '@S9S_MB_2U_LIB.S9S_MB_2U(SCH_1):PAGE160_I173@PURE_QUANTA.74LVC2G17GW(CHIPS)':
 'VCC': CDS_PINID='VCC';
NODE_NAME     C1977 1
 '@S9S_MB_2U_LIB.S9S_MB_2U(SCH_1):PAGE160_I175@PURE_QUANTA.Q_CAP(CHIPS)':
 'A': CDS_PINID='A';
NODE_NAME     R3470 1
 '@S9S_MB_2U_LIB.S9S_MB_2U(SCH_1):PAGE299_I145@PURE_QUANTA.Q_RES(CHIPS)':
 'A': CDS_PINID='A';
NODE_NAME     R3475 1
 '@S9S_MB_2U_LIB.S9S_MB_2U(SCH_1):PAGE299_I154@PURE_QUANTA.Q_RES(CHIPS)':
 'A': CDS_PINID='A';
NODE_NAME     R3474 1
 '@S9S_MB_2U_LIB.S9S_MB_2U(SCH_1):PAGE299_I158@PURE_QUANTA.Q_RES(CHIPS)':
 'A': CDS_PINID='A';
NODE_NAME     R3487 1
 '@S9S_MB_2U_LIB.S9S_MB_2U(SCH_1):PAGE299_I166@PURE_QUANTA.Q_RES(CHIPS)':
 'A': CDS_PINID='A';
NODE_NAME     R3488 1
 '@S9S_MB_2U_LIB.S9S_MB_2U(SCH_1):PAGE296_I40@PURE_QUANTA.Q_RES(CHIPS)':
 'A': CDS_PINID='A';
NODE_NAME     R3492 1
 '@S9S_MB_2U_LIB.S9S_MB_2U(SCH_1):PAGE296_I47@PURE_QUANTA.Q_RES(CHIPS)':
 'A': CDS_PINID='A';
NODE_NAME     U257 5
 '@S9S_MB_2U_LIB.S9S_MB_2U(SCH_1):PAGE296_I50@PURE_QUANTA.74LVC2G07DW7(CHIPS)':
 'VCC': CDS_PINID='VCC';
NODE_NAME     R3494 1
 '@S9S_MB_2U_LIB.S9S_MB_2U(SCH_1):PAGE296_I55@PURE_QUANTA.Q_RES(CHIPS)':
 'A': CDS_PINID='A';
NODE_NAME     R3490 1
 '@S9S_MB_2U_LIB.S9S_MB_2U(SCH_1):PAGE296_I57@PURE_QUANTA.Q_RES(CHIPS)':
 'A': CDS_PINID='A';
NODE_NAME     C1979 1
 '@S9S_MB_2U_LIB.S9S_MB_2U(SCH_1):PAGE296_I67@PURE_QUANTA.Q_CAP(CHIPS)':
 'A': CDS_PINID='A';
NODE_NAME     R3498 1
 '@S9S_MB_2U_LIB.S9S_MB_2U(SCH_1):PAGE299_I167@PURE_QUANTA.Q_RES(CHIPS)':
 'A': CDS_PINID='A';
NODE_NAME     R3512 1
 '@S9S_MB_2U_LIB.S9S_MB_2U(SCH_1):PAGE145_I174@PURE_QUANTA.Q_RES(CHIPS)':
 'A': CDS_PINID='A';
NODE_NAME     R3514 1
 '@S9S_MB_2U_LIB.S9S_MB_2U(SCH_1):PAGE145_I175@PURE_QUANTA.Q_RES(CHIPS)':
 'A': CDS_PINID='A';
NODE_NAME     R3510 1
 '@S9S_MB_2U_LIB.S9S_MB_2U(SCH_1):PAGE145_I176@PURE_QUANTA.Q_RES(CHIPS)':
 'A': CDS_PINID='A';
NODE_NAME     R3317 1
 '@S9S_MB_2U_LIB.S9S_MB_2U(SCH_1):PAGE140_I190@PURE_QUANTA.Q_RES(CHIPS)':
 'A': CDS_PINID='A';
NODE_NAME     R3506 1
 '@S9S_MB_2U_LIB.S9S_MB_2U(SCH_1):PAGE140_I193@PURE_QUANTA.Q_RES(CHIPS)':
 'A': CDS_PINID='A';
NODE_NAME     R3504 1
 '@S9S_MB_2U_LIB.S9S_MB_2U(SCH_1):PAGE299_I174@PURE_QUANTA.Q_RES(CHIPS)':
 'A': CDS_PINID='A';
NODE_NAME     R3503 1
 '@S9S_MB_2U_LIB.S9S_MB_2U(SCH_1):PAGE299_I177@PURE_QUANTA.Q_RES(CHIPS)':
 'A': CDS_PINID='A';
NODE_NAME     R3525 1
 '@S9S_MB_2U_LIB.S9S_MB_2U(SCH_1):PAGE299_I184@PURE_QUANTA.Q_RES(CHIPS)':
 'A': CDS_PINID='A';
NODE_NAME     R2910 1
 '@S9S_MB_2U_LIB.S9S_MB_2U(SCH_1):PAGE160_I187@PURE_QUANTA.Q_RES(CHIPS)':
 'A': CDS_PINID='A';
NODE_NAME     R2914 1
 '@S9S_MB_2U_LIB.S9S_MB_2U(SCH_1):PAGE160_I192@PURE_QUANTA.Q_RES(CHIPS)':
 'A': CDS_PINID='A';
NODE_NAME     C1997 1
 '@S9S_MB_2U_LIB.S9S_MB_2U(SCH_1):PAGE183_I89@PURE_QUANTA.Q_CAP(CHIPS)':
 'A': CDS_PINID='A';
NODE_NAME     C2013 1
 '@S9S_MB_2U_LIB.S9S_MB_2U(SCH_1):PAGE163_I42@PURE_QUANTA.Q_CAP(CHIPS)':
 'A': CDS_PINID='A';
NODE_NAME     U264 9
 '@S9S_MB_2U_LIB.S9S_MB_2U(SCH_1):PAGE163_I46@PURE_QUANTA.INA230AIRGTR(CHIPS)':
 'VS': CDS_PINID='VS';
NODE_NAME     C2014 1
 '@S9S_MB_2U_LIB.S9S_MB_2U(SCH_1):PAGE163_I65@PURE_QUANTA.Q_CAP(CHIPS)':
 'A': CDS_PINID='A';
NODE_NAME     U265 9
 '@S9S_MB_2U_LIB.S9S_MB_2U(SCH_1):PAGE163_I69@PURE_QUANTA.INA230AIRGTR(CHIPS)':
 'VS': CDS_PINID='VS';
NODE_NAME     U266 9
 '@S9S_MB_2U_LIB.S9S_MB_2U(SCH_1):PAGE295_I30@PURE_QUANTA.INA230AIRGTR(CHIPS)':
 'VS': CDS_PINID='VS';
NODE_NAME     C2015 1
 '@S9S_MB_2U_LIB.S9S_MB_2U(SCH_1):PAGE295_I34@PURE_QUANTA.Q_CAP(CHIPS)':
 'A': CDS_PINID='A';
NODE_NAME     R3623 1
 '@S9S_MB_2U_LIB.S9S_MB_2U(SCH_1):PAGE163_I86@PURE_QUANTA.Q_RES(CHIPS)':
 'A': CDS_PINID='A';
NODE_NAME     R3621 1
 '@S9S_MB_2U_LIB.S9S_MB_2U(SCH_1):PAGE163_I87@PURE_QUANTA.Q_RES(CHIPS)':
 'A': CDS_PINID='A';
NODE_NAME     R3624 1
 '@S9S_MB_2U_LIB.S9S_MB_2U(SCH_1):PAGE163_I89@PURE_QUANTA.Q_RES(CHIPS)':
 'A': CDS_PINID='A';
NODE_NAME     R3622 1
 '@S9S_MB_2U_LIB.S9S_MB_2U(SCH_1):PAGE163_I90@PURE_QUANTA.Q_RES(CHIPS)':
 'A': CDS_PINID='A';
NODE_NAME     R3628 1
 '@S9S_MB_2U_LIB.S9S_MB_2U(SCH_1):PAGE295_I88@PURE_QUANTA.Q_RES(CHIPS)':
 'A': CDS_PINID='A';
NODE_NAME     R3627 1
 '@S9S_MB_2U_LIB.S9S_MB_2U(SCH_1):PAGE295_I89@PURE_QUANTA.Q_RES(CHIPS)':
 'A': CDS_PINID='A';
NODE_NAME     R3638 1
 '@S9S_MB_2U_LIB.S9S_MB_2U(SCH_1):PAGE197_I378@PURE_QUANTA.Q_RES(CHIPS)':
 'A': CDS_PINID='A';
NODE_NAME     R3639 1
 '@S9S_MB_2U_LIB.S9S_MB_2U(SCH_1):PAGE197_I379@PURE_QUANTA.Q_RES(CHIPS)':
 'A': CDS_PINID='A';
NODE_NAME     R3640 1
 '@S9S_MB_2U_LIB.S9S_MB_2U(SCH_1):PAGE197_I380@PURE_QUANTA.Q_RES(CHIPS)':
 'A': CDS_PINID='A';
NODE_NAME     R3641 1
 '@S9S_MB_2U_LIB.S9S_MB_2U(SCH_1):PAGE197_I381@PURE_QUANTA.Q_RES(CHIPS)':
 'A': CDS_PINID='A';
NODE_NAME     R3642 1
 '@S9S_MB_2U_LIB.S9S_MB_2U(SCH_1):PAGE197_I382@PURE_QUANTA.Q_RES(CHIPS)':
 'A': CDS_PINID='A';
NODE_NAME     R3643 1
 '@S9S_MB_2U_LIB.S9S_MB_2U(SCH_1):PAGE197_I383@PURE_QUANTA.Q_RES(CHIPS)':
 'A': CDS_PINID='A';
NODE_NAME     R3660 1
 '@S9S_MB_2U_LIB.S9S_MB_2U(SCH_1):PAGE155_I159@PURE_QUANTA.Q_RES(CHIPS)':
 'A': CDS_PINID='A';
NODE_NAME     R3655 1
 '@S9S_MB_2U_LIB.S9S_MB_2U(SCH_1):PAGE155_I161@PURE_QUANTA.Q_RES(CHIPS)':
 'A': CDS_PINID='A';
NODE_NAME     R3663 1
 '@S9S_MB_2U_LIB.S9S_MB_2U(SCH_1):PAGE155_I186@PURE_QUANTA.Q_RES(CHIPS)':
 'A': CDS_PINID='A';
NODE_NAME     R3656 1
 '@S9S_MB_2U_LIB.S9S_MB_2U(SCH_1):PAGE155_I194@PURE_QUANTA.Q_RES(CHIPS)':
 'A': CDS_PINID='A';
NODE_NAME     R3657 1
 '@S9S_MB_2U_LIB.S9S_MB_2U(SCH_1):PAGE155_I195@PURE_QUANTA.Q_RES(CHIPS)':
 'A': CDS_PINID='A';
NODE_NAME     R3658 1
 '@S9S_MB_2U_LIB.S9S_MB_2U(SCH_1):PAGE155_I196@PURE_QUANTA.Q_RES(CHIPS)':
 'A': CDS_PINID='A';
NODE_NAME     R3659 1
 '@S9S_MB_2U_LIB.S9S_MB_2U(SCH_1):PAGE155_I198@PURE_QUANTA.Q_RES(CHIPS)':
 'A': CDS_PINID='A';
NODE_NAME     L16 1
 '@S9S_MB_2U_LIB.S9S_MB_2U(SCH_1):PAGE239_I118@PURE_QUANTA.Q_INDUCTOR(CHIPS)':
 '1': CDS_PINID='\1\';
NODE_NAME     R2907 1
 '@S9S_MB_2U_LIB.S9S_MB_2U(SCH_1):PAGE239_I141@PURE_QUANTA.Q_RES(CHIPS)':
 'A': CDS_PINID='A';
NODE_NAME     R3667 1
 '@S9S_MB_2U_LIB.S9S_MB_2U(SCH_1):PAGE239_I224@PURE_QUANTA.Q_RES(CHIPS)':
 'A': CDS_PINID='A';
NODE_NAME     R3669 1
 '@S9S_MB_2U_LIB.S9S_MB_2U(SCH_1):PAGE239_I228@PURE_QUANTA.Q_RES(CHIPS)':
 'A': CDS_PINID='A';
NODE_NAME     C2010 1
 '@S9S_MB_2U_LIB.S9S_MB_2U(SCH_1):PAGE161_I16@PURE_QUANTA.Q_CAP(CHIPS)':
 'A': CDS_PINID='A';
NODE_NAME     R3703 1
 '@S9S_MB_2U_LIB.S9S_MB_2U(SCH_1):PAGE221_I3@PURE_QUANTA.Q_RES(CHIPS)':
 'A': CDS_PINID='A';
NODE_NAME     R3706 1
 '@S9S_MB_2U_LIB.S9S_MB_2U(SCH_1):PAGE221_I9@PURE_QUANTA.Q_RES(CHIPS)':
 'A': CDS_PINID='A';
NODE_NAME     R3708 1
 '@S9S_MB_2U_LIB.S9S_MB_2U(SCH_1):PAGE221_I10@PURE_QUANTA.Q_RES(CHIPS)':
 'A': CDS_PINID='A';
NODE_NAME     R3732 1
 '@S9S_MB_2U_LIB.S9S_MB_2U(SCH_1):PAGE221_I34@PURE_QUANTA.Q_RES(CHIPS)':
 'A': CDS_PINID='A';
NODE_NAME     R3729 1
 '@S9S_MB_2U_LIB.S9S_MB_2U(SCH_1):PAGE221_I48@PURE_QUANTA.Q_RES(CHIPS)':
 'A': CDS_PINID='A';
NODE_NAME     R3730 1
 '@S9S_MB_2U_LIB.S9S_MB_2U(SCH_1):PAGE221_I49@PURE_QUANTA.Q_RES(CHIPS)':
 'A': CDS_PINID='A';
NODE_NAME     R3728 1
 '@S9S_MB_2U_LIB.S9S_MB_2U(SCH_1):PAGE221_I50@PURE_QUANTA.Q_RES(CHIPS)':
 'A': CDS_PINID='A';
NODE_NAME     R3727 1
 '@S9S_MB_2U_LIB.S9S_MB_2U(SCH_1):PAGE221_I51@PURE_QUANTA.Q_RES(CHIPS)':
 'A': CDS_PINID='A';
NODE_NAME     R3726 1
 '@S9S_MB_2U_LIB.S9S_MB_2U(SCH_1):PAGE221_I52@PURE_QUANTA.Q_RES(CHIPS)':
 'A': CDS_PINID='A';
NODE_NAME     R3725 1
 '@S9S_MB_2U_LIB.S9S_MB_2U(SCH_1):PAGE221_I53@PURE_QUANTA.Q_RES(CHIPS)':
 'A': CDS_PINID='A';
NODE_NAME     R3723 1
 '@S9S_MB_2U_LIB.S9S_MB_2U(SCH_1):PAGE221_I55@PURE_QUANTA.Q_RES(CHIPS)':
 'A': CDS_PINID='A';
NODE_NAME     R3724 1
 '@S9S_MB_2U_LIB.S9S_MB_2U(SCH_1):PAGE221_I56@PURE_QUANTA.Q_RES(CHIPS)':
 'A': CDS_PINID='A';
NODE_NAME     R3731 1
 '@S9S_MB_2U_LIB.S9S_MB_2U(SCH_1):PAGE221_I98@PURE_QUANTA.Q_RES(CHIPS)':
 'A': CDS_PINID='A';
NODE_NAME     C2067 1
 '@S9S_MB_2U_LIB.S9S_MB_2U(SCH_1):PAGE295_I125@PURE_QUANTA.Q_CAP(CHIPS)':
 'A': CDS_PINID='A';
NODE_NAME     U276 9
 '@S9S_MB_2U_LIB.S9S_MB_2U(SCH_1):PAGE295_I129@PURE_QUANTA.INA230AIRGTR(CHIPS)':
 'VS': CDS_PINID='VS';
NODE_NAME     U263 9
 '@S9S_MB_2U_LIB.S9S_MB_2U(SCH_1):PAGE163_I94@PURE_QUANTA.INA230AIRGTR(CHIPS)':
 'VS': CDS_PINID='VS';
NODE_NAME     C2012 1
 '@S9S_MB_2U_LIB.S9S_MB_2U(SCH_1):PAGE163_I98@PURE_QUANTA.Q_CAP(CHIPS)':
 'A': CDS_PINID='A';
NODE_NAME     U278 5
 '@S9S_MB_2U_LIB.S9S_MB_2U(SCH_1):PAGE230_I31@PURE_QUANTA.74LVC1G08W57(CHIPS)':
 'VCC': CDS_PINID='VCC';
NODE_NAME     R2304 1
 '@S9S_MB_2U_LIB.S9S_MB_2U(SCH_1):PAGE297_I159@PURE_QUANTA.Q_RES(CHIPS)':
 'A': CDS_PINID='A';
NODE_NAME     U145 5
 '@S9S_MB_2U_LIB.S9S_MB_2U(SCH_1):PAGE297_I163@PURE_QUANTA.74LVC1G126SE7(CHIPS)':
 'VCC': CDS_PINID='VCC';
NODE_NAME     R2282 1
 '@S9S_MB_2U_LIB.S9S_MB_2U(SCH_1):PAGE297_I169@PURE_QUANTA.Q_RES(CHIPS)':
 'A': CDS_PINID='A';
NODE_NAME     C1614 1
 '@S9S_MB_2U_LIB.S9S_MB_2U(SCH_1):PAGE297_I170@PURE_QUANTA.Q_CAP(CHIPS)':
 'A': CDS_PINID='A';
NODE_NAME     R3298 1
 '@S9S_MB_2U_LIB.S9S_MB_2U(SCH_1):PAGE182_I306@PURE_QUANTA.Q_RES(CHIPS)':
 'A': CDS_PINID='A';
NODE_NAME     C1873 1
 '@S9S_MB_2U_LIB.S9S_MB_2U(SCH_1):PAGE182_I308@PURE_QUANTA.Q_CAP(CHIPS)':
 'A': CDS_PINID='A';
NODE_NAME     U239 5
 '@S9S_MB_2U_LIB.S9S_MB_2U(SCH_1):PAGE182_I315@PURE_QUANTA.74LVC1G126SE7(CHIPS)':
 'VCC': CDS_PINID='VCC';
NODE_NAME     R3296 1
 '@S9S_MB_2U_LIB.S9S_MB_2U(SCH_1):PAGE182_I324@PURE_QUANTA.Q_RES(CHIPS)':
 'A': CDS_PINID='A';
NODE_NAME     C2007 1
 '@S9S_MB_2U_LIB.S9S_MB_2U(SCH_1):PAGE182_I326@PURE_QUANTA.Q_CAP(CHIPS)':
 'A': CDS_PINID='A';
NODE_NAME     U259 5
 '@S9S_MB_2U_LIB.S9S_MB_2U(SCH_1):PAGE182_I327@PURE_QUANTA.SN74LVC2G07DCKR(CHIPS)':
 'VCC': CDS_PINID='VCC';
NODE_NAME     R2121 1
 '@S9S_MB_2U_LIB.S9S_MB_2U(SCH_1):PAGE182_I337@PURE_QUANTA.Q_RES(CHIPS)':
 'A': CDS_PINID='A';
NODE_NAME     U279 8
 '@S9S_MB_2U_LIB.S9S_MB_2U(SCH_1):PAGE183_I93@PURE_QUANTA.PCA9617ADP(CHIPS)':
 'VCCB': CDS_PINID='VCCB';
NODE_NAME     R3771 1
 '@S9S_MB_2U_LIB.S9S_MB_2U(SCH_1):PAGE297_I291@PURE_QUANTA.Q_RES(CHIPS)':
 'A': CDS_PINID='A';
NODE_NAME     R2125 1
 '@S9S_MB_2U_LIB.S9S_MB_2U(SCH_1):PAGE297_I296@PURE_QUANTA.Q_RES(CHIPS)':
 'A': CDS_PINID='A';
NODE_NAME     R3773 1
 '@S9S_MB_2U_LIB.S9S_MB_2U(SCH_1):PAGE297_I299@PURE_QUANTA.Q_RES(CHIPS)':
 'A': CDS_PINID='A';
NODE_NAME     C1592 1
 '@S9S_MB_2U_LIB.S9S_MB_2U(SCH_1):PAGE297_I304@PURE_QUANTA.Q_CAP(CHIPS)':
 'A': CDS_PINID='A';
NODE_NAME     U134 5
 '@S9S_MB_2U_LIB.S9S_MB_2U(SCH_1):PAGE297_I305@PURE_QUANTA.74LVC2G07DW7(CHIPS)':
 'VCC': CDS_PINID='VCC';
NODE_NAME     U150 5
 '@S9S_MB_2U_LIB.S9S_MB_2U(SCH_1):PAGE213_I2@PURE_QUANTA.74LVC2G17GW(CHIPS)':
 'VCC': CDS_PINID='VCC';
NODE_NAME     C1619 1
 '@S9S_MB_2U_LIB.S9S_MB_2U(SCH_1):PAGE213_I5@PURE_QUANTA.Q_CAP(CHIPS)':
 'A': CDS_PINID='A';
NODE_NAME     R2355 1
 '@S9S_MB_2U_LIB.S9S_MB_2U(SCH_1):PAGE213_I7@PURE_QUANTA.Q_RES(CHIPS)':
 'A': CDS_PINID='A';
NODE_NAME     R4761 1
 '@S9S_MB_2U_LIB.S9S_MB_2U(SCH_1):PAGE131_I70@PURE_QUANTA.Q_RES(CHIPS)':
 'A': CDS_PINID='A';
NODE_NAME     U286 5
 '@S9S_MB_2U_LIB.S9S_MB_2U(SCH_1):PAGE307_I80@PURE_QUANTA.74LVC1G126SE7(CHIPS)':
 'VCC': CDS_PINID='VCC';
NODE_NAME     U225 5
 '@S9S_MB_2U_LIB.S9S_MB_2U(SCH_1):PAGE156_I74@PURE_QUANTA.74LVC1G126SE7(CHIPS)':
 'VCC': CDS_PINID='VCC';
NODE_NAME     U217 5
 '@S9S_MB_2U_LIB.S9S_MB_2U(SCH_1):PAGE156_I79@PURE_QUANTA.74LVC1G126SE7(CHIPS)':
 'VCC': CDS_PINID='VCC';
NODE_NAME     U82 5
 '@S9S_MB_2U_LIB.S9S_MB_2U(SCH_1):PAGE152_I79@PURE_QUANTA.74LVC1G126SE7(CHIPS)':
 'VCC': CDS_PINID='VCC';
NODE_NAME     U204 5
 '@S9S_MB_2U_LIB.S9S_MB_2U(SCH_1):PAGE140_I195@PURE_QUANTA.74LVC1G126SE7(CHIPS)':
 'VCC': CDS_PINID='VCC';
NODE_NAME     U154 5
 '@S9S_MB_2U_LIB.S9S_MB_2U(SCH_1):PAGE190_I95@PURE_QUANTA.74LVC1G07SE7(CHIPS)':
 'VCC': CDS_PINID='VCC';
NODE_NAME     R1841 1
 '@S9S_MB_2U_LIB.S9S_MB_2U(SCH_1):PAGE207_I275@PURE_QUANTA.Q_RES(CHIPS)':
 'A': CDS_PINID='A';
NODE_NAME     R494 1
 '@S9S_MB_2U_LIB.S9S_MB_2U(SCH_1):PAGE174_I98@PURE_QUANTA.Q_RES(CHIPS)':
 'A': CDS_PINID='A';
NODE_NAME     R3938 2
 '@S9S_MB_2U_LIB.S9S_MB_2U(SCH_1):PAGE175_I272@PURE_QUANTA.Q_RES(CHIPS)':
 'B': CDS_PINID='B';
NODE_NAME     PR3967 1
 '@S9S_MB_2U_LIB.S9S_MB_2U(SCH_1):PAGE324_I39@PURE_QUANTA.Q_RES(CHIPS)':
 'A': CDS_PINID='A';
NODE_NAME     R3977 1
 '@S9S_MB_2U_LIB.S9S_MB_2U(SCH_1):PAGE324_I48@PURE_QUANTA.Q_RES(CHIPS)':
 'A': CDS_PINID='A';
NODE_NAME     PC2200 1
 '@S9S_MB_2U_LIB.S9S_MB_2U(SCH_1):PAGE323_I9@PURE_QUANTA.Q_CAP(CHIPS)':
 'A': CDS_PINID='A';
NODE_NAME     C2246 1
 '@S9S_MB_2U_LIB.S9S_MB_2U(SCH_1):PAGE322_I9@PURE_QUANTA.Q_CAP(CHIPS)':
 'A': CDS_PINID='A';
NODE_NAME     U304 14
 '@S9S_MB_2U_LIB.S9S_MB_2U(SCH_1):PAGE322_I27@PURE_QUANTA.GTL2014PW(CHIPS)':
 'VCC': CDS_PINID='VCC';
NODE_NAME     U305 14
 '@S9S_MB_2U_LIB.S9S_MB_2U(SCH_1):PAGE322_I44@PURE_QUANTA.GTL2014PW(CHIPS)':
 'VCC': CDS_PINID='VCC';
NODE_NAME     C2247 1
 '@S9S_MB_2U_LIB.S9S_MB_2U(SCH_1):PAGE322_I59@PURE_QUANTA.Q_CAP(CHIPS)':
 'A': CDS_PINID='A';
NODE_NAME     R4078 1
 '@S9S_MB_2U_LIB.S9S_MB_2U(SCH_1):PAGE201_I127@PURE_QUANTA.Q_RES(CHIPS)':
 'A': CDS_PINID='A';
NODE_NAME     R4081 1
 '@S9S_MB_2U_LIB.S9S_MB_2U(SCH_1):PAGE201_I135@PURE_QUANTA.Q_RES(CHIPS)':
 'A': CDS_PINID='A';
NODE_NAME     R4080 1
 '@S9S_MB_2U_LIB.S9S_MB_2U(SCH_1):PAGE201_I142@PURE_QUANTA.Q_RES(CHIPS)':
 'A': CDS_PINID='A';
NODE_NAME     R1216 1
 '@S9S_MB_2U_LIB.S9S_MB_2U(SCH_1):PAGE80_I1@PURE_QUANTA.Q_RES(CHIPS)':
 'A': CDS_PINID='A';
NODE_NAME     R321 1
 '@S9S_MB_2U_LIB.S9S_MB_2U(SCH_1):PAGE80_I2@PURE_QUANTA.Q_RES(CHIPS)':
 'A': CDS_PINID='A';
NODE_NAME     R320 1
 '@S9S_MB_2U_LIB.S9S_MB_2U(SCH_1):PAGE80_I7@PURE_QUANTA.Q_RES(CHIPS)':
 'A': CDS_PINID='A';
NODE_NAME     R1217 1
 '@S9S_MB_2U_LIB.S9S_MB_2U(SCH_1):PAGE80_I22@PURE_QUANTA.Q_RES(CHIPS)':
 'A': CDS_PINID='A';
NODE_NAME     R327 1
 '@S9S_MB_2U_LIB.S9S_MB_2U(SCH_1):PAGE80_I25@PURE_QUANTA.Q_RES(CHIPS)':
 'A': CDS_PINID='A';
NODE_NAME     R326 1
 '@S9S_MB_2U_LIB.S9S_MB_2U(SCH_1):PAGE80_I26@PURE_QUANTA.Q_RES(CHIPS)':
 'A': CDS_PINID='A';
NODE_NAME     R325 1
 '@S9S_MB_2U_LIB.S9S_MB_2U(SCH_1):PAGE80_I27@PURE_QUANTA.Q_RES(CHIPS)':
 'A': CDS_PINID='A';
NODE_NAME     R1908 1
 '@S9S_MB_2U_LIB.S9S_MB_2U(SCH_1):PAGE153_I22@PURE_QUANTA.Q_RES(CHIPS)':
 'A': CDS_PINID='A';
NODE_NAME     PR3789 1
 '@S9S_MB_2U_LIB.S9S_MB_2U(SCH_1):PAGE153_I70@PURE_QUANTA.Q_RES(CHIPS)':
 'A': CDS_PINID='A';
NODE_NAME     R1150 1
 '@S9S_MB_2U_LIB.S9S_MB_2U(SCH_1):PAGE153_I74@PURE_QUANTA.Q_RES(CHIPS)':
 'A': CDS_PINID='A';
NODE_NAME     R4762 1
 '@S9S_MB_2U_LIB.S9S_MB_2U(SCH_1):PAGE153_I76@PURE_QUANTA.Q_RES(CHIPS)':
 'A': CDS_PINID='A';
NODE_NAME     R3816 1
 '@S9S_MB_2U_LIB.S9S_MB_2U(SCH_1):PAGE131_I80@PURE_QUANTA.Q_RES(CHIPS)':
 'A': CDS_PINID='A';
NODE_NAME     PC2208 1
 '@S9S_MB_2U_LIB.S9S_MB_2U(SCH_1):PAGE324_I17@PURE_QUANTA.Q_CAP(CHIPS)':
 'A': CDS_PINID='A';
NODE_NAME     R1857 1
 '@S9S_MB_2U_LIB.S9S_MB_2U(SCH_1):PAGE229_I18@PURE_QUANTA.Q_RES(CHIPS)':
 'A': CDS_PINID='A';
NODE_NAME     PR4007 2
 '@S9S_MB_2U_LIB.S9S_MB_2U(SCH_1):PAGE229_I48@PURE_QUANTA.Q_RES(CHIPS)':
 'B': CDS_PINID='B';
NODE_NAME     C1332 1
 '@S9S_MB_2U_LIB.S9S_MB_2U(SCH_1):PAGE246_I48@PURE_QUANTA.Q_CAP(CHIPS)':
 'A': CDS_PINID='A';
NODE_NAME     C1333 1
 '@S9S_MB_2U_LIB.S9S_MB_2U(SCH_1):PAGE246_I49@PURE_QUANTA.Q_CAP(CHIPS)':
 'A': CDS_PINID='A';
NODE_NAME     C1338 1
 '@S9S_MB_2U_LIB.S9S_MB_2U(SCH_1):PAGE246_I50@PURE_QUANTA.Q_CAP(CHIPS)':
 'A': CDS_PINID='A';
NODE_NAME     Q56 5
 '@S9S_MB_2U_LIB.S9S_MB_2U(SCH_1):PAGE246_I51@PURE_QUANTA.MOSFET_NCH_1D3S(CHIPS)':
 '5': CDS_PINID='\5\';
NODE_NAME     PR1647 1
 '@S9S_MB_2U_LIB.S9S_MB_2U(SCH_1):PAGE248_I26@PURE_QUANTA.Q_RES(CHIPS)':
 'A': CDS_PINID='A';
NODE_NAME     PR395 1
 '@S9S_MB_2U_LIB.S9S_MB_2U(SCH_1):PAGE249_I8@PURE_QUANTA.Q_RES(CHIPS)':
 'A': CDS_PINID='A';
NODE_NAME     R2406 1
 '@S9S_MB_2U_LIB.S9S_MB_2U(SCH_1):PAGE267_I9@PURE_QUANTA.Q_RES(CHIPS)':
 'A': CDS_PINID='A';
NODE_NAME     R2522 1
 '@S9S_MB_2U_LIB.S9S_MB_2U(SCH_1):PAGE270_I25@PURE_QUANTA.Q_RES(CHIPS)':
 'A': CDS_PINID='A';
NODE_NAME     R307 1
 '@S9S_MB_2U_LIB.S9S_MB_2U(SCH_1):PAGE270_I61@PURE_QUANTA.Q_RES(CHIPS)':
 'A': CDS_PINID='A';
NODE_NAME     R2573 1
 '@S9S_MB_2U_LIB.S9S_MB_2U(SCH_1):PAGE278_I73@PURE_QUANTA.Q_RES(CHIPS)':
 'A': CDS_PINID='A';
NODE_NAME     R2575 1
 '@S9S_MB_2U_LIB.S9S_MB_2U(SCH_1):PAGE282_I46@PURE_QUANTA.Q_RES(CHIPS)':
 'A': CDS_PINID='A';
NODE_NAME     R2583 1
 '@S9S_MB_2U_LIB.S9S_MB_2U(SCH_1):PAGE285_I27@PURE_QUANTA.Q_RES(CHIPS)':
 'A': CDS_PINID='A';
NODE_NAME     R2584 1
 '@S9S_MB_2U_LIB.S9S_MB_2U(SCH_1):PAGE286_I31@PURE_QUANTA.Q_RES(CHIPS)':
 'A': CDS_PINID='A';
NODE_NAME     L17 1
 '@S9S_MB_2U_LIB.S9S_MB_2U(SCH_1):PAGE201_I155@PURE_QUANTA.Q_INDUCTOR(CHIPS)':
 '1': CDS_PINID='\1\';
NODE_NAME     R4093 1
 '@S9S_MB_2U_LIB.S9S_MB_2U(SCH_1):PAGE295_I149@PURE_QUANTA.Q_RES(CHIPS)':
 'A': CDS_PINID='A';
NODE_NAME     R4094 1
 '@S9S_MB_2U_LIB.S9S_MB_2U(SCH_1):PAGE295_I151@PURE_QUANTA.Q_RES(CHIPS)':
 'A': CDS_PINID='A';
NODE_NAME     R4091 1
 '@S9S_MB_2U_LIB.S9S_MB_2U(SCH_1):PAGE163_I122@PURE_QUANTA.Q_RES(CHIPS)':
 'A': CDS_PINID='A';
NODE_NAME     R4090 1
 '@S9S_MB_2U_LIB.S9S_MB_2U(SCH_1):PAGE163_I124@PURE_QUANTA.Q_RES(CHIPS)':
 'A': CDS_PINID='A';
NODE_NAME     R4092 1
 '@S9S_MB_2U_LIB.S9S_MB_2U(SCH_1):PAGE163_I126@PURE_QUANTA.Q_RES(CHIPS)':
 'A': CDS_PINID='A';
NODE_NAME     R3529 1
 '@S9S_MB_2U_LIB.S9S_MB_2U(SCH_1):PAGE183_I99@PURE_QUANTA.Q_RES(CHIPS)':
 'A': CDS_PINID='A';
NODE_NAME     R3322 1
 '@S9S_MB_2U_LIB.S9S_MB_2U(SCH_1):PAGE201_I157@PURE_QUANTA.Q_RES(CHIPS)':
 'A': CDS_PINID='A';
NODE_NAME     R2909 1
 '@S9S_MB_2U_LIB.S9S_MB_2U(SCH_1):PAGE140_I198@PURE_QUANTA.Q_RES(CHIPS)':
 'A': CDS_PINID='A';
NODE_NAME     U248 5
 '@S9S_MB_2U_LIB.S9S_MB_2U(SCH_1):PAGE201_I158@PURE_QUANTA.74LVC1G32GW(CHIPS)':
 'VCC': CDS_PINID='VCC';
NODE_NAME     R4128 1
 '@S9S_MB_2U_LIB.S9S_MB_2U(SCH_1):PAGE143_I5@PURE_QUANTA.Q_RES(CHIPS)':
 'A': CDS_PINID='A';
NODE_NAME     R4125 1
 '@S9S_MB_2U_LIB.S9S_MB_2U(SCH_1):PAGE143_I9@PURE_QUANTA.Q_RES(CHIPS)':
 'A': CDS_PINID='A';
NODE_NAME     R4119 1
 '@S9S_MB_2U_LIB.S9S_MB_2U(SCH_1):PAGE143_I13@PURE_QUANTA.Q_RES(CHIPS)':
 'A': CDS_PINID='A';
NODE_NAME     R4130 1
 '@S9S_MB_2U_LIB.S9S_MB_2U(SCH_1):PAGE143_I21@PURE_QUANTA.Q_RES(CHIPS)':
 'A': CDS_PINID='A';
NODE_NAME     R4127 1
 '@S9S_MB_2U_LIB.S9S_MB_2U(SCH_1):PAGE143_I27@PURE_QUANTA.Q_RES(CHIPS)':
 'A': CDS_PINID='A';
NODE_NAME     R4123 1
 '@S9S_MB_2U_LIB.S9S_MB_2U(SCH_1):PAGE143_I31@PURE_QUANTA.Q_RES(CHIPS)':
 'A': CDS_PINID='A';
NODE_NAME     R4129 1
 '@S9S_MB_2U_LIB.S9S_MB_2U(SCH_1):PAGE143_I36@PURE_QUANTA.Q_RES(CHIPS)':
 'A': CDS_PINID='A';
NODE_NAME     R4126 1
 '@S9S_MB_2U_LIB.S9S_MB_2U(SCH_1):PAGE143_I43@PURE_QUANTA.Q_RES(CHIPS)':
 'A': CDS_PINID='A';
NODE_NAME     R4140 1
 '@S9S_MB_2U_LIB.S9S_MB_2U(SCH_1):PAGE143_I52@PURE_QUANTA.Q_RES(CHIPS)':
 'A': CDS_PINID='A';
NODE_NAME     R4142 1
 '@S9S_MB_2U_LIB.S9S_MB_2U(SCH_1):PAGE143_I60@PURE_QUANTA.Q_RES(CHIPS)':
 'A': CDS_PINID='A';
NODE_NAME     R4141 1
 '@S9S_MB_2U_LIB.S9S_MB_2U(SCH_1):PAGE143_I64@PURE_QUANTA.Q_RES(CHIPS)':
 'A': CDS_PINID='A';
NODE_NAME     R4137 1
 '@S9S_MB_2U_LIB.S9S_MB_2U(SCH_1):PAGE143_I72@PURE_QUANTA.Q_RES(CHIPS)':
 'A': CDS_PINID='A';
NODE_NAME     R4139 1
 '@S9S_MB_2U_LIB.S9S_MB_2U(SCH_1):PAGE143_I76@PURE_QUANTA.Q_RES(CHIPS)':
 'A': CDS_PINID='A';
NODE_NAME     R4138 1
 '@S9S_MB_2U_LIB.S9S_MB_2U(SCH_1):PAGE143_I81@PURE_QUANTA.Q_RES(CHIPS)':
 'A': CDS_PINID='A';
NODE_NAME     R4131 1
 '@S9S_MB_2U_LIB.S9S_MB_2U(SCH_1):PAGE143_I85@PURE_QUANTA.Q_RES(CHIPS)':
 'A': CDS_PINID='A';
NODE_NAME     R4133 1
 '@S9S_MB_2U_LIB.S9S_MB_2U(SCH_1):PAGE143_I95@PURE_QUANTA.Q_RES(CHIPS)':
 'A': CDS_PINID='A';
NODE_NAME     R4155 1
 '@S9S_MB_2U_LIB.S9S_MB_2U(SCH_1):PAGE143_I100@PURE_QUANTA.Q_RES(CHIPS)':
 'A': CDS_PINID='A';
NODE_NAME     R4156 1
 '@S9S_MB_2U_LIB.S9S_MB_2U(SCH_1):PAGE143_I101@PURE_QUANTA.Q_RES(CHIPS)':
 'A': CDS_PINID='A';
NODE_NAME     R4160 1
 '@S9S_MB_2U_LIB.S9S_MB_2U(SCH_1):PAGE139_I4@PURE_QUANTA.Q_RES(CHIPS)':
 'A': CDS_PINID='A';
NODE_NAME     R4162 1
 '@S9S_MB_2U_LIB.S9S_MB_2U(SCH_1):PAGE139_I9@PURE_QUANTA.Q_RES(CHIPS)':
 'A': CDS_PINID='A';
NODE_NAME     R4158 1
 '@S9S_MB_2U_LIB.S9S_MB_2U(SCH_1):PAGE139_I14@PURE_QUANTA.Q_RES(CHIPS)':
 'A': CDS_PINID='A';
NODE_NAME     R4165 1
 '@S9S_MB_2U_LIB.S9S_MB_2U(SCH_1):PAGE139_I18@PURE_QUANTA.Q_RES(CHIPS)':
 'A': CDS_PINID='A';
NODE_NAME     R4166 1
 '@S9S_MB_2U_LIB.S9S_MB_2U(SCH_1):PAGE139_I23@PURE_QUANTA.Q_RES(CHIPS)':
 'A': CDS_PINID='A';
NODE_NAME     R4164 1
 '@S9S_MB_2U_LIB.S9S_MB_2U(SCH_1):PAGE139_I27@PURE_QUANTA.Q_RES(CHIPS)':
 'A': CDS_PINID='A';
NODE_NAME     R4168 1
 '@S9S_MB_2U_LIB.S9S_MB_2U(SCH_1):PAGE139_I35@PURE_QUANTA.Q_RES(CHIPS)':
 'A': CDS_PINID='A';
NODE_NAME     R4169 1
 '@S9S_MB_2U_LIB.S9S_MB_2U(SCH_1):PAGE139_I39@PURE_QUANTA.Q_RES(CHIPS)':
 'A': CDS_PINID='A';
NODE_NAME     R4167 1
 '@S9S_MB_2U_LIB.S9S_MB_2U(SCH_1):PAGE139_I47@PURE_QUANTA.Q_RES(CHIPS)':
 'A': CDS_PINID='A';
NODE_NAME     R4176 1
 '@S9S_MB_2U_LIB.S9S_MB_2U(SCH_1):PAGE243_I16@PURE_QUANTA.Q_RES(CHIPS)':
 'A': CDS_PINID='A';
NODE_NAME     R4198 1
 '@S9S_MB_2U_LIB.S9S_MB_2U(SCH_1):PAGE161_I82@PURE_QUANTA.Q_RES(CHIPS)':
 'A': CDS_PINID='A';
NODE_NAME     R4206 1
 '@S9S_MB_2U_LIB.S9S_MB_2U(SCH_1):PAGE161_I86@PURE_QUANTA.Q_RES(CHIPS)':
 'A': CDS_PINID='A';
NODE_NAME     R4190 1
 '@S9S_MB_2U_LIB.S9S_MB_2U(SCH_1):PAGE161_I91@PURE_QUANTA.Q_RES(CHIPS)':
 'A': CDS_PINID='A';
NODE_NAME     R4204 1
 '@S9S_MB_2U_LIB.S9S_MB_2U(SCH_1):PAGE161_I94@PURE_QUANTA.Q_RES(CHIPS)':
 'A': CDS_PINID='A';
NODE_NAME     R4196 1
 '@S9S_MB_2U_LIB.S9S_MB_2U(SCH_1):PAGE161_I95@PURE_QUANTA.Q_RES(CHIPS)':
 'A': CDS_PINID='A';
NODE_NAME     R4188 1
 '@S9S_MB_2U_LIB.S9S_MB_2U(SCH_1):PAGE161_I101@PURE_QUANTA.Q_RES(CHIPS)':
 'A': CDS_PINID='A';
NODE_NAME     C2276 1
 '@S9S_MB_2U_LIB.S9S_MB_2U(SCH_1):PAGE161_I104@PURE_QUANTA.Q_CAP(CHIPS)':
 'A': CDS_PINID='A';
NODE_NAME     C2275 1
 '@S9S_MB_2U_LIB.S9S_MB_2U(SCH_1):PAGE161_I119@PURE_QUANTA.Q_CAP(CHIPS)':
 'A': CDS_PINID='A';
NODE_NAME     R4186 1
 '@S9S_MB_2U_LIB.S9S_MB_2U(SCH_1):PAGE161_I122@PURE_QUANTA.Q_RES(CHIPS)':
 'A': CDS_PINID='A';
NODE_NAME     R4194 1
 '@S9S_MB_2U_LIB.S9S_MB_2U(SCH_1):PAGE161_I128@PURE_QUANTA.Q_RES(CHIPS)':
 'A': CDS_PINID='A';
NODE_NAME     R4202 1
 '@S9S_MB_2U_LIB.S9S_MB_2U(SCH_1):PAGE161_I129@PURE_QUANTA.Q_RES(CHIPS)':
 'A': CDS_PINID='A';
NODE_NAME     C2274 1
 '@S9S_MB_2U_LIB.S9S_MB_2U(SCH_1):PAGE161_I139@PURE_QUANTA.Q_CAP(CHIPS)':
 'A': CDS_PINID='A';
NODE_NAME     R4184 1
 '@S9S_MB_2U_LIB.S9S_MB_2U(SCH_1):PAGE161_I142@PURE_QUANTA.Q_RES(CHIPS)':
 'A': CDS_PINID='A';
NODE_NAME     R4192 1
 '@S9S_MB_2U_LIB.S9S_MB_2U(SCH_1):PAGE161_I148@PURE_QUANTA.Q_RES(CHIPS)':
 'A': CDS_PINID='A';
NODE_NAME     R4200 1
 '@S9S_MB_2U_LIB.S9S_MB_2U(SCH_1):PAGE161_I149@PURE_QUANTA.Q_RES(CHIPS)':
 'A': CDS_PINID='A';
NODE_NAME     PR176 2
 '@S9S_MB_2U_LIB.S9S_MB_2U(SCH_1):PAGE252_I133@PURE_QUANTA.Q_RES(CHIPS)':
 'B': CDS_PINID='B';
NODE_NAME     R2398 1
 '@S9S_MB_2U_LIB.S9S_MB_2U(SCH_1):PAGE260_I79@PURE_QUANTA.Q_RES(CHIPS)':
 'A': CDS_PINID='A';
NODE_NAME     PR372 1
 '@S9S_MB_2U_LIB.S9S_MB_2U(SCH_1):PAGE264_I14@PURE_QUANTA.Q_RES(CHIPS)':
 'A': CDS_PINID='A';
NODE_NAME     R2357 1
 '@S9S_MB_2U_LIB.S9S_MB_2U(SCH_1):PAGE248_I32@PURE_QUANTA.Q_RES(CHIPS)':
 'A': CDS_PINID='A';
NODE_NAME     U308 5
 '@S9S_MB_2U_LIB.S9S_MB_2U(SCH_1):PAGE230_I37@PURE_QUANTA.74LVC2G07DW7(CHIPS)':
 'VCC': CDS_PINID='VCC';
NODE_NAME     C2283 1
 '@S9S_MB_2U_LIB.S9S_MB_2U(SCH_1):PAGE230_I40@PURE_QUANTA.Q_CAP(CHIPS)':
 'A': CDS_PINID='A';
NODE_NAME     R4264 1
 '@S9S_MB_2U_LIB.S9S_MB_2U(SCH_1):PAGE230_I47@PURE_QUANTA.Q_RES(CHIPS)':
 'A': CDS_PINID='A';
NODE_NAME     R4270 1
 '@S9S_MB_2U_LIB.S9S_MB_2U(SCH_1):PAGE221_I99@PURE_QUANTA.Q_RES(CHIPS)':
 'A': CDS_PINID='A';
NODE_NAME     R4269 1
 '@S9S_MB_2U_LIB.S9S_MB_2U(SCH_1):PAGE221_I102@PURE_QUANTA.Q_RES(CHIPS)':
 'A': CDS_PINID='A';
NODE_NAME     U270 8
 '@S9S_MB_2U_LIB.S9S_MB_2U(SCH_1):PAGE161_I164@PURE_QUANTA.LM75BD(CHIPS)':
 'VCC': CDS_PINID='VCC';
NODE_NAME     U271 8
 '@S9S_MB_2U_LIB.S9S_MB_2U(SCH_1):PAGE161_I165@PURE_QUANTA.LM75BD(CHIPS)':
 'VCC': CDS_PINID='VCC';
NODE_NAME     U272 8
 '@S9S_MB_2U_LIB.S9S_MB_2U(SCH_1):PAGE161_I166@PURE_QUANTA.LM75BD(CHIPS)':
 'VCC': CDS_PINID='VCC';
NODE_NAME     U273 8
 '@S9S_MB_2U_LIB.S9S_MB_2U(SCH_1):PAGE161_I167@PURE_QUANTA.LM75BD(CHIPS)':
 'VCC': CDS_PINID='VCC';
NODE_NAME     R4281 1
 '@S9S_MB_2U_LIB.S9S_MB_2U(SCH_1):PAGE162_I7@PURE_QUANTA.Q_RES(CHIPS)':
 'A': CDS_PINID='A';
NODE_NAME     R4284 1
 '@S9S_MB_2U_LIB.S9S_MB_2U(SCH_1):PAGE162_I41@PURE_QUANTA.Q_RES(CHIPS)':
 'A': CDS_PINID='A';
NODE_NAME     R4036 1
 '@S9S_MB_2U_LIB.S9S_MB_2U(SCH_1):PAGE322_I128@PURE_QUANTA.Q_RES(CHIPS)':
 'A': CDS_PINID='A';
NODE_NAME     R4037 1
 '@S9S_MB_2U_LIB.S9S_MB_2U(SCH_1):PAGE322_I130@PURE_QUANTA.Q_RES(CHIPS)':
 'A': CDS_PINID='A';
NODE_NAME     R947 1
 '@S9S_MB_2U_LIB.S9S_MB_2U(SCH_1):PAGE115_I11@PURE_QUANTA.Q_RES(CHIPS)':
 'A': CDS_PINID='A';
NODE_NAME     R946 1
 '@S9S_MB_2U_LIB.S9S_MB_2U(SCH_1):PAGE115_I14@PURE_QUANTA.Q_RES(CHIPS)':
 'A': CDS_PINID='A';
NODE_NAME     R945 1
 '@S9S_MB_2U_LIB.S9S_MB_2U(SCH_1):PAGE115_I16@PURE_QUANTA.Q_RES(CHIPS)':
 'A': CDS_PINID='A';
NODE_NAME     R944 1
 '@S9S_MB_2U_LIB.S9S_MB_2U(SCH_1):PAGE115_I19@PURE_QUANTA.Q_RES(CHIPS)':
 'A': CDS_PINID='A';
NODE_NAME     D49 2
 '@S9S_MB_2U_LIB.S9S_MB_2U(SCH_1):PAGE115_I22@PURE_QUANTA.SCHOTTKY_12(CHIPS)':
 'C': CDS_PINID='C';
NODE_NAME     D48 2
 '@S9S_MB_2U_LIB.S9S_MB_2U(SCH_1):PAGE115_I25@PURE_QUANTA.SCHOTTKY_12(CHIPS)':
 'C': CDS_PINID='C';
NODE_NAME     D47 2
 '@S9S_MB_2U_LIB.S9S_MB_2U(SCH_1):PAGE115_I27@PURE_QUANTA.SCHOTTKY_12(CHIPS)':
 'C': CDS_PINID='C';
NODE_NAME     R941 1
 '@S9S_MB_2U_LIB.S9S_MB_2U(SCH_1):PAGE115_I45@PURE_QUANTA.Q_RES(CHIPS)':
 'A': CDS_PINID='A';
NODE_NAME     R940 1
 '@S9S_MB_2U_LIB.S9S_MB_2U(SCH_1):PAGE115_I48@PURE_QUANTA.Q_RES(CHIPS)':
 'A': CDS_PINID='A';
NODE_NAME     D43 2
 '@S9S_MB_2U_LIB.S9S_MB_2U(SCH_1):PAGE115_I54@PURE_QUANTA.SCHOTTKY_12(CHIPS)':
 'C': CDS_PINID='C';
NODE_NAME     D42 2
 '@S9S_MB_2U_LIB.S9S_MB_2U(SCH_1):PAGE115_I59@PURE_QUANTA.SCHOTTKY_12(CHIPS)':
 'C': CDS_PINID='C';
NODE_NAME     PU205 1_2
 '@S9S_MB_2U_LIB.S9S_MB_2U(SCH_1):PAGE236_I50@PURE_QUANTA.MP5016GQHLZ(CHIPS)':
 'VCC': CDS_PINID='VCC';
NODE_NAME     PC2159 1
 '@S9S_MB_2U_LIB.S9S_MB_2U(SCH_1):PAGE236_I55@PURE_QUANTA.Q_CAP(CHIPS)':
 'A': CDS_PINID='A';
NODE_NAME     PC2169 1
 '@S9S_MB_2U_LIB.S9S_MB_2U(SCH_1):PAGE237_I48@PURE_QUANTA.Q_CAP(CHIPS)':
 'A': CDS_PINID='A';
NODE_NAME     D46 2
 '@S9S_MB_2U_LIB.S9S_MB_2U(SCH_1):PAGE115_I29@PURE_QUANTA.SCHOTTKY_12(CHIPS)':
 'C': CDS_PINID='C';
NODE_NAME     R943 1
 '@S9S_MB_2U_LIB.S9S_MB_2U(SCH_1):PAGE115_I37@PURE_QUANTA.Q_RES(CHIPS)':
 'A': CDS_PINID='A';
NODE_NAME     R942 1
 '@S9S_MB_2U_LIB.S9S_MB_2U(SCH_1):PAGE115_I40@PURE_QUANTA.Q_RES(CHIPS)':
 'A': CDS_PINID='A';
NODE_NAME     D45 2
 '@S9S_MB_2U_LIB.S9S_MB_2U(SCH_1):PAGE115_I50@PURE_QUANTA.SCHOTTKY_12(CHIPS)':
 'C': CDS_PINID='C';
NODE_NAME     D44 2
 '@S9S_MB_2U_LIB.S9S_MB_2U(SCH_1):PAGE115_I52@PURE_QUANTA.SCHOTTKY_12(CHIPS)':
 'C': CDS_PINID='C';
NODE_NAME     R4448 1
 '@S9S_MB_2U_LIB.S9S_MB_2U(SCH_1):PAGE194_I9@PURE_QUANTA.Q_RES(CHIPS)':
 'A': CDS_PINID='A';
NODE_NAME     U312 12
 '@S9S_MB_2U_LIB.S9S_MB_2U(SCH_1):PAGE194_I20@PURE_QUANTA.TUSB211IRWBR(CHIPS)':
 'VCC': CDS_PINID='VCC';
NODE_NAME     R4459 1
 '@S9S_MB_2U_LIB.S9S_MB_2U(SCH_1):PAGE194_I22@PURE_QUANTA.Q_RES(CHIPS)':
 'A': CDS_PINID='A';
NODE_NAME     R4458 1
 '@S9S_MB_2U_LIB.S9S_MB_2U(SCH_1):PAGE194_I23@PURE_QUANTA.Q_RES(CHIPS)':
 'A': CDS_PINID='A';
NODE_NAME     R4457 1
 '@S9S_MB_2U_LIB.S9S_MB_2U(SCH_1):PAGE194_I24@PURE_QUANTA.Q_RES(CHIPS)':
 'A': CDS_PINID='A';
NODE_NAME     R4456 1
 '@S9S_MB_2U_LIB.S9S_MB_2U(SCH_1):PAGE194_I25@PURE_QUANTA.Q_RES(CHIPS)':
 'A': CDS_PINID='A';
NODE_NAME     R4452 1
 '@S9S_MB_2U_LIB.S9S_MB_2U(SCH_1):PAGE194_I27@PURE_QUANTA.Q_RES(CHIPS)':
 'A': CDS_PINID='A';
NODE_NAME     R4450 1
 '@S9S_MB_2U_LIB.S9S_MB_2U(SCH_1):PAGE194_I41@PURE_QUANTA.Q_RES(CHIPS)':
 'A': CDS_PINID='A';
NODE_NAME     C2323 1
 '@S9S_MB_2U_LIB.S9S_MB_2U(SCH_1):PAGE194_I56@PURE_QUANTA.Q_CAP(CHIPS)':
 'A': CDS_PINID='A';
NODE_NAME     C2324 1
 '@S9S_MB_2U_LIB.S9S_MB_2U(SCH_1):PAGE194_I58@PURE_QUANTA.Q_CAP(CHIPS)':
 'A': CDS_PINID='A';
NODE_NAME     R4211 1
 '@S9S_MB_2U_LIB.S9S_MB_2U(SCH_1):PAGE161_I168@PURE_QUANTA.Q_RES(CHIPS)':
 'A': CDS_PINID='A';
NODE_NAME     R4209 1
 '@S9S_MB_2U_LIB.S9S_MB_2U(SCH_1):PAGE161_I169@PURE_QUANTA.Q_RES(CHIPS)':
 'A': CDS_PINID='A';
NODE_NAME     R4210 1
 '@S9S_MB_2U_LIB.S9S_MB_2U(SCH_1):PAGE161_I170@PURE_QUANTA.Q_RES(CHIPS)':
 'A': CDS_PINID='A';
NODE_NAME     R4208 1
 '@S9S_MB_2U_LIB.S9S_MB_2U(SCH_1):PAGE161_I171@PURE_QUANTA.Q_RES(CHIPS)':
 'A': CDS_PINID='A';
NODE_NAME     C2337 1
 '@S9S_MB_2U_LIB.S9S_MB_2U(SCH_1):PAGE225_I5@PURE_QUANTA.Q_CAP(CHIPS)':
 'A': CDS_PINID='A';
NODE_NAME     U315 1
 '@S9S_MB_2U_LIB.S9S_MB_2U(SCH_1):PAGE225_I17@PURE_QUANTA.PCA9617ADP(CHIPS)':
 'VCCA': CDS_PINID='VCCA';
NODE_NAME     R2392 1
 '@S9S_MB_2U_LIB.S9S_MB_2U(SCH_1):PAGE260_I18@PURE_QUANTA.Q_RES(CHIPS)':
 'A': CDS_PINID='A';
NODE_NAME     R2404 1
 '@S9S_MB_2U_LIB.S9S_MB_2U(SCH_1):PAGE264_I85@PURE_QUANTA.Q_RES(CHIPS)':
 'A': CDS_PINID='A';
NODE_NAME     PR323 2
 '@S9S_MB_2U_LIB.S9S_MB_2U(SCH_1):PAGE270_I126@PURE_QUANTA.Q_RES(CHIPS)':
 'B': CDS_PINID='B';
NODE_NAME     R2589 1
 '@S9S_MB_2U_LIB.S9S_MB_2U(SCH_1):PAGE252_I20@PURE_QUANTA.Q_RES(CHIPS)':
 'A': CDS_PINID='A';
NODE_NAME     R1713 2
 '@S9S_MB_2U_LIB.S9S_MB_2U(SCH_1):PAGE252_I40@PURE_QUANTA.Q_RES(CHIPS)':
 'B': CDS_PINID='B';
NODE_NAME     PR215 1
 '@S9S_MB_2U_LIB.S9S_MB_2U(SCH_1):PAGE282_I18@PURE_QUANTA.Q_RES(CHIPS)':
 'A': CDS_PINID='A';
NODE_NAME     PR217 1
 '@S9S_MB_2U_LIB.S9S_MB_2U(SCH_1):PAGE282_I20@PURE_QUANTA.Q_RES(CHIPS)':
 'A': CDS_PINID='A';
NODE_NAME     R223 1
 '@S9S_MB_2U_LIB.S9S_MB_2U(SCH_1):PAGE282_I85@PURE_QUANTA.Q_RES(CHIPS)':
 'A': CDS_PINID='A';
NODE_NAME     D141 1
 '@S9S_MB_2U_LIB.S9S_MB_2U(SCH_1):PAGE210_I91@PURE_QUANTA.SCHOTTKY_12(CHIPS)':
 'A': CDS_PINID='A';
NODE_NAME     R4515 1
 '@S9S_MB_2U_LIB.S9S_MB_2U(SCH_1):PAGE140_I200@PURE_QUANTA.Q_RES(CHIPS)':
 'A': CDS_PINID='A';
NODE_NAME     R4173 1
 '@S9S_MB_2U_LIB.S9S_MB_2U(SCH_1):PAGE140_I202@PURE_QUANTA.Q_RES(CHIPS)':
 'A': CDS_PINID='A';
NODE_NAME     R4521 1
 '@S9S_MB_2U_LIB.S9S_MB_2U(SCH_1):PAGE201_I163@PURE_QUANTA.Q_RES(CHIPS)':
 'A': CDS_PINID='A';
NODE_NAME     R4546 1
 '@S9S_MB_2U_LIB.S9S_MB_2U(SCH_1):PAGE139_I50@PURE_QUANTA.Q_RES(CHIPS)':
 'A': CDS_PINID='A';
NODE_NAME     R4545 1
 '@S9S_MB_2U_LIB.S9S_MB_2U(SCH_1):PAGE139_I57@PURE_QUANTA.Q_RES(CHIPS)':
 'A': CDS_PINID='A';
NODE_NAME     R4551 1
 '@S9S_MB_2U_LIB.S9S_MB_2U(SCH_1):PAGE230_I51@PURE_QUANTA.Q_RES(CHIPS)':
 'A': CDS_PINID='A';
NODE_NAME     R4553 1
 '@S9S_MB_2U_LIB.S9S_MB_2U(SCH_1):PAGE230_I55@PURE_QUANTA.Q_RES(CHIPS)':
 'A': CDS_PINID='A';
NODE_NAME     R4554 1
 '@S9S_MB_2U_LIB.S9S_MB_2U(SCH_1):PAGE230_I59@PURE_QUANTA.Q_RES(CHIPS)':
 'A': CDS_PINID='A';
NODE_NAME     U212 5
 '@S9S_MB_2U_LIB.S9S_MB_2U(SCH_1):PAGE153_I23@PURE_QUANTA.74LVC2G07DW7(CHIPS)':
 'VCC': CDS_PINID='VCC';
NODE_NAME     U211 5
 '@S9S_MB_2U_LIB.S9S_MB_2U(SCH_1):PAGE153_I26@PURE_QUANTA.74LVC2G07DW7(CHIPS)':
 'VCC': CDS_PINID='VCC';
NODE_NAME     C593 1
 '@S9S_MB_2U_LIB.S9S_MB_2U(SCH_1):PAGE153_I27@PURE_QUANTA.Q_CAP(CHIPS)':
 'A': CDS_PINID='A';
NODE_NAME     R1149 1
 '@S9S_MB_2U_LIB.S9S_MB_2U(SCH_1):PAGE153_I50@PURE_QUANTA.Q_RES(CHIPS)':
 'A': CDS_PINID='A';
NODE_NAME     R3799 1
 '@S9S_MB_2U_LIB.S9S_MB_2U(SCH_1):PAGE153_I90@PURE_QUANTA.Q_RES(CHIPS)':
 'A': CDS_PINID='A';
NODE_NAME     R3797 1
 '@S9S_MB_2U_LIB.S9S_MB_2U(SCH_1):PAGE153_I92@PURE_QUANTA.Q_RES(CHIPS)':
 'A': CDS_PINID='A';
NODE_NAME     R3134 1
 '@S9S_MB_2U_LIB.S9S_MB_2U(SCH_1):PAGE131_I3@PURE_QUANTA.Q_RES(CHIPS)':
 'A': CDS_PINID='A';
NODE_NAME     R3136 1
 '@S9S_MB_2U_LIB.S9S_MB_2U(SCH_1):PAGE131_I5@PURE_QUANTA.Q_RES(CHIPS)':
 'A': CDS_PINID='A';
NODE_NAME     R3133 1
 '@S9S_MB_2U_LIB.S9S_MB_2U(SCH_1):PAGE131_I11@PURE_QUANTA.Q_RES(CHIPS)':
 'A': CDS_PINID='A';
NODE_NAME     R3135 1
 '@S9S_MB_2U_LIB.S9S_MB_2U(SCH_1):PAGE131_I13@PURE_QUANTA.Q_RES(CHIPS)':
 'A': CDS_PINID='A';
NODE_NAME     U59 5
 '@S9S_MB_2U_LIB.S9S_MB_2U(SCH_1):PAGE131_I19@PURE_QUANTA.74LVC2G07DW7(CHIPS)':
 'VCC': CDS_PINID='VCC';
NODE_NAME     U58 5
 '@S9S_MB_2U_LIB.S9S_MB_2U(SCH_1):PAGE131_I25@PURE_QUANTA.74LVC2G07DW7(CHIPS)':
 'VCC': CDS_PINID='VCC';
NODE_NAME     PC2140 1
 '@S9S_MB_2U_LIB.S9S_MB_2U(SCH_1):PAGE131_I52@PURE_QUANTA.Q_CAP(CHIPS)':
 'A': CDS_PINID='A';
NODE_NAME     R3147 1
 '@S9S_MB_2U_LIB.S9S_MB_2U(SCH_1):PAGE131_I66@PURE_QUANTA.Q_RES(CHIPS)':
 'A': CDS_PINID='A';
NODE_NAME     R3825 1
 '@S9S_MB_2U_LIB.S9S_MB_2U(SCH_1):PAGE131_I81@PURE_QUANTA.Q_RES(CHIPS)':
 'A': CDS_PINID='A';
NODE_NAME     PU200 A3
 '@S9S_MB_2U_LIB.S9S_MB_2U(SCH_1):PAGE131_I90@PURE_QUANTA.MAX15090BEWIT(CHIPS)':
 'IN_A3': CDS_PINID='IN_A3';
NODE_NAME     PU200 A5
 '@S9S_MB_2U_LIB.S9S_MB_2U(SCH_1):PAGE131_I90@PURE_QUANTA.MAX15090BEWIT(CHIPS)':
 'IN_A5': CDS_PINID='IN_A5';
NODE_NAME     PU200 B3
 '@S9S_MB_2U_LIB.S9S_MB_2U(SCH_1):PAGE131_I90@PURE_QUANTA.MAX15090BEWIT(CHIPS)':
 'IN_B3': CDS_PINID='IN_B3';
NODE_NAME     PU200 B5
 '@S9S_MB_2U_LIB.S9S_MB_2U(SCH_1):PAGE131_I90@PURE_QUANTA.MAX15090BEWIT(CHIPS)':
 'IN_B5': CDS_PINID='IN_B5';
NODE_NAME     PU200 C3
 '@S9S_MB_2U_LIB.S9S_MB_2U(SCH_1):PAGE131_I90@PURE_QUANTA.MAX15090BEWIT(CHIPS)':
 'IN_C3': CDS_PINID='IN_C3';
NODE_NAME     PU200 C5
 '@S9S_MB_2U_LIB.S9S_MB_2U(SCH_1):PAGE131_I90@PURE_QUANTA.MAX15090BEWIT(CHIPS)':
 'IN_C5': CDS_PINID='IN_C5';
NODE_NAME     PU200 D5
 '@S9S_MB_2U_LIB.S9S_MB_2U(SCH_1):PAGE131_I90@PURE_QUANTA.MAX15090BEWIT(CHIPS)':
 'IN_D5': CDS_PINID='IN_D5';
NODE_NAME     PR3782 1
 '@S9S_MB_2U_LIB.S9S_MB_2U(SCH_1):PAGE131_I92@PURE_QUANTA.Q_RES(CHIPS)':
 'A': CDS_PINID='A';
NODE_NAME     PU207 1_2
 '@S9S_MB_2U_LIB.S9S_MB_2U(SCH_1):PAGE237_I51@PURE_QUANTA.MP5016GQHLZ(CHIPS)':
 'VCC': CDS_PINID='VCC';
NODE_NAME     R3979 1
 '@S9S_MB_2U_LIB.S9S_MB_2U(SCH_1):PAGE324_I50@PURE_QUANTA.Q_RES(CHIPS)':
 'A': CDS_PINID='A';
NODE_NAME     R3978 1
 '@S9S_MB_2U_LIB.S9S_MB_2U(SCH_1):PAGE324_I76@PURE_QUANTA.Q_RES(CHIPS)':
 'A': CDS_PINID='A';
NODE_NAME     PU293 1_2
 '@S9S_MB_2U_LIB.S9S_MB_2U(SCH_1):PAGE323_I31@PURE_QUANTA.MP5016GQHLZ(CHIPS)':
 'VCC': CDS_PINID='VCC';
NODE_NAME     PR3951 2
 '@S9S_MB_2U_LIB.S9S_MB_2U(SCH_1):PAGE323_I54@PURE_QUANTA.Q_RES(CHIPS)':
 'B': CDS_PINID='B';
NODE_NAME     R1854 1
 '@S9S_MB_2U_LIB.S9S_MB_2U(SCH_1):PAGE229_I2@PURE_QUANTA.Q_RES(CHIPS)':
 'A': CDS_PINID='A';
NODE_NAME     R4013 1
 '@S9S_MB_2U_LIB.S9S_MB_2U(SCH_1):PAGE229_I79@PURE_QUANTA.Q_RES(CHIPS)':
 'A': CDS_PINID='A';
NODE_NAME     R4015 1
 '@S9S_MB_2U_LIB.S9S_MB_2U(SCH_1):PAGE229_I81@PURE_QUANTA.Q_RES(CHIPS)':
 'A': CDS_PINID='A';
NODE_NAME     R2407 1
 '@S9S_MB_2U_LIB.S9S_MB_2U(SCH_1):PAGE267_I45@PURE_QUANTA.Q_RES(CHIPS)':
 'A': CDS_PINID='A';
NODE_NAME     PR3338 1
 '@S9S_MB_2U_LIB.S9S_MB_2U(SCH_1):PAGE286_I13@PURE_QUANTA.Q_RES(CHIPS)':
 'A': CDS_PINID='A';
NODE_NAME     R4543 1
 '@S9S_MB_2U_LIB.S9S_MB_2U(SCH_1):PAGE139_I85@PURE_QUANTA.Q_RES(CHIPS)':
 'A': CDS_PINID='A';
NODE_NAME     U316 5
 '@S9S_MB_2U_LIB.S9S_MB_2U(SCH_1):PAGE139_I86@PURE_QUANTA.74LVC2G17GW(CHIPS)':
 'VCC': CDS_PINID='VCC';
NODE_NAME     R4547 1
 '@S9S_MB_2U_LIB.S9S_MB_2U(SCH_1):PAGE139_I89@PURE_QUANTA.Q_RES(CHIPS)':
 'A': CDS_PINID='A';
NODE_NAME     C2341 1
 '@S9S_MB_2U_LIB.S9S_MB_2U(SCH_1):PAGE139_I93@PURE_QUANTA.Q_CAP(CHIPS)':
 'A': CDS_PINID='A';
NODE_NAME     R4549 1
 '@S9S_MB_2U_LIB.S9S_MB_2U(SCH_1):PAGE139_I98@PURE_QUANTA.Q_RES(CHIPS)':
 'A': CDS_PINID='A';
NODE_NAME     U39 24
 '@S9S_MB_2U_LIB.S9S_MB_2U(SCH_1):PAGE221_I103@PURE_QUANTA.TCA9548APWR(CHIPS)':
 'VCC': CDS_PINID='VCC';
NODE_NAME     C2056 1
 '@S9S_MB_2U_LIB.S9S_MB_2U(SCH_1):PAGE221_I106@PURE_QUANTA.Q_CAP(CHIPS)':
 'A': CDS_PINID='A';
NODE_NAME     R3705 1
 '@S9S_MB_2U_LIB.S9S_MB_2U(SCH_1):PAGE221_I147@PURE_QUANTA.Q_RES(CHIPS)':
 'A': CDS_PINID='A';
NODE_NAME     R4561 1
 '@S9S_MB_2U_LIB.S9S_MB_2U(SCH_1):PAGE143_I116@PURE_QUANTA.Q_RES(CHIPS)':
 'A': CDS_PINID='A';
NODE_NAME     R4560 1
 '@S9S_MB_2U_LIB.S9S_MB_2U(SCH_1):PAGE143_I124@PURE_QUANTA.Q_RES(CHIPS)':
 'A': CDS_PINID='A';
NODE_NAME     R4562 1
 '@S9S_MB_2U_LIB.S9S_MB_2U(SCH_1):PAGE143_I132@PURE_QUANTA.Q_RES(CHIPS)':
 'A': CDS_PINID='A';
NODE_NAME     C2344 1
 '@S9S_MB_2U_LIB.S9S_MB_2U(SCH_1):PAGE152_I87@PURE_QUANTA.Q_CAP(CHIPS)':
 'A': CDS_PINID='A';
NODE_NAME     C2345 1
 '@S9S_MB_2U_LIB.S9S_MB_2U(SCH_1):PAGE156_I81@PURE_QUANTA.Q_CAP(CHIPS)':
 'A': CDS_PINID='A';
NODE_NAME     R4597 1
 '@S9S_MB_2U_LIB.S9S_MB_2U(SCH_1):PAGE184_I22@PURE_QUANTA.Q_RES(CHIPS)':
 'A': CDS_PINID='A';
NODE_NAME     R4586 1
 '@S9S_MB_2U_LIB.S9S_MB_2U(SCH_1):PAGE184_I62@PURE_QUANTA.Q_RES(CHIPS)':
 'A': CDS_PINID='A';
NODE_NAME     R1195 1
 '@S9S_MB_2U_LIB.S9S_MB_2U(SCH_1):PAGE207_I278@PURE_QUANTA.Q_RES(CHIPS)':
 'A': CDS_PINID='A';
NODE_NAME     R366 1
 '@S9S_MB_2U_LIB.S9S_MB_2U(SCH_1):PAGE207_I280@PURE_QUANTA.Q_RES(CHIPS)':
 'A': CDS_PINID='A';
NODE_NAME     U209 24
 '@S9S_MB_2U_LIB.S9S_MB_2U(SCH_1):PAGE154_I206@PURE_QUANTA.PCA9555APW(CHIPS)':
 'VDD': CDS_PINID='VDD';
NODE_NAME     U51 24
 '@S9S_MB_2U_LIB.S9S_MB_2U(SCH_1):PAGE132_I66@PURE_QUANTA.PCA9555APW(CHIPS)':
 'VDD': CDS_PINID='VDD';
NODE_NAME     R4604 1
 '@S9S_MB_2U_LIB.S9S_MB_2U(SCH_1):PAGE213_I18@PURE_QUANTA.Q_RES(CHIPS)':
 'A': CDS_PINID='A';
NODE_NAME     R4605 1
 '@S9S_MB_2U_LIB.S9S_MB_2U(SCH_1):PAGE213_I22@PURE_QUANTA.Q_RES(CHIPS)':
 'A': CDS_PINID='A';
NODE_NAME     C1243 1
 '@S9S_MB_2U_LIB.S9S_MB_2U(SCH_1):PAGE181_I162@PURE_QUANTA.Q_CAP(CHIPS)':
 'A': CDS_PINID='A';
NODE_NAME     C1245 1
 '@S9S_MB_2U_LIB.S9S_MB_2U(SCH_1):PAGE181_I163@PURE_QUANTA.Q_CAP(CHIPS)':
 'A': CDS_PINID='A';
NODE_NAME     U16 5
 '@S9S_MB_2U_LIB.S9S_MB_2U(SCH_1):PAGE135_I115@PURE_QUANTA.74LVC1G66GV(CHIPS)':
 'VCC': CDS_PINID='VCC';
NODE_NAME     R1493 1
 '@S9S_MB_2U_LIB.S9S_MB_2U(SCH_1):PAGE312_I191@PURE_QUANTA.Q_RES(CHIPS)':
 'A': CDS_PINID='A';
NODE_NAME     U322 5
 '@S9S_MB_2U_LIB.S9S_MB_2U(SCH_1):PAGE154_I221@PURE_QUANTA.74LVC1G08W57(CHIPS)':
 'VCC': CDS_PINID='VCC';
NODE_NAME     C2346 1
 '@S9S_MB_2U_LIB.S9S_MB_2U(SCH_1):PAGE154_I223@PURE_QUANTA.Q_CAP(CHIPS)':
 'A': CDS_PINID='A';
NODE_NAME     R3160 1
 '@S9S_MB_2U_LIB.S9S_MB_2U(SCH_1):PAGE154_I235@PURE_QUANTA.Q_RES(CHIPS)':
 'A': CDS_PINID='A';
NODE_NAME     C2347 1
 '@S9S_MB_2U_LIB.S9S_MB_2U(SCH_1):PAGE132_I90@PURE_QUANTA.Q_CAP(CHIPS)':
 'A': CDS_PINID='A';
NODE_NAME     U323 5
 '@S9S_MB_2U_LIB.S9S_MB_2U(SCH_1):PAGE132_I92@PURE_QUANTA.74LVC1G08W57(CHIPS)':
 'VCC': CDS_PINID='VCC';
NODE_NAME     R1132 1
 '@S9S_MB_2U_LIB.S9S_MB_2U(SCH_1):PAGE132_I95@PURE_QUANTA.Q_RES(CHIPS)':
 'A': CDS_PINID='A';
NODE_NAME     PR220 2
 '@S9S_MB_2U_LIB.S9S_MB_2U(SCH_1):PAGE282_I78@PURE_QUANTA.Q_RES(CHIPS)':
 'B': CDS_PINID='B';
NODE_NAME     R2571 1
 '@S9S_MB_2U_LIB.S9S_MB_2U(SCH_1):PAGE278_I30@PURE_QUANTA.Q_RES(CHIPS)':
 'A': CDS_PINID='A';
NODE_NAME     R2569 1
 '@S9S_MB_2U_LIB.S9S_MB_2U(SCH_1):PAGE278_I49@PURE_QUANTA.Q_RES(CHIPS)':
 'A': CDS_PINID='A';
NODE_NAME     R2568 1
 '@S9S_MB_2U_LIB.S9S_MB_2U(SCH_1):PAGE278_I50@PURE_QUANTA.Q_RES(CHIPS)':
 'A': CDS_PINID='A';
NODE_NAME     R2556 1
 '@S9S_MB_2U_LIB.S9S_MB_2U(SCH_1):PAGE278_I105@PURE_QUANTA.Q_RES(CHIPS)':
 'A': CDS_PINID='A';
NODE_NAME     PR283 2
 '@S9S_MB_2U_LIB.S9S_MB_2U(SCH_1):PAGE278_I108@PURE_QUANTA.Q_RES(CHIPS)':
 'B': CDS_PINID='B';
NODE_NAME     PR370 1
 '@S9S_MB_2U_LIB.S9S_MB_2U(SCH_1):PAGE264_I13@PURE_QUANTA.Q_RES(CHIPS)':
 'A': CDS_PINID='A';
NODE_NAME     PR375 2
 '@S9S_MB_2U_LIB.S9S_MB_2U(SCH_1):PAGE264_I80@PURE_QUANTA.Q_RES(CHIPS)':
 'B': CDS_PINID='B';
NODE_NAME     R2373 1
 '@S9S_MB_2U_LIB.S9S_MB_2U(SCH_1):PAGE252_I23@PURE_QUANTA.Q_RES(CHIPS)':
 'A': CDS_PINID='A';
NODE_NAME     R1712 2
 '@S9S_MB_2U_LIB.S9S_MB_2U(SCH_1):PAGE252_I42@PURE_QUANTA.Q_RES(CHIPS)':
 'B': CDS_PINID='B';
NODE_NAME     R2377 1
 '@S9S_MB_2U_LIB.S9S_MB_2U(SCH_1):PAGE252_I54@PURE_QUANTA.Q_RES(CHIPS)':
 'A': CDS_PINID='A';
NODE_NAME     R2551 1
 '@S9S_MB_2U_LIB.S9S_MB_2U(SCH_1):PAGE270_I15@PURE_QUANTA.Q_RES(CHIPS)':
 'A': CDS_PINID='A';
NODE_NAME     R2396 1
 '@S9S_MB_2U_LIB.S9S_MB_2U(SCH_1):PAGE260_I13@PURE_QUANTA.Q_RES(CHIPS)':
 'A': CDS_PINID='A';
NODE_NAME     R2393 1
 '@S9S_MB_2U_LIB.S9S_MB_2U(SCH_1):PAGE260_I17@PURE_QUANTA.Q_RES(CHIPS)':
 'A': CDS_PINID='A';
NODE_NAME     PR130 2
 '@S9S_MB_2U_LIB.S9S_MB_2U(SCH_1):PAGE260_I100@PURE_QUANTA.Q_RES(CHIPS)':
 'B': CDS_PINID='B';
NODE_NAME     U321 5
 '@S9S_MB_2U_LIB.S9S_MB_2U(SCH_1):PAGE156_I92@PURE_QUANTA.74LVC1G66GV(CHIPS)':
 'VCC': CDS_PINID='VCC';
NODE_NAME     U320 5
 '@S9S_MB_2U_LIB.S9S_MB_2U(SCH_1):PAGE152_I92@PURE_QUANTA.74LVC1G66GV(CHIPS)':
 'VCC': CDS_PINID='VCC';
NODE_NAME     PR1326 1
 '@S9S_MB_2U_LIB.S9S_MB_2U(SCH_1):PAGE248_I3@PURE_QUANTA.Q_RES(CHIPS)':
 'A': CDS_PINID='A';
NODE_NAME     PR1338 1
 '@S9S_MB_2U_LIB.S9S_MB_2U(SCH_1):PAGE285_I3@PURE_QUANTA.Q_RES(CHIPS)':
 'A': CDS_PINID='A';
NODE_NAME     C2364 1
 '@S9S_MB_2U_LIB.S9S_MB_2U(SCH_1):PAGE240_I33@PURE_QUANTA.Q_CAP(CHIPS)':
 'A': CDS_PINID='A';
NODE_NAME     R4692 1
 '@S9S_MB_2U_LIB.S9S_MB_2U(SCH_1):PAGE240_I35@PURE_QUANTA.Q_RES(CHIPS)':
 'A': CDS_PINID='A';
NODE_NAME     R3925 2
 '@S9S_MB_2U_LIB.S9S_MB_2U(SCH_1):PAGE303_I33@PURE_QUANTA.Q_RES(CHIPS)':
 'B': CDS_PINID='B';
NODE_NAME     C2458 1
 '@S9S_MB_2U_LIB.S9S_MB_2U(SCH_1):PAGE327_I8@PURE_QUANTA.Q_CAP(CHIPS)':
 'A': CDS_PINID='A';
NODE_NAME     U345 1
 '@S9S_MB_2U_LIB.S9S_MB_2U(SCH_1):PAGE327_I10@PURE_QUANTA.NCT7718W(CHIPS)':
 'VDD': CDS_PINID='VDD';
NODE_NAME     R4686 1
 '@S9S_MB_2U_LIB.S9S_MB_2U(SCH_1):PAGE327_I17@PURE_QUANTA.Q_RES(CHIPS)':
 'A': CDS_PINID='A';
NODE_NAME     R4685 1
 '@S9S_MB_2U_LIB.S9S_MB_2U(SCH_1):PAGE327_I23@PURE_QUANTA.Q_RES(CHIPS)':
 'A': CDS_PINID='A';
NODE_NAME     PJ42 12
 '@S9S_MB_2U_LIB.S9S_MB_2U(SCH_1):PAGE327_I34@PURE_QUANTA.SCONN21_9193031121LF(CHIPS)':
 '12': CDS_PINID='\12\';
NODE_NAME     R2230 1
 '@S9S_MB_2U_LIB.S9S_MB_2U(SCH_1):PAGE326_I39@PURE_QUANTA.Q_RES(CHIPS)':
 'A': CDS_PINID='A';
NODE_NAME     R2233 1
 '@S9S_MB_2U_LIB.S9S_MB_2U(SCH_1):PAGE326_I41@PURE_QUANTA.Q_RES(CHIPS)':
 'A': CDS_PINID='A';
NODE_NAME     R4620 1
 '@S9S_MB_2U_LIB.S9S_MB_2U(SCH_1):PAGE326_I45@PURE_QUANTA.Q_RES(CHIPS)':
 'A': CDS_PINID='A';
NODE_NAME     R4671 1
 '@S9S_MB_2U_LIB.S9S_MB_2U(SCH_1):PAGE326_I51@PURE_QUANTA.Q_RES(CHIPS)':
 'A': CDS_PINID='A';
NODE_NAME     R4672 1
 '@S9S_MB_2U_LIB.S9S_MB_2U(SCH_1):PAGE326_I53@PURE_QUANTA.Q_RES(CHIPS)':
 'A': CDS_PINID='A';
NODE_NAME     R3271 1
 '@S9S_MB_2U_LIB.S9S_MB_2U(SCH_1):PAGE136_I9@PURE_QUANTA.Q_RES(CHIPS)':
 'A': CDS_PINID='A';
NODE_NAME     R3269 1
 '@S9S_MB_2U_LIB.S9S_MB_2U(SCH_1):PAGE136_I15@PURE_QUANTA.Q_RES(CHIPS)':
 'A': CDS_PINID='A';
NODE_NAME     R3275 1
 '@S9S_MB_2U_LIB.S9S_MB_2U(SCH_1):PAGE136_I21@PURE_QUANTA.Q_RES(CHIPS)':
 'A': CDS_PINID='A';
NODE_NAME     R3280 1
 '@S9S_MB_2U_LIB.S9S_MB_2U(SCH_1):PAGE136_I32@PURE_QUANTA.Q_RES(CHIPS)':
 'A': CDS_PINID='A';
NODE_NAME     C1863 1
 '@S9S_MB_2U_LIB.S9S_MB_2U(SCH_1):PAGE136_I49@PURE_QUANTA.Q_CAP(CHIPS)':
 'A': CDS_PINID='A';
NODE_NAME     U237 1
 '@S9S_MB_2U_LIB.S9S_MB_2U(SCH_1):PAGE136_I50@PURE_QUANTA.PI3EQX12902AZLEX(CHIPS)':
 'VDD1': CDS_PINID='VDD1';
NODE_NAME     U237 10
 '@S9S_MB_2U_LIB.S9S_MB_2U(SCH_1):PAGE136_I50@PURE_QUANTA.PI3EQX12902AZLEX(CHIPS)':
 'VDD2': CDS_PINID='VDD2';
NODE_NAME     U237 16
 '@S9S_MB_2U_LIB.S9S_MB_2U(SCH_1):PAGE136_I50@PURE_QUANTA.PI3EQX12902AZLEX(CHIPS)':
 'VDD3': CDS_PINID='VDD3';
NODE_NAME     U237 25
 '@S9S_MB_2U_LIB.S9S_MB_2U(SCH_1):PAGE136_I50@PURE_QUANTA.PI3EQX12902AZLEX(CHIPS)':
 'VDD4': CDS_PINID='VDD4';
NODE_NAME     C1864 1
 '@S9S_MB_2U_LIB.S9S_MB_2U(SCH_1):PAGE136_I51@PURE_QUANTA.Q_CAP(CHIPS)':
 'A': CDS_PINID='A';
NODE_NAME     C1865 1
 '@S9S_MB_2U_LIB.S9S_MB_2U(SCH_1):PAGE136_I52@PURE_QUANTA.Q_CAP(CHIPS)':
 'A': CDS_PINID='A';
NODE_NAME     C1866 1
 '@S9S_MB_2U_LIB.S9S_MB_2U(SCH_1):PAGE136_I53@PURE_QUANTA.Q_CAP(CHIPS)':
 'A': CDS_PINID='A';
NODE_NAME     R3283 1
 '@S9S_MB_2U_LIB.S9S_MB_2U(SCH_1):PAGE136_I57@PURE_QUANTA.Q_RES(CHIPS)':
 'A': CDS_PINID='A';
NODE_NAME     R3286 1
 '@S9S_MB_2U_LIB.S9S_MB_2U(SCH_1):PAGE136_I64@PURE_QUANTA.Q_RES(CHIPS)':
 'A': CDS_PINID='A';
NODE_NAME     R3292 1
 '@S9S_MB_2U_LIB.S9S_MB_2U(SCH_1):PAGE136_I85@PURE_QUANTA.Q_RES(CHIPS)':
 'A': CDS_PINID='A';
NODE_NAME     R3266 1
 '@S9S_MB_2U_LIB.S9S_MB_2U(SCH_1):PAGE136_I89@PURE_QUANTA.Q_RES(CHIPS)':
 'A': CDS_PINID='A';
NODE_NAME     R4642 1
 '@S9S_MB_2U_LIB.S9S_MB_2U(SCH_1):PAGE159_I7@PURE_QUANTA.Q_RES(CHIPS)':
 'A': CDS_PINID='A';
NODE_NAME     R4644 1
 '@S9S_MB_2U_LIB.S9S_MB_2U(SCH_1):PAGE159_I11@PURE_QUANTA.Q_RES(CHIPS)':
 'A': CDS_PINID='A';
NODE_NAME     R4643 1
 '@S9S_MB_2U_LIB.S9S_MB_2U(SCH_1):PAGE159_I13@PURE_QUANTA.Q_RES(CHIPS)':
 'A': CDS_PINID='A';
NODE_NAME     R4648 1
 '@S9S_MB_2U_LIB.S9S_MB_2U(SCH_1):PAGE159_I72@PURE_QUANTA.Q_RES(CHIPS)':
 'A': CDS_PINID='A';
NODE_NAME     R4649 1
 '@S9S_MB_2U_LIB.S9S_MB_2U(SCH_1):PAGE159_I74@PURE_QUANTA.Q_RES(CHIPS)':
 'A': CDS_PINID='A';
NODE_NAME     C2355 1
 '@S9S_MB_2U_LIB.S9S_MB_2U(SCH_1):PAGE159_I96@PURE_QUANTA.Q_CAP(CHIPS)':
 'A': CDS_PINID='A';
NODE_NAME     C2356 1
 '@S9S_MB_2U_LIB.S9S_MB_2U(SCH_1):PAGE159_I98@PURE_QUANTA.Q_CAP(CHIPS)':
 'A': CDS_PINID='A';
NODE_NAME     R2344 1
 '@S9S_MB_2U_LIB.S9S_MB_2U(SCH_1):PAGE314_I45@PURE_QUANTA.Q_RES(CHIPS)':
 'A': CDS_PINID='A';
NODE_NAME     R1681 1
 '@S9S_MB_2U_LIB.S9S_MB_2U(SCH_1):PAGE314_I47@PURE_QUANTA.Q_RES(CHIPS)':
 'A': CDS_PINID='A';
NODE_NAME     R2346 1
 '@S9S_MB_2U_LIB.S9S_MB_2U(SCH_1):PAGE314_I51@PURE_QUANTA.Q_RES(CHIPS)':
 'A': CDS_PINID='A';
NODE_NAME     R1551 1
 '@S9S_MB_2U_LIB.S9S_MB_2U(SCH_1):PAGE314_I179@PURE_QUANTA.Q_RES(CHIPS)':
 'A': CDS_PINID='A';
NODE_NAME     U224 5
 '@S9S_MB_2U_LIB.S9S_MB_2U(SCH_1):PAGE151_I7@PURE_QUANTA.74LVC1G126SE7(CHIPS)':
 'VCC': CDS_PINID='VCC';
NODE_NAME     C1840 1
 '@S9S_MB_2U_LIB.S9S_MB_2U(SCH_1):PAGE151_I8@PURE_QUANTA.Q_CAP(CHIPS)':
 'A': CDS_PINID='A';
NODE_NAME     U66 5
 '@S9S_MB_2U_LIB.S9S_MB_2U(SCH_1):PAGE151_I15@PURE_QUANTA.74LVC1G126SE7(CHIPS)':
 'VCC': CDS_PINID='VCC';
NODE_NAME     C639 1
 '@S9S_MB_2U_LIB.S9S_MB_2U(SCH_1):PAGE151_I22@PURE_QUANTA.Q_CAP(CHIPS)':
 'A': CDS_PINID='A';
NODE_NAME     U68 14
 '@S9S_MB_2U_LIB.S9S_MB_2U(SCH_1):PAGE151_I30@PURE_QUANTA.74CBTLV3126PW(CHIPS)':
 'VCC': CDS_PINID='VCC';
NODE_NAME     C641 1
 '@S9S_MB_2U_LIB.S9S_MB_2U(SCH_1):PAGE151_I32@PURE_QUANTA.Q_CAP(CHIPS)':
 'A': CDS_PINID='A';
NODE_NAME     U67 14
 '@S9S_MB_2U_LIB.S9S_MB_2U(SCH_1):PAGE151_I39@PURE_QUANTA.74CBTLV3126PW(CHIPS)':
 'VCC': CDS_PINID='VCC';
NODE_NAME     C640 1
 '@S9S_MB_2U_LIB.S9S_MB_2U(SCH_1):PAGE151_I40@PURE_QUANTA.Q_CAP(CHIPS)':
 'A': CDS_PINID='A';
NODE_NAME     R735 1
 '@S9S_MB_2U_LIB.S9S_MB_2U(SCH_1):PAGE209_I13@PURE_QUANTA.Q_RES(CHIPS)':
 'A': CDS_PINID='A';
NODE_NAME     R1660 2
 '@S9S_MB_2U_LIB.S9S_MB_2U(SCH_1):PAGE209_I14@PURE_QUANTA.Q_RES(CHIPS)':
 'B': CDS_PINID='B';
NODE_NAME     R1558 2
 '@S9S_MB_2U_LIB.S9S_MB_2U(SCH_1):PAGE209_I15@PURE_QUANTA.Q_RES(CHIPS)':
 'B': CDS_PINID='B';
NODE_NAME     R1401 2
 '@S9S_MB_2U_LIB.S9S_MB_2U(SCH_1):PAGE209_I16@PURE_QUANTA.Q_RES(CHIPS)':
 'B': CDS_PINID='B';
NODE_NAME     R1399 2
 '@S9S_MB_2U_LIB.S9S_MB_2U(SCH_1):PAGE209_I17@PURE_QUANTA.Q_RES(CHIPS)':
 'B': CDS_PINID='B';
NODE_NAME     R1492 2
 '@S9S_MB_2U_LIB.S9S_MB_2U(SCH_1):PAGE209_I35@PURE_QUANTA.Q_RES(CHIPS)':
 'B': CDS_PINID='B';
NODE_NAME     R1474 2
 '@S9S_MB_2U_LIB.S9S_MB_2U(SCH_1):PAGE209_I36@PURE_QUANTA.Q_RES(CHIPS)':
 'B': CDS_PINID='B';
NODE_NAME     R1473 2
 '@S9S_MB_2U_LIB.S9S_MB_2U(SCH_1):PAGE209_I37@PURE_QUANTA.Q_RES(CHIPS)':
 'B': CDS_PINID='B';
NODE_NAME     R1741 2
 '@S9S_MB_2U_LIB.S9S_MB_2U(SCH_1):PAGE209_I38@PURE_QUANTA.Q_RES(CHIPS)':
 'B': CDS_PINID='B';
NODE_NAME     R2244 2
 '@S9S_MB_2U_LIB.S9S_MB_2U(SCH_1):PAGE209_I39@PURE_QUANTA.Q_RES(CHIPS)':
 'B': CDS_PINID='B';
NODE_NAME     R139 2
 '@S9S_MB_2U_LIB.S9S_MB_2U(SCH_1):PAGE209_I40@PURE_QUANTA.Q_RES(CHIPS)':
 'B': CDS_PINID='B';
NODE_NAME     R1440 2
 '@S9S_MB_2U_LIB.S9S_MB_2U(SCH_1):PAGE209_I41@PURE_QUANTA.Q_RES(CHIPS)':
 'B': CDS_PINID='B';
NODE_NAME     R1437 2
 '@S9S_MB_2U_LIB.S9S_MB_2U(SCH_1):PAGE209_I42@PURE_QUANTA.Q_RES(CHIPS)':
 'B': CDS_PINID='B';
NODE_NAME     R1435 2
 '@S9S_MB_2U_LIB.S9S_MB_2U(SCH_1):PAGE209_I43@PURE_QUANTA.Q_RES(CHIPS)':
 'B': CDS_PINID='B';
NODE_NAME     R1434 2
 '@S9S_MB_2U_LIB.S9S_MB_2U(SCH_1):PAGE209_I44@PURE_QUANTA.Q_RES(CHIPS)':
 'B': CDS_PINID='B';
NODE_NAME     R1467 1
 '@S9S_MB_2U_LIB.S9S_MB_2U(SCH_1):PAGE314_I178@PURE_QUANTA.Q_RES(CHIPS)':
 'A': CDS_PINID='A';
NODE_NAME     PR3339 1
 '@S9S_MB_2U_LIB.S9S_MB_2U(SCH_1):PAGE268_I10@PURE_QUANTA.Q_RES(CHIPS)':
 'A': CDS_PINID='A';
NODE_NAME     R2409 1
 '@S9S_MB_2U_LIB.S9S_MB_2U(SCH_1):PAGE268_I32@PURE_QUANTA.Q_RES(CHIPS)':
 'A': CDS_PINID='A';
NODE_NAME     R4275 1
 '@S9S_MB_2U_LIB.S9S_MB_2U(SCH_1):PAGE162_I3@PURE_QUANTA.Q_RES(CHIPS)':
 'A': CDS_PINID='A';
NODE_NAME     R4273 1
 '@S9S_MB_2U_LIB.S9S_MB_2U(SCH_1):PAGE162_I12@PURE_QUANTA.Q_RES(CHIPS)':
 'A': CDS_PINID='A';
NODE_NAME     R4279 1
 '@S9S_MB_2U_LIB.S9S_MB_2U(SCH_1):PAGE162_I18@PURE_QUANTA.Q_RES(CHIPS)':
 'A': CDS_PINID='A';
NODE_NAME     L18 1
 '@S9S_MB_2U_LIB.S9S_MB_2U(SCH_1):PAGE162_I35@PURE_QUANTA.Q_INDUCTOR(CHIPS)':
 '1': CDS_PINID='\1\';
NODE_NAME     R4287 1
 '@S9S_MB_2U_LIB.S9S_MB_2U(SCH_1):PAGE162_I49@PURE_QUANTA.Q_RES(CHIPS)':
 'A': CDS_PINID='A';
NODE_NAME     R4291 1
 '@S9S_MB_2U_LIB.S9S_MB_2U(SCH_1):PAGE162_I65@PURE_QUANTA.Q_RES(CHIPS)':
 'A': CDS_PINID='A';
NODE_NAME     R4289 1
 '@S9S_MB_2U_LIB.S9S_MB_2U(SCH_1):PAGE162_I69@PURE_QUANTA.Q_RES(CHIPS)':
 'A': CDS_PINID='A';
NODE_NAME     R4711 2
 '@S9S_MB_2U_LIB.S9S_MB_2U(SCH_1):PAGE241_I68@PURE_QUANTA.Q_RES(CHIPS)':
 'B': CDS_PINID='B';
NODE_NAME     R4710 1
 '@S9S_MB_2U_LIB.S9S_MB_2U(SCH_1):PAGE241_I74@PURE_QUANTA.Q_RES(CHIPS)':
 'A': CDS_PINID='A';
NODE_NAME     R4719 1
 '@S9S_MB_2U_LIB.S9S_MB_2U(SCH_1):PAGE213_I32@PURE_QUANTA.Q_RES(CHIPS)':
 'A': CDS_PINID='A';
NODE_NAME     C2370 1
 '@S9S_MB_2U_LIB.S9S_MB_2U(SCH_1):PAGE213_I35@PURE_QUANTA.Q_CAP(CHIPS)':
 'A': CDS_PINID='A';
NODE_NAME     U332 5
 '@S9S_MB_2U_LIB.S9S_MB_2U(SCH_1):PAGE213_I37@PURE_QUANTA.74LVC2G07DW7(CHIPS)':
 'VCC': CDS_PINID='VCC';
NODE_NAME     R4716 1
 '@S9S_MB_2U_LIB.S9S_MB_2U(SCH_1):PAGE213_I40@PURE_QUANTA.Q_RES(CHIPS)':
 'A': CDS_PINID='A';
NODE_NAME     R4722 2
 '@S9S_MB_2U_LIB.S9S_MB_2U(SCH_1):PAGE176_I246@PURE_QUANTA.Q_RES(CHIPS)':
 'B': CDS_PINID='B';
NODE_NAME     R4121 1
 '@S9S_MB_2U_LIB.S9S_MB_2U(SCH_1):PAGE143_I143@PURE_QUANTA.Q_RES(CHIPS)':
 'A': CDS_PINID='A';
NODE_NAME     R4135 1
 '@S9S_MB_2U_LIB.S9S_MB_2U(SCH_1):PAGE143_I144@PURE_QUANTA.Q_RES(CHIPS)':
 'A': CDS_PINID='A';
NODE_NAME     R4726 1
 '@S9S_MB_2U_LIB.S9S_MB_2U(SCH_1):PAGE147_I18@PURE_QUANTA.Q_RES(CHIPS)':
 'A': CDS_PINID='A';
NODE_NAME     R4733 1
 '@S9S_MB_2U_LIB.S9S_MB_2U(SCH_1):PAGE147_I25@PURE_QUANTA.Q_RES(CHIPS)':
 'A': CDS_PINID='A';
NODE_NAME     R4725 1
 '@S9S_MB_2U_LIB.S9S_MB_2U(SCH_1):PAGE147_I28@PURE_QUANTA.Q_RES(CHIPS)':
 'A': CDS_PINID='A';
NODE_NAME     R4727 1
 '@S9S_MB_2U_LIB.S9S_MB_2U(SCH_1):PAGE147_I33@PURE_QUANTA.Q_RES(CHIPS)':
 'A': CDS_PINID='A';
NODE_NAME     R4732 1
 '@S9S_MB_2U_LIB.S9S_MB_2U(SCH_1):PAGE147_I36@PURE_QUANTA.Q_RES(CHIPS)':
 'A': CDS_PINID='A';
NODE_NAME     R4730 1
 '@S9S_MB_2U_LIB.S9S_MB_2U(SCH_1):PAGE147_I41@PURE_QUANTA.Q_RES(CHIPS)':
 'A': CDS_PINID='A';
NODE_NAME     R4740 1
 '@S9S_MB_2U_LIB.S9S_MB_2U(SCH_1):PAGE147_I50@PURE_QUANTA.Q_RES(CHIPS)':
 'A': CDS_PINID='A';
NODE_NAME     R4739 1
 '@S9S_MB_2U_LIB.S9S_MB_2U(SCH_1):PAGE147_I54@PURE_QUANTA.Q_RES(CHIPS)':
 'A': CDS_PINID='A';
NODE_NAME     R4737 1
 '@S9S_MB_2U_LIB.S9S_MB_2U(SCH_1):PAGE147_I58@PURE_QUANTA.Q_RES(CHIPS)':
 'A': CDS_PINID='A';
NODE_NAME     R4153 1
 '@S9S_MB_2U_LIB.S9S_MB_2U(SCH_1):PAGE143_I145@PURE_QUANTA.Q_RES(CHIPS)':
 'A': CDS_PINID='A';
NODE_NAME     C2376 1
 '@S9S_MB_2U_LIB.S9S_MB_2U(SCH_1):PAGE154_I241@PURE_QUANTA.Q_CAP(CHIPS)':
 'A': CDS_PINID='A';
NODE_NAME     U334 5
 '@S9S_MB_2U_LIB.S9S_MB_2U(SCH_1):PAGE154_I243@PURE_QUANTA.74LVC1G08W57(CHIPS)':
 'VCC': CDS_PINID='VCC';
NODE_NAME     R4745 1
 '@S9S_MB_2U_LIB.S9S_MB_2U(SCH_1):PAGE154_I256@PURE_QUANTA.Q_RES(CHIPS)':
 'A': CDS_PINID='A';
NODE_NAME     R4756 1
 '@S9S_MB_2U_LIB.S9S_MB_2U(SCH_1):PAGE132_I105@PURE_QUANTA.Q_RES(CHIPS)':
 'A': CDS_PINID='A';
NODE_NAME     U335 5
 '@S9S_MB_2U_LIB.S9S_MB_2U(SCH_1):PAGE132_I108@PURE_QUANTA.74LVC1G08W57(CHIPS)':
 'VCC': CDS_PINID='VCC';
NODE_NAME     C2377 1
 '@S9S_MB_2U_LIB.S9S_MB_2U(SCH_1):PAGE132_I110@PURE_QUANTA.Q_CAP(CHIPS)':
 'A': CDS_PINID='A';
NODE_NAME     R4763 1
 '@S9S_MB_2U_LIB.S9S_MB_2U(SCH_1):PAGE132_I119@PURE_QUANTA.Q_RES(CHIPS)':
 'A': CDS_PINID='A';
NODE_NAME     R4764 1
 '@S9S_MB_2U_LIB.S9S_MB_2U(SCH_1):PAGE154_I257@PURE_QUANTA.Q_RES(CHIPS)':
 'A': CDS_PINID='A';
NODE_NAME     R4768 2
 '@S9S_MB_2U_LIB.S9S_MB_2U(SCH_1):PAGE175_I315@PURE_QUANTA.Q_RES(CHIPS)':
 'B': CDS_PINID='B';
NODE_NAME     R4784 1
 '@S9S_MB_2U_LIB.S9S_MB_2U(SCH_1):PAGE329_I6@PURE_QUANTA.Q_RES(CHIPS)':
 'A': CDS_PINID='A';
NODE_NAME     R4772 1
 '@S9S_MB_2U_LIB.S9S_MB_2U(SCH_1):PAGE329_I21@PURE_QUANTA.Q_RES(CHIPS)':
 'A': CDS_PINID='A';
NODE_NAME     R4785 1
 '@S9S_MB_2U_LIB.S9S_MB_2U(SCH_1):PAGE329_I25@PURE_QUANTA.Q_RES(CHIPS)':
 'A': CDS_PINID='A';
NODE_NAME     R4773 1
 '@S9S_MB_2U_LIB.S9S_MB_2U(SCH_1):PAGE329_I42@PURE_QUANTA.Q_RES(CHIPS)':
 'A': CDS_PINID='A';
NODE_NAME     R4789 1
 '@S9S_MB_2U_LIB.S9S_MB_2U(SCH_1):PAGE329_I49@PURE_QUANTA.Q_RES(CHIPS)':
 'A': CDS_PINID='A';
NODE_NAME     R4786 1
 '@S9S_MB_2U_LIB.S9S_MB_2U(SCH_1):PAGE329_I65@PURE_QUANTA.Q_RES(CHIPS)':
 'A': CDS_PINID='A';
NODE_NAME     R4792 1
 '@S9S_MB_2U_LIB.S9S_MB_2U(SCH_1):PAGE326_I57@PURE_QUANTA.Q_RES(CHIPS)':
 'A': CDS_PINID='A';
NODE_NAME     R4797 1
 '@S9S_MB_2U_LIB.S9S_MB_2U(SCH_1):PAGE326_I80@PURE_QUANTA.Q_RES(CHIPS)':
 'A': CDS_PINID='A';
NODE_NAME     R4801 1
 '@S9S_MB_2U_LIB.S9S_MB_2U(SCH_1):PAGE147_I65@PURE_QUANTA.Q_RES(CHIPS)':
 'A': CDS_PINID='A';
NODE_NAME     R4800 1
 '@S9S_MB_2U_LIB.S9S_MB_2U(SCH_1):PAGE147_I70@PURE_QUANTA.Q_RES(CHIPS)':
 'A': CDS_PINID='A';
NODE_NAME     R4798 1
 '@S9S_MB_2U_LIB.S9S_MB_2U(SCH_1):PAGE147_I75@PURE_QUANTA.Q_RES(CHIPS)':
 'A': CDS_PINID='A';
NODE_NAME     R4804 1
 '@S9S_MB_2U_LIB.S9S_MB_2U(SCH_1):PAGE326_I97@PURE_QUANTA.Q_RES(CHIPS)':
 'A': CDS_PINID='A';
NODE_NAME     R4805 1
 '@S9S_MB_2U_LIB.S9S_MB_2U(SCH_1):PAGE326_I99@PURE_QUANTA.Q_RES(CHIPS)':
 'A': CDS_PINID='A';
NODE_NAME     R1906 1
 '@S9S_MB_2U_LIB.S9S_MB_2U(SCH_1):PAGE153_I7@PURE_QUANTA.Q_RES(CHIPS)':
 'A': CDS_PINID='A';
NODE_NAME     R1905 1
 '@S9S_MB_2U_LIB.S9S_MB_2U(SCH_1):PAGE153_I13@PURE_QUANTA.Q_RES(CHIPS)':
 'A': CDS_PINID='A';
NODE_NAME     R1907 1
 '@S9S_MB_2U_LIB.S9S_MB_2U(SCH_1):PAGE153_I25@PURE_QUANTA.Q_RES(CHIPS)':
 'A': CDS_PINID='A';
NODE_NAME     C592 1
 '@S9S_MB_2U_LIB.S9S_MB_2U(SCH_1):PAGE153_I30@PURE_QUANTA.Q_CAP(CHIPS)':
 'A': CDS_PINID='A';
NODE_NAME     PU202 A3
 '@S9S_MB_2U_LIB.S9S_MB_2U(SCH_1):PAGE153_I61@PURE_QUANTA.MAX15090BEWIT(CHIPS)':
 'IN_A3': CDS_PINID='IN_A3';
NODE_NAME     PU202 A5
 '@S9S_MB_2U_LIB.S9S_MB_2U(SCH_1):PAGE153_I61@PURE_QUANTA.MAX15090BEWIT(CHIPS)':
 'IN_A5': CDS_PINID='IN_A5';
NODE_NAME     PU202 B3
 '@S9S_MB_2U_LIB.S9S_MB_2U(SCH_1):PAGE153_I61@PURE_QUANTA.MAX15090BEWIT(CHIPS)':
 'IN_B3': CDS_PINID='IN_B3';
NODE_NAME     PU202 B5
 '@S9S_MB_2U_LIB.S9S_MB_2U(SCH_1):PAGE153_I61@PURE_QUANTA.MAX15090BEWIT(CHIPS)':
 'IN_B5': CDS_PINID='IN_B5';
NODE_NAME     PU202 C3
 '@S9S_MB_2U_LIB.S9S_MB_2U(SCH_1):PAGE153_I61@PURE_QUANTA.MAX15090BEWIT(CHIPS)':
 'IN_C3': CDS_PINID='IN_C3';
NODE_NAME     PU202 C5
 '@S9S_MB_2U_LIB.S9S_MB_2U(SCH_1):PAGE153_I61@PURE_QUANTA.MAX15090BEWIT(CHIPS)':
 'IN_C5': CDS_PINID='IN_C5';
NODE_NAME     PU202 D5
 '@S9S_MB_2U_LIB.S9S_MB_2U(SCH_1):PAGE153_I61@PURE_QUANTA.MAX15090BEWIT(CHIPS)':
 'IN_D5': CDS_PINID='IN_D5';
NODE_NAME     PC5328 1
 '@S9S_MB_2U_LIB.S9S_MB_2U(SCH_1):PAGE153_I66@PURE_QUANTA.Q_CAP(CHIPS)':
 'A': CDS_PINID='A';
NODE_NAME     PR3798 1
 '@S9S_MB_2U_LIB.S9S_MB_2U(SCH_1):PAGE153_I73@PURE_QUANTA.Q_RES(CHIPS)':
 'A': CDS_PINID='A';
NODE_NAME     R3796 1
 '@S9S_MB_2U_LIB.S9S_MB_2U(SCH_1):PAGE153_I108@PURE_QUANTA.Q_RES(CHIPS)':
 'A': CDS_PINID='A';
NODE_NAME     R3783 1
 '@S9S_MB_2U_LIB.S9S_MB_2U(SCH_1):PAGE153_I110@PURE_QUANTA.Q_RES(CHIPS)':
 'A': CDS_PINID='A';
NODE_NAME     PR3839 2
 '@S9S_MB_2U_LIB.S9S_MB_2U(SCH_1):PAGE236_I75@PURE_QUANTA.Q_RES(CHIPS)':
 'B': CDS_PINID='B';
NODE_NAME     R4532 1
 '@S9S_MB_2U_LIB.S9S_MB_2U(SCH_1):PAGE236_I76@PURE_QUANTA.Q_RES(CHIPS)':
 'A': CDS_PINID='A';
NODE_NAME     C1810 1
 '@S9S_MB_2U_LIB.S9S_MB_2U(SCH_1):PAGE131_I21@PURE_QUANTA.Q_CAP(CHIPS)':
 'A': CDS_PINID='A';
NODE_NAME     PR3795 1
 '@S9S_MB_2U_LIB.S9S_MB_2U(SCH_1):PAGE131_I53@PURE_QUANTA.Q_RES(CHIPS)':
 'A': CDS_PINID='A';
NODE_NAME     R3145 1
 '@S9S_MB_2U_LIB.S9S_MB_2U(SCH_1):PAGE131_I64@PURE_QUANTA.Q_RES(CHIPS)':
 'A': CDS_PINID='A';
NODE_NAME     R3833 1
 '@S9S_MB_2U_LIB.S9S_MB_2U(SCH_1):PAGE131_I108@PURE_QUANTA.Q_RES(CHIPS)':
 'A': CDS_PINID='A';
NODE_NAME     R3826 1
 '@S9S_MB_2U_LIB.S9S_MB_2U(SCH_1):PAGE131_I110@PURE_QUANTA.Q_RES(CHIPS)':
 'A': CDS_PINID='A';
NODE_NAME     PR3851 2
 '@S9S_MB_2U_LIB.S9S_MB_2U(SCH_1):PAGE237_I74@PURE_QUANTA.Q_RES(CHIPS)':
 'B': CDS_PINID='B';
NODE_NAME     R3848 1
 '@S9S_MB_2U_LIB.S9S_MB_2U(SCH_1):PAGE237_I75@PURE_QUANTA.Q_RES(CHIPS)':
 'A': CDS_PINID='A';
NODE_NAME     R3948 1
 '@S9S_MB_2U_LIB.S9S_MB_2U(SCH_1):PAGE323_I64@PURE_QUANTA.Q_RES(CHIPS)':
 'A': CDS_PINID='A';
NODE_NAME     PR3963 1
 '@S9S_MB_2U_LIB.S9S_MB_2U(SCH_1):PAGE324_I18@PURE_QUANTA.Q_RES(CHIPS)':
 'A': CDS_PINID='A';
NODE_NAME     PU295 A3
 '@S9S_MB_2U_LIB.S9S_MB_2U(SCH_1):PAGE324_I35@PURE_QUANTA.MAX15090BEWIT(CHIPS)':
 'IN_A3': CDS_PINID='IN_A3';
NODE_NAME     PU295 A5
 '@S9S_MB_2U_LIB.S9S_MB_2U(SCH_1):PAGE324_I35@PURE_QUANTA.MAX15090BEWIT(CHIPS)':
 'IN_A5': CDS_PINID='IN_A5';
NODE_NAME     PU295 B3
 '@S9S_MB_2U_LIB.S9S_MB_2U(SCH_1):PAGE324_I35@PURE_QUANTA.MAX15090BEWIT(CHIPS)':
 'IN_B3': CDS_PINID='IN_B3';
NODE_NAME     PU295 B5
 '@S9S_MB_2U_LIB.S9S_MB_2U(SCH_1):PAGE324_I35@PURE_QUANTA.MAX15090BEWIT(CHIPS)':
 'IN_B5': CDS_PINID='IN_B5';
NODE_NAME     PU295 C3
 '@S9S_MB_2U_LIB.S9S_MB_2U(SCH_1):PAGE324_I35@PURE_QUANTA.MAX15090BEWIT(CHIPS)':
 'IN_C3': CDS_PINID='IN_C3';
NODE_NAME     PU295 C5
 '@S9S_MB_2U_LIB.S9S_MB_2U(SCH_1):PAGE324_I35@PURE_QUANTA.MAX15090BEWIT(CHIPS)':
 'IN_C5': CDS_PINID='IN_C5';
NODE_NAME     PU295 D5
 '@S9S_MB_2U_LIB.S9S_MB_2U(SCH_1):PAGE324_I35@PURE_QUANTA.MAX15090BEWIT(CHIPS)':
 'IN_D5': CDS_PINID='IN_D5';
NODE_NAME     R3976 1
 '@S9S_MB_2U_LIB.S9S_MB_2U(SCH_1):PAGE324_I73@PURE_QUANTA.Q_RES(CHIPS)':
 'A': CDS_PINID='A';
NODE_NAME     PR836 2
 '@S9S_MB_2U_LIB.S9S_MB_2U(SCH_1):PAGE245_I121@PURE_QUANTA.Q_RES(CHIPS)':
 'B': CDS_PINID='B';
NODE_NAME     PC569 2
 '@S9S_MB_2U_LIB.S9S_MB_2U(SCH_1):PAGE245_I127@PURE_QUANTA.Q_CAP(CHIPS)':
 'B': CDS_PINID='B';
NODE_NAME     PR831 2
 '@S9S_MB_2U_LIB.S9S_MB_2U(SCH_1):PAGE245_I128@PURE_QUANTA.Q_RES(CHIPS)':
 'B': CDS_PINID='B';
NODE_NAME     PL66 2
 '@S9S_MB_2U_LIB.S9S_MB_2U(SCH_1):PAGE245_I129@PURE_QUANTA.Q_INDUCTOR(CHIPS)':
 '2': CDS_PINID='\2\';
NODE_NAME     PC1866 1
 '@S9S_MB_2U_LIB.S9S_MB_2U(SCH_1):PAGE245_I131@PURE_QUANTA.Q_CAPP(CHIPS)':
 'A': CDS_PINID='A';
NODE_NAME     PC1867 1
 '@S9S_MB_2U_LIB.S9S_MB_2U(SCH_1):PAGE245_I132@PURE_QUANTA.Q_CAPP(CHIPS)':
 'A': CDS_PINID='A';
NODE_NAME     PC1868 1
 '@S9S_MB_2U_LIB.S9S_MB_2U(SCH_1):PAGE245_I133@PURE_QUANTA.Q_CAP(CHIPS)':
 'A': CDS_PINID='A';
NODE_NAME     PC1599 1
 '@S9S_MB_2U_LIB.S9S_MB_2U(SCH_1):PAGE245_I134@PURE_QUANTA.Q_CAP(CHIPS)':
 'A': CDS_PINID='A';
NODE_NAME     PC1600 1
 '@S9S_MB_2U_LIB.S9S_MB_2U(SCH_1):PAGE245_I136@PURE_QUANTA.Q_CAP(CHIPS)':
 'A': CDS_PINID='A';
NODE_NAME     PC1869 1
 '@S9S_MB_2U_LIB.S9S_MB_2U(SCH_1):PAGE245_I137@PURE_QUANTA.Q_CAP(CHIPS)':
 'A': CDS_PINID='A';
NODE_NAME     PR73 1
 '@S9S_MB_2U_LIB.S9S_MB_2U(SCH_1):PAGE245_I139@PURE_QUANTA.Q_RES(CHIPS)':
 'A': CDS_PINID='A';
NODE_NAME     R2359 1
 '@S9S_MB_2U_LIB.S9S_MB_2U(SCH_1):PAGE249_I31@PURE_QUANTA.Q_RES(CHIPS)':
 'A': CDS_PINID='A';
NODE_NAME     PR1335 1
 '@S9S_MB_2U_LIB.S9S_MB_2U(SCH_1):PAGE267_I5@PURE_QUANTA.Q_RES(CHIPS)':
 'A': CDS_PINID='A';
NODE_NAME     R2338 1
 '@S9S_MB_2U_LIB.S9S_MB_2U(SCH_1):PAGE268_I5@PURE_QUANTA.Q_RES(CHIPS)':
 'A': CDS_PINID='A';
NODE_NAME     R2367 1
 '@S9S_MB_2U_LIB.S9S_MB_2U(SCH_1):PAGE285_I14@PURE_QUANTA.Q_RES(CHIPS)':
 'A': CDS_PINID='A';
NODE_NAME     R2384 1
 '@S9S_MB_2U_LIB.S9S_MB_2U(SCH_1):PAGE286_I5@PURE_QUANTA.Q_RES(CHIPS)':
 'A': CDS_PINID='A';
NODE_NAME     R3836 1
 '@S9S_MB_2U_LIB.S9S_MB_2U(SCH_1):PAGE229_I92@PURE_QUANTA.Q_RES(CHIPS)':
 'A': CDS_PINID='A';
NODE_NAME     C1317 1
 '@S9S_MB_2U_LIB.S9S_MB_2U(SCH_1):PAGE232_I9@PURE_QUANTA.Q_CAP(CHIPS)':
 'A': CDS_PINID='A';
NODE_NAME     U95 5
 '@S9S_MB_2U_LIB.S9S_MB_2U(SCH_1):PAGE232_I11@PURE_QUANTA.74LVC1G07SE7(CHIPS)':
 'VCC': CDS_PINID='VCC';
NODE_NAME     R1690 1
 '@S9S_MB_2U_LIB.S9S_MB_2U(SCH_1):PAGE232_I22@PURE_QUANTA.Q_RES(CHIPS)':
 'A': CDS_PINID='A';
NODE_NAME     C1315 1
 '@S9S_MB_2U_LIB.S9S_MB_2U(SCH_1):PAGE232_I24@PURE_QUANTA.Q_CAP(CHIPS)':
 'A': CDS_PINID='A';
NODE_NAME     U117 6
 '@S9S_MB_2U_LIB.S9S_MB_2U(SCH_1):PAGE232_I26@PURE_QUANTA.TPS3895ADRYR(CHIPS)':
 'VCC': CDS_PINID='VCC';
NODE_NAME     U94 6
 '@S9S_MB_2U_LIB.S9S_MB_2U(SCH_1):PAGE232_I27@PURE_QUANTA.ADM1086AKSZREEL7(CHIPS)':
 'VCC': CDS_PINID='VCC';
NODE_NAME     R2486 1
 '@S9S_MB_2U_LIB.S9S_MB_2U(SCH_1):PAGE232_I40@PURE_QUANTA.Q_RES(CHIPS)':
 'A': CDS_PINID='A';
NODE_NAME     U15 16
 '@S9S_MB_2U_LIB.S9S_MB_2U(SCH_1):PAGE217_I19@PURE_QUANTA.QS3VH257QG8(CHIPS)':
 'VCC': CDS_PINID='VCC';
NODE_NAME     C538 1
 '@S9S_MB_2U_LIB.S9S_MB_2U(SCH_1):PAGE217_I24@PURE_QUANTA.Q_CAP(CHIPS)':
 'A': CDS_PINID='A';
NODE_NAME     R87 1
 '@S9S_MB_2U_LIB.S9S_MB_2U(SCH_1):PAGE217_I43@PURE_QUANTA.Q_RES(CHIPS)':
 'A': CDS_PINID='A';
NODE_NAME     R4580 1
 '@S9S_MB_2U_LIB.S9S_MB_2U(SCH_1):PAGE184_I5@PURE_QUANTA.Q_RES(CHIPS)':
 'A': CDS_PINID='A';
NODE_NAME     R4591 1
 '@S9S_MB_2U_LIB.S9S_MB_2U(SCH_1):PAGE184_I6@PURE_QUANTA.Q_RES(CHIPS)':
 'A': CDS_PINID='A';
NODE_NAME     R4582 1
 '@S9S_MB_2U_LIB.S9S_MB_2U(SCH_1):PAGE184_I23@PURE_QUANTA.Q_RES(CHIPS)':
 'A': CDS_PINID='A';
NODE_NAME     R4584 1
 '@S9S_MB_2U_LIB.S9S_MB_2U(SCH_1):PAGE184_I24@PURE_QUANTA.Q_RES(CHIPS)':
 'A': CDS_PINID='A';
NODE_NAME     R2950 1
 '@S9S_MB_2U_LIB.S9S_MB_2U(SCH_1):PAGE233_I4@PURE_QUANTA.Q_RES(CHIPS)':
 'A': CDS_PINID='A';
NODE_NAME     U192 8
 '@S9S_MB_2U_LIB.S9S_MB_2U(SCH_1):PAGE233_I16@PURE_QUANTA.LTC4307CMS8(CHIPS)':
 'VCC': CDS_PINID='VCC';
NODE_NAME     C1751 1
 '@S9S_MB_2U_LIB.S9S_MB_2U(SCH_1):PAGE233_I19@PURE_QUANTA.Q_CAP(CHIPS)':
 'A': CDS_PINID='A';
NODE_NAME     R2805 1
 '@S9S_MB_2U_LIB.S9S_MB_2U(SCH_1):PAGE233_I22@PURE_QUANTA.Q_RES(CHIPS)':
 'A': CDS_PINID='A';
NODE_NAME     R2807 1
 '@S9S_MB_2U_LIB.S9S_MB_2U(SCH_1):PAGE233_I24@PURE_QUANTA.Q_RES(CHIPS)':
 'A': CDS_PINID='A';
NODE_NAME     R4701 1
 '@S9S_MB_2U_LIB.S9S_MB_2U(SCH_1):PAGE233_I41@PURE_QUANTA.Q_RES(CHIPS)':
 'A': CDS_PINID='A';
NODE_NAME     U14 16
 '@S9S_MB_2U_LIB.S9S_MB_2U(SCH_1):PAGE218_I12@PURE_QUANTA.QS3VH257QG8(CHIPS)':
 'VCC': CDS_PINID='VCC';
NODE_NAME     C537 1
 '@S9S_MB_2U_LIB.S9S_MB_2U(SCH_1):PAGE218_I25@PURE_QUANTA.Q_CAP(CHIPS)':
 'A': CDS_PINID='A';
NODE_NAME     U200 8
 '@S9S_MB_2U_LIB.S9S_MB_2U(SCH_1):PAGE222_I11@PURE_QUANTA.LTC4307CMS8(CHIPS)':
 'VCC': CDS_PINID='VCC';
NODE_NAME     C1796 1
 '@S9S_MB_2U_LIB.S9S_MB_2U(SCH_1):PAGE222_I20@PURE_QUANTA.Q_CAP(CHIPS)':
 'A': CDS_PINID='A';
NODE_NAME     R3521 1
 '@S9S_MB_2U_LIB.S9S_MB_2U(SCH_1):PAGE222_I23@PURE_QUANTA.Q_RES(CHIPS)':
 'A': CDS_PINID='A';
NODE_NAME     R3522 1
 '@S9S_MB_2U_LIB.S9S_MB_2U(SCH_1):PAGE222_I25@PURE_QUANTA.Q_RES(CHIPS)':
 'A': CDS_PINID='A';
NODE_NAME     U176 8
 '@S9S_MB_2U_LIB.S9S_MB_2U(SCH_1):PAGE222_I31@PURE_QUANTA.LTC4307CMS8(CHIPS)':
 'VCC': CDS_PINID='VCC';
NODE_NAME     U175 8
 '@S9S_MB_2U_LIB.S9S_MB_2U(SCH_1):PAGE222_I50@PURE_QUANTA.LTC4307CMS8(CHIPS)':
 'VCC': CDS_PINID='VCC';
NODE_NAME     C1707 1
 '@S9S_MB_2U_LIB.S9S_MB_2U(SCH_1):PAGE222_I58@PURE_QUANTA.Q_CAP(CHIPS)':
 'A': CDS_PINID='A';
NODE_NAME     R2667 1
 '@S9S_MB_2U_LIB.S9S_MB_2U(SCH_1):PAGE222_I59@PURE_QUANTA.Q_RES(CHIPS)':
 'A': CDS_PINID='A';
NODE_NAME     R2669 1
 '@S9S_MB_2U_LIB.S9S_MB_2U(SCH_1):PAGE222_I61@PURE_QUANTA.Q_RES(CHIPS)':
 'A': CDS_PINID='A';
NODE_NAME     U194 8
 '@S9S_MB_2U_LIB.S9S_MB_2U(SCH_1):PAGE222_I63@PURE_QUANTA.LTC4307CMS8(CHIPS)':
 'VCC': CDS_PINID='VCC';
NODE_NAME     R2668 1
 '@S9S_MB_2U_LIB.S9S_MB_2U(SCH_1):PAGE222_I75@PURE_QUANTA.Q_RES(CHIPS)':
 'A': CDS_PINID='A';
NODE_NAME     R2670 1
 '@S9S_MB_2U_LIB.S9S_MB_2U(SCH_1):PAGE222_I77@PURE_QUANTA.Q_RES(CHIPS)':
 'A': CDS_PINID='A';
NODE_NAME     R3523 1
 '@S9S_MB_2U_LIB.S9S_MB_2U(SCH_1):PAGE222_I80@PURE_QUANTA.Q_RES(CHIPS)':
 'A': CDS_PINID='A';
NODE_NAME     R3524 1
 '@S9S_MB_2U_LIB.S9S_MB_2U(SCH_1):PAGE222_I81@PURE_QUANTA.Q_RES(CHIPS)':
 'A': CDS_PINID='A';
NODE_NAME     R536 1
 '@S9S_MB_2U_LIB.S9S_MB_2U(SCH_1):PAGE219_I3@PURE_QUANTA.Q_RES(CHIPS)':
 'A': CDS_PINID='A';
NODE_NAME     R1822 1
 '@S9S_MB_2U_LIB.S9S_MB_2U(SCH_1):PAGE219_I18@PURE_QUANTA.Q_RES(CHIPS)':
 'A': CDS_PINID='A';
NODE_NAME     R1090 1
 '@S9S_MB_2U_LIB.S9S_MB_2U(SCH_1):PAGE219_I20@PURE_QUANTA.Q_RES(CHIPS)':
 'A': CDS_PINID='A';
NODE_NAME     R1089 1
 '@S9S_MB_2U_LIB.S9S_MB_2U(SCH_1):PAGE219_I21@PURE_QUANTA.Q_RES(CHIPS)':
 'A': CDS_PINID='A';
NODE_NAME     R651 1
 '@S9S_MB_2U_LIB.S9S_MB_2U(SCH_1):PAGE219_I22@PURE_QUANTA.Q_RES(CHIPS)':
 'A': CDS_PINID='A';
NODE_NAME     R652 1
 '@S9S_MB_2U_LIB.S9S_MB_2U(SCH_1):PAGE219_I23@PURE_QUANTA.Q_RES(CHIPS)':
 'A': CDS_PINID='A';
NODE_NAME     R2985 1
 '@S9S_MB_2U_LIB.S9S_MB_2U(SCH_1):PAGE219_I24@PURE_QUANTA.Q_RES(CHIPS)':
 'A': CDS_PINID='A';
NODE_NAME     R2984 1
 '@S9S_MB_2U_LIB.S9S_MB_2U(SCH_1):PAGE219_I25@PURE_QUANTA.Q_RES(CHIPS)':
 'A': CDS_PINID='A';
NODE_NAME     U36 24
 '@S9S_MB_2U_LIB.S9S_MB_2U(SCH_1):PAGE219_I45@PURE_QUANTA.TCA9548APWR(CHIPS)':
 'VCC': CDS_PINID='VCC';
NODE_NAME     C174 1
 '@S9S_MB_2U_LIB.S9S_MB_2U(SCH_1):PAGE219_I47@PURE_QUANTA.Q_CAP(CHIPS)':
 'A': CDS_PINID='A';
NODE_NAME     R3535 1
 '@S9S_MB_2U_LIB.S9S_MB_2U(SCH_1):PAGE219_I49@PURE_QUANTA.Q_RES(CHIPS)':
 'A': CDS_PINID='A';
NODE_NAME     R3536 1
 '@S9S_MB_2U_LIB.S9S_MB_2U(SCH_1):PAGE219_I50@PURE_QUANTA.Q_RES(CHIPS)':
 'A': CDS_PINID='A';
NODE_NAME     R3583 1
 '@S9S_MB_2U_LIB.S9S_MB_2U(SCH_1):PAGE219_I51@PURE_QUANTA.Q_RES(CHIPS)':
 'A': CDS_PINID='A';
NODE_NAME     R3582 1
 '@S9S_MB_2U_LIB.S9S_MB_2U(SCH_1):PAGE219_I52@PURE_QUANTA.Q_RES(CHIPS)':
 'A': CDS_PINID='A';
NODE_NAME     R3396 1
 '@S9S_MB_2U_LIB.S9S_MB_2U(SCH_1):PAGE219_I53@PURE_QUANTA.Q_RES(CHIPS)':
 'A': CDS_PINID='A';
NODE_NAME     R3395 1
 '@S9S_MB_2U_LIB.S9S_MB_2U(SCH_1):PAGE219_I54@PURE_QUANTA.Q_RES(CHIPS)':
 'A': CDS_PINID='A';
NODE_NAME     R2205 1
 '@S9S_MB_2U_LIB.S9S_MB_2U(SCH_1):PAGE219_I56@PURE_QUANTA.Q_RES(CHIPS)':
 'A': CDS_PINID='A';
NODE_NAME     R2204 1
 '@S9S_MB_2U_LIB.S9S_MB_2U(SCH_1):PAGE219_I57@PURE_QUANTA.Q_RES(CHIPS)':
 'A': CDS_PINID='A';
NODE_NAME     R4634 1
 '@S9S_MB_2U_LIB.S9S_MB_2U(SCH_1):PAGE235_I4@PURE_QUANTA.Q_RES(CHIPS)':
 'A': CDS_PINID='A';
NODE_NAME     R4623 1
 '@S9S_MB_2U_LIB.S9S_MB_2U(SCH_1):PAGE235_I11@PURE_QUANTA.Q_RES(CHIPS)':
 'A': CDS_PINID='A';
NODE_NAME     U327 14
 '@S9S_MB_2U_LIB.S9S_MB_2U(SCH_1):PAGE235_I19@PURE_QUANTA.74CBTLV3126PW(CHIPS)':
 'VCC': CDS_PINID='VCC';
NODE_NAME     C2348 1
 '@S9S_MB_2U_LIB.S9S_MB_2U(SCH_1):PAGE235_I23@PURE_QUANTA.Q_CAP(CHIPS)':
 'A': CDS_PINID='A';
NODE_NAME     U331 9
 '@S9S_MB_2U_LIB.S9S_MB_2U(SCH_1):PAGE240_I39@PURE_QUANTA.INA230AIRGTR(CHIPS)':
 'VS': CDS_PINID='VS';
NODE_NAME     R4589 1
 '@S9S_MB_2U_LIB.S9S_MB_2U(SCH_1):PAGE184_I63@PURE_QUANTA.Q_RES(CHIPS)':
 'A': CDS_PINID='A';
NODE_NAME     R4579 1
 '@S9S_MB_2U_LIB.S9S_MB_2U(SCH_1):PAGE184_I67@PURE_QUANTA.Q_RES(CHIPS)':
 'A': CDS_PINID='A';
NET_NAME
'P3V3_AUX_ADC'
 '@S9S_MB_2U_LIB.S9S_MB_2U(SCH_1):P3V3_AUX_ADC':
 C_SIGNAL='@s9s_mb_2u_lib.s9s_mb_2u(sch_1):p3v3_aux_adc';
NODE_NAME     R2907 2
 '@S9S_MB_2U_LIB.S9S_MB_2U(SCH_1):PAGE239_I141@PURE_QUANTA.Q_RES(CHIPS)':
 'B': CDS_PINID='B';
NODE_NAME     R1785 1
 '@S9S_MB_2U_LIB.S9S_MB_2U(SCH_1):PAGE239_I149@PURE_QUANTA.Q_RES(CHIPS)':
 'A': CDS_PINID='A';
NODE_NAME     R3681 1
 '@S9S_MB_2U_LIB.S9S_MB_2U(SCH_1):PAGE239_I176@PURE_QUANTA.Q_RES(CHIPS)':
 'A': CDS_PINID='A';
NODE_NAME     R3682 1
 '@S9S_MB_2U_LIB.S9S_MB_2U(SCH_1):PAGE239_I179@PURE_QUANTA.Q_RES(CHIPS)':
 'A': CDS_PINID='A';
NET_NAME
'P3V3_AUX_ADC_MAM'
 '@S9S_MB_2U_LIB.S9S_MB_2U(SCH_1):P3V3_AUX_ADC_MAM':
 C_SIGNAL='@s9s_mb_2u_lib.s9s_mb_2u(sch_1):p3v3_aux_adc_mam';
NODE_NAME     U193 10
 '@S9S_MB_2U_LIB.S9S_MB_2U(SCH_1):PAGE239_I57@PURE_QUANTA.MAX11617EEET(CHIPS)':
 'AIN5': CDS_PINID='AIN5';
NODE_NAME     R3681 2
 '@S9S_MB_2U_LIB.S9S_MB_2U(SCH_1):PAGE239_I176@PURE_QUANTA.Q_RES(CHIPS)':
 'B': CDS_PINID='B';
NODE_NAME     C2042 1
 '@S9S_MB_2U_LIB.S9S_MB_2U(SCH_1):PAGE239_I180@PURE_QUANTA.Q_CAP(CHIPS)':
 'A': CDS_PINID='A';
NET_NAME
'P3V3_AUX_ADC_TIC'
 '@S9S_MB_2U_LIB.S9S_MB_2U(SCH_1):P3V3_AUX_ADC_TIC':
 C_SIGNAL='@s9s_mb_2u_lib.s9s_mb_2u(sch_1):p3v3_aux_adc_tic';
NODE_NAME     U269 11
 '@S9S_MB_2U_LIB.S9S_MB_2U(SCH_1):PAGE239_I103@PURE_QUANTA.ADC128D818CIMTXNOPB(CHIPS)':
 'IN5': CDS_PINID='IN5';
NODE_NAME     R3682 2
 '@S9S_MB_2U_LIB.S9S_MB_2U(SCH_1):PAGE239_I179@PURE_QUANTA.Q_RES(CHIPS)':
 'B': CDS_PINID='B';
NODE_NAME     C2047 1
 '@S9S_MB_2U_LIB.S9S_MB_2U(SCH_1):PAGE239_I181@PURE_QUANTA.Q_CAP(CHIPS)':
 'A': CDS_PINID='A';
NET_NAME
'P3V3_AUX_BMC_D'
 '@S9S_MB_2U_LIB.S9S_MB_2U(SCH_1):P3V3_AUX_BMC_D':
 C_SIGNAL='@s9s_mb_2u_lib.s9s_mb_2u(sch_1):p3v3_aux_bmc_d';
NODE_NAME     J43 1
 '@S9S_MB_2U_LIB.S9S_MB_2U(SCH_1):PAGE210_I79@PURE_QUANTA.CONN8_210HP1080BR1(CHIPS)':
 '1': CDS_PINID='\1\';
NODE_NAME     C554 1
 '@S9S_MB_2U_LIB.S9S_MB_2U(SCH_1):PAGE210_I86@PURE_QUANTA.Q_CAP(CHIPS)':
 'A': CDS_PINID='A';
NODE_NAME     C563 1
 '@S9S_MB_2U_LIB.S9S_MB_2U(SCH_1):PAGE210_I88@PURE_QUANTA.Q_CAP(CHIPS)':
 'A': CDS_PINID='A';
NODE_NAME     D141 2
 '@S9S_MB_2U_LIB.S9S_MB_2U(SCH_1):PAGE210_I91@PURE_QUANTA.SCHOTTKY_12(CHIPS)':
 'C': CDS_PINID='C';
NET_NAME
'P3V3_AUX_CLK_GEN_VDDA100M_CK440'
 '@S9S_MB_2U_LIB.S9S_MB_2U(SCH_1):P3V3_AUX_CLK_GEN_VDDA100M_CK440':
 C_SIGNAL='@s9s_mb_2u_lib.s9s_mb_2u(sch_1):p3v3_aux_clk_gen_vdda100m_ck440',
 CDS_GLOBAL_NET='TRUE';
NODE_NAME     U13 B17
 '@S9S_MB_2U_LIB.S9S_MB_2U(SCH_1):PAGE197_I180@PURE_QUANTA.9SQ440NQQI8(CHIPS)':
 'VDDA100M': CDS_PINID='VDDA100M';
NODE_NAME     C172 1
 '@S9S_MB_2U_LIB.S9S_MB_2U(SCH_1):PAGE199_I6@PURE_QUANTA.Q_CAP(CHIPS)':
 'A': CDS_PINID='A';
NODE_NAME     R519 2
 '@S9S_MB_2U_LIB.S9S_MB_2U(SCH_1):PAGE199_I7@PURE_QUANTA.Q_RES(CHIPS)':
 'B': CDS_PINID='B';
NODE_NAME     C173 1
 '@S9S_MB_2U_LIB.S9S_MB_2U(SCH_1):PAGE199_I78@PURE_QUANTA.Q_CAP(CHIPS)':
 'A': CDS_PINID='A';
NET_NAME
'P3V3_AUX_CLK_GEN_VDDA25M_CK440'
 '@S9S_MB_2U_LIB.S9S_MB_2U(SCH_1):P3V3_AUX_CLK_GEN_VDDA25M_CK440':
 C_SIGNAL='@s9s_mb_2u_lib.s9s_mb_2u(sch_1):p3v3_aux_clk_gen_vdda25m_ck440',
 CDS_GLOBAL_NET='TRUE';
NODE_NAME     U13 B1
 '@S9S_MB_2U_LIB.S9S_MB_2U(SCH_1):PAGE197_I180@PURE_QUANTA.9SQ440NQQI8(CHIPS)':
 'VDDA25M': CDS_PINID='VDDA25M';
NODE_NAME     R442 2
 '@S9S_MB_2U_LIB.S9S_MB_2U(SCH_1):PAGE199_I36@PURE_QUANTA.Q_RES(CHIPS)':
 'B': CDS_PINID='B';
NODE_NAME     C1313 1
 '@S9S_MB_2U_LIB.S9S_MB_2U(SCH_1):PAGE199_I48@PURE_QUANTA.Q_CAP(CHIPS)':
 'A': CDS_PINID='A';
NODE_NAME     C114 1
 '@S9S_MB_2U_LIB.S9S_MB_2U(SCH_1):PAGE199_I79@PURE_QUANTA.Q_CAP(CHIPS)':
 'A': CDS_PINID='A';
NET_NAME
'P3V3_AUX_CLK_GEN_VDDMXCK_CK440'
 '@S9S_MB_2U_LIB.S9S_MB_2U(SCH_1):P3V3_AUX_CLK_GEN_VDDMXCK_CK440':
 C_SIGNAL='@s9s_mb_2u_lib.s9s_mb_2u(sch_1):p3v3_aux_clk_gen_vddmxck_ck440',
 CDS_GLOBAL_NET='TRUE';
NODE_NAME     U13 B29
 '@S9S_MB_2U_LIB.S9S_MB_2U(SCH_1):PAGE197_I180@PURE_QUANTA.9SQ440NQQI8(CHIPS)':
 'VDDMXCK_B29': CDS_PINID='VDDMXCK_B29';
NODE_NAME     U13 B32
 '@S9S_MB_2U_LIB.S9S_MB_2U(SCH_1):PAGE197_I180@PURE_QUANTA.9SQ440NQQI8(CHIPS)':
 'VDDMXCK_B32': CDS_PINID='VDDMXCK_B32';
NODE_NAME     U13 B35
 '@S9S_MB_2U_LIB.S9S_MB_2U(SCH_1):PAGE197_I180@PURE_QUANTA.9SQ440NQQI8(CHIPS)':
 'VDDMXCK_B35': CDS_PINID='VDDMXCK_B35';
NODE_NAME     U13 B40
 '@S9S_MB_2U_LIB.S9S_MB_2U(SCH_1):PAGE197_I180@PURE_QUANTA.9SQ440NQQI8(CHIPS)':
 'VDDMXCK_B40': CDS_PINID='VDDMXCK_B40';
NODE_NAME     R447 1
 '@S9S_MB_2U_LIB.S9S_MB_2U(SCH_1):PAGE199_I55@PURE_QUANTA.Q_RES(CHIPS)':
 'A': CDS_PINID='A';
NODE_NAME     C1312 1
 '@S9S_MB_2U_LIB.S9S_MB_2U(SCH_1):PAGE199_I58@PURE_QUANTA.Q_CAP(CHIPS)':
 'A': CDS_PINID='A';
NODE_NAME     C1310 1
 '@S9S_MB_2U_LIB.S9S_MB_2U(SCH_1):PAGE199_I59@PURE_QUANTA.Q_CAP(CHIPS)':
 'A': CDS_PINID='A';
NODE_NAME     L14 2
 '@S9S_MB_2U_LIB.S9S_MB_2U(SCH_1):PAGE199_I60@PURE_QUANTA.Q_INDUCTOR(CHIPS)':
 '2': CDS_PINID='\2\';
NODE_NAME     C119 1
 '@S9S_MB_2U_LIB.S9S_MB_2U(SCH_1):PAGE199_I86@PURE_QUANTA.Q_CAP(CHIPS)':
 'A': CDS_PINID='A';
NODE_NAME     C117 1
 '@S9S_MB_2U_LIB.S9S_MB_2U(SCH_1):PAGE199_I87@PURE_QUANTA.Q_CAP(CHIPS)':
 'A': CDS_PINID='A';
NODE_NAME     C116 1
 '@S9S_MB_2U_LIB.S9S_MB_2U(SCH_1):PAGE199_I88@PURE_QUANTA.Q_CAP(CHIPS)':
 'A': CDS_PINID='A';
NODE_NAME     C115 1
 '@S9S_MB_2U_LIB.S9S_MB_2U(SCH_1):PAGE199_I89@PURE_QUANTA.Q_CAP(CHIPS)':
 'A': CDS_PINID='A';
NET_NAME
'P3V3_AUX_CLK_GEN_VDDPT_CK440'
 '@S9S_MB_2U_LIB.S9S_MB_2U(SCH_1):P3V3_AUX_CLK_GEN_VDDPT_CK440':
 C_SIGNAL='@s9s_mb_2u_lib.s9s_mb_2u(sch_1):p3v3_aux_clk_gen_vddpt_ck440',
 CDS_GLOBAL_NET='TRUE';
NODE_NAME     U13 B6
 '@S9S_MB_2U_LIB.S9S_MB_2U(SCH_1):PAGE197_I180@PURE_QUANTA.9SQ440NQQI8(CHIPS)':
 'VDDPT': CDS_PINID='VDDPT';
NODE_NAME     C1314 1
 '@S9S_MB_2U_LIB.S9S_MB_2U(SCH_1):PAGE199_I53@PURE_QUANTA.Q_CAP(CHIPS)':
 'A': CDS_PINID='A';
NODE_NAME     R447 2
 '@S9S_MB_2U_LIB.S9S_MB_2U(SCH_1):PAGE199_I55@PURE_QUANTA.Q_RES(CHIPS)':
 'B': CDS_PINID='B';
NODE_NAME     C120 1
 '@S9S_MB_2U_LIB.S9S_MB_2U(SCH_1):PAGE199_I85@PURE_QUANTA.Q_CAP(CHIPS)':
 'A': CDS_PINID='A';
NET_NAME
'P3V3_AUX_CLK_GEN_VDDXTAL_CK440'
 '@S9S_MB_2U_LIB.S9S_MB_2U(SCH_1):P3V3_AUX_CLK_GEN_VDDXTAL_CK440':
 C_SIGNAL='@s9s_mb_2u_lib.s9s_mb_2u(sch_1):p3v3_aux_clk_gen_vddxtal_ck440',
 CDS_GLOBAL_NET='TRUE';
NODE_NAME     U13 A12
 '@S9S_MB_2U_LIB.S9S_MB_2U(SCH_1):PAGE197_I180@PURE_QUANTA.9SQ440NQQI8(CHIPS)':
 'VDDXTAL': CDS_PINID='VDDXTAL';
NODE_NAME     R442 1
 '@S9S_MB_2U_LIB.S9S_MB_2U(SCH_1):PAGE199_I36@PURE_QUANTA.Q_RES(CHIPS)':
 'A': CDS_PINID='A';
NODE_NAME     L13 2
 '@S9S_MB_2U_LIB.S9S_MB_2U(SCH_1):PAGE199_I41@PURE_QUANTA.Q_INDUCTOR(CHIPS)':
 '2': CDS_PINID='\2\';
NODE_NAME     C1311 1
 '@S9S_MB_2U_LIB.S9S_MB_2U(SCH_1):PAGE199_I43@PURE_QUANTA.Q_CAP(CHIPS)':
 'A': CDS_PINID='A';
NODE_NAME     C1309 1
 '@S9S_MB_2U_LIB.S9S_MB_2U(SCH_1):PAGE199_I44@PURE_QUANTA.Q_CAP(CHIPS)':
 'A': CDS_PINID='A';
NODE_NAME     C112 1
 '@S9S_MB_2U_LIB.S9S_MB_2U(SCH_1):PAGE199_I80@PURE_QUANTA.Q_CAP(CHIPS)':
 'A': CDS_PINID='A';
NODE_NAME     C111 1
 '@S9S_MB_2U_LIB.S9S_MB_2U(SCH_1):PAGE199_I81@PURE_QUANTA.Q_CAP(CHIPS)':
 'A': CDS_PINID='A';
NET_NAME
'P3V3_AUX_CLK_GEN_VDD_CK440'
 '@S9S_MB_2U_LIB.S9S_MB_2U(SCH_1):P3V3_AUX_CLK_GEN_VDD_CK440':
 C_SIGNAL='@s9s_mb_2u_lib.s9s_mb_2u(sch_1):p3v3_aux_clk_gen_vdd_ck440',
 CDS_GLOBAL_NET='TRUE';
NODE_NAME     U13 B21
 '@S9S_MB_2U_LIB.S9S_MB_2U(SCH_1):PAGE197_I180@PURE_QUANTA.9SQ440NQQI8(CHIPS)':
 'VDD100M_B21': CDS_PINID='VDD100M_B21';
NODE_NAME     U13 B23
 '@S9S_MB_2U_LIB.S9S_MB_2U(SCH_1):PAGE197_I180@PURE_QUANTA.9SQ440NQQI8(CHIPS)':
 'VDD100M_B23': CDS_PINID='VDD100M_B23';
NODE_NAME     R519 1
 '@S9S_MB_2U_LIB.S9S_MB_2U(SCH_1):PAGE199_I7@PURE_QUANTA.Q_RES(CHIPS)':
 'A': CDS_PINID='A';
NODE_NAME     C108 1
 '@S9S_MB_2U_LIB.S9S_MB_2U(SCH_1):PAGE199_I19@PURE_QUANTA.Q_CAP(CHIPS)':
 'A': CDS_PINID='A';
NODE_NAME     L1 2
 '@S9S_MB_2U_LIB.S9S_MB_2U(SCH_1):PAGE199_I20@PURE_QUANTA.Q_INDUCTOR(CHIPS)':
 '2': CDS_PINID='\2\';
NODE_NAME     C110 1
 '@S9S_MB_2U_LIB.S9S_MB_2U(SCH_1):PAGE199_I76@PURE_QUANTA.Q_CAP(CHIPS)':
 'A': CDS_PINID='A';
NODE_NAME     C171 1
 '@S9S_MB_2U_LIB.S9S_MB_2U(SCH_1):PAGE199_I77@PURE_QUANTA.Q_CAP(CHIPS)':
 'A': CDS_PINID='A';
NODE_NAME     C107 1
 '@S9S_MB_2U_LIB.S9S_MB_2U(SCH_1):PAGE199_I82@PURE_QUANTA.Q_CAP(CHIPS)':
 'A': CDS_PINID='A';
NET_NAME
'P3V3_AUX_EN'
 '@S9S_MB_2U_LIB.S9S_MB_2U(SCH_1):P3V3_AUX_EN':
 C_SIGNAL='@s9s_mb_2u_lib.s9s_mb_2u(sch_1):p3v3_aux_en';
NODE_NAME     D145 2
 '@S9S_MB_2U_LIB.S9S_MB_2U(SCH_1):PAGE245_I71@PURE_QUANTA.Q_DIODE(CHIPS)':
 '2': CDS_PINID='\2\';
NODE_NAME     R1571 2
 '@S9S_MB_2U_LIB.S9S_MB_2U(SCH_1):PAGE245_I72@PURE_QUANTA.Q_RES(CHIPS)':
 'B': CDS_PINID='B';
NODE_NAME     C2541 1
 '@S9S_MB_2U_LIB.S9S_MB_2U(SCH_1):PAGE245_I73@PURE_QUANTA.Q_CAP(CHIPS)':
 'A': CDS_PINID='A';
NODE_NAME     R3118 1
 '@S9S_MB_2U_LIB.S9S_MB_2U(SCH_1):PAGE245_I76@PURE_QUANTA.Q_RES(CHIPS)':
 'A': CDS_PINID='A';
NODE_NAME     R3117 2
 '@S9S_MB_2U_LIB.S9S_MB_2U(SCH_1):PAGE245_I78@PURE_QUANTA.Q_RES(CHIPS)':
 'B': CDS_PINID='B';
NODE_NAME     PU9 27
 '@S9S_MB_2U_LIB.S9S_MB_2U(SCH_1):PAGE245_I95@PURE_QUANTA.IR3889MTRPBF(CHIPS)':
 'EN': CDS_PINID='EN';
NET_NAME
'P3V3_AUX_FB'
 '@S9S_MB_2U_LIB.S9S_MB_2U(SCH_1):P3V3_AUX_FB':
 C_SIGNAL='@s9s_mb_2u_lib.s9s_mb_2u(sch_1):p3v3_aux_fb';
NODE_NAME     PU9 30
 '@S9S_MB_2U_LIB.S9S_MB_2U(SCH_1):PAGE245_I95@PURE_QUANTA.IR3889MTRPBF(CHIPS)':
 'FB': CDS_PINID='FB';
NODE_NAME     PR830 1
 '@S9S_MB_2U_LIB.S9S_MB_2U(SCH_1):PAGE245_I125@PURE_QUANTA.Q_RES(CHIPS)':
 'A': CDS_PINID='A';
NODE_NAME     PC569 1
 '@S9S_MB_2U_LIB.S9S_MB_2U(SCH_1):PAGE245_I127@PURE_QUANTA.Q_CAP(CHIPS)':
 'A': CDS_PINID='A';
NODE_NAME     PR831 1
 '@S9S_MB_2U_LIB.S9S_MB_2U(SCH_1):PAGE245_I128@PURE_QUANTA.Q_RES(CHIPS)':
 'A': CDS_PINID='A';
NET_NAME
'P3V3_AUX_FPGA_VCCIO0'
 '@S9S_MB_2U_LIB.S9S_MB_2U(SCH_1):P3V3_AUX_FPGA_VCCIO0':
 C_SIGNAL='@s9s_mb_2u_lib.s9s_mb_2u(sch_1):p3v3_aux_fpga_vccio0',
 CDS_GLOBAL_NET='TRUE';
NODE_NAME     C1932 1
 '@S9S_MB_2U_LIB.S9S_MB_2U(SCH_1):PAGE202_I9@PURE_QUANTA.Q_CAP(CHIPS)':
 'A': CDS_PINID='A';
NODE_NAME     C1929 1
 '@S9S_MB_2U_LIB.S9S_MB_2U(SCH_1):PAGE202_I33@PURE_QUANTA.Q_CAP(CHIPS)':
 'A': CDS_PINID='A';
NODE_NAME     C1926 1
 '@S9S_MB_2U_LIB.S9S_MB_2U(SCH_1):PAGE202_I34@PURE_QUANTA.Q_CAP(CHIPS)':
 'A': CDS_PINID='A';
NODE_NAME     C1917 1
 '@S9S_MB_2U_LIB.S9S_MB_2U(SCH_1):PAGE202_I35@PURE_QUANTA.Q_CAP(CHIPS)':
 'A': CDS_PINID='A';
NODE_NAME     C1914 1
 '@S9S_MB_2U_LIB.S9S_MB_2U(SCH_1):PAGE202_I36@PURE_QUANTA.Q_CAP(CHIPS)':
 'A': CDS_PINID='A';
NODE_NAME     C1905 1
 '@S9S_MB_2U_LIB.S9S_MB_2U(SCH_1):PAGE202_I41@PURE_QUANTA.Q_CAP(CHIPS)':
 'A': CDS_PINID='A';
NODE_NAME     C1901 1
 '@S9S_MB_2U_LIB.S9S_MB_2U(SCH_1):PAGE202_I42@PURE_QUANTA.Q_CAP(CHIPS)':
 'A': CDS_PINID='A';
NODE_NAME     C1895 1
 '@S9S_MB_2U_LIB.S9S_MB_2U(SCH_1):PAGE202_I43@PURE_QUANTA.Q_CAP(CHIPS)':
 'A': CDS_PINID='A';
NODE_NAME     C1910 1
 '@S9S_MB_2U_LIB.S9S_MB_2U(SCH_1):PAGE202_I44@PURE_QUANTA.Q_CAP(CHIPS)':
 'A': CDS_PINID='A';
NODE_NAME     C1945 1
 '@S9S_MB_2U_LIB.S9S_MB_2U(SCH_1):PAGE202_I62@PURE_QUANTA.Q_CAP(CHIPS)':
 'A': CDS_PINID='A';
NODE_NAME     R3346 2
 '@S9S_MB_2U_LIB.S9S_MB_2U(SCH_1):PAGE202_I63@PURE_QUANTA.Q_RES(CHIPS)':
 'B': CDS_PINID='B';
NODE_NAME     C1938 1
 '@S9S_MB_2U_LIB.S9S_MB_2U(SCH_1):PAGE202_I64@PURE_QUANTA.Q_CAP(CHIPS)':
 'A': CDS_PINID='A';
NODE_NAME     U249 C7
 '@S9S_MB_2U_LIB.S9S_MB_2U(SCH_1):PAGE202_I102@PURE_QUANTA.LCMXO3LF9400C5BG484C(CHIPS)':
 'VCCIO0_1': CDS_PINID='VCCIO0_1';
NODE_NAME     U249 C12
 '@S9S_MB_2U_LIB.S9S_MB_2U(SCH_1):PAGE202_I102@PURE_QUANTA.LCMXO3LF9400C5BG484C(CHIPS)':
 'VCCIO0_2': CDS_PINID='VCCIO0_2';
NODE_NAME     U249 C16
 '@S9S_MB_2U_LIB.S9S_MB_2U(SCH_1):PAGE202_I102@PURE_QUANTA.LCMXO3LF9400C5BG484C(CHIPS)':
 'VCCIO0_3': CDS_PINID='VCCIO0_3';
NODE_NAME     U249 G10
 '@S9S_MB_2U_LIB.S9S_MB_2U(SCH_1):PAGE202_I102@PURE_QUANTA.LCMXO3LF9400C5BG484C(CHIPS)':
 'VCCIO0_4': CDS_PINID='VCCIO0_4';
NODE_NAME     U249 G13
 '@S9S_MB_2U_LIB.S9S_MB_2U(SCH_1):PAGE202_I102@PURE_QUANTA.LCMXO3LF9400C5BG484C(CHIPS)':
 'VCCIO0_5': CDS_PINID='VCCIO0_5';
NODE_NAME     U249 H9
 '@S9S_MB_2U_LIB.S9S_MB_2U(SCH_1):PAGE202_I102@PURE_QUANTA.LCMXO3LF9400C5BG484C(CHIPS)':
 'VCCIO0_6': CDS_PINID='VCCIO0_6';
NODE_NAME     U249 H11
 '@S9S_MB_2U_LIB.S9S_MB_2U(SCH_1):PAGE202_I102@PURE_QUANTA.LCMXO3LF9400C5BG484C(CHIPS)':
 'VCCIO0_7': CDS_PINID='VCCIO0_7';
NODE_NAME     U249 H12
 '@S9S_MB_2U_LIB.S9S_MB_2U(SCH_1):PAGE202_I102@PURE_QUANTA.LCMXO3LF9400C5BG484C(CHIPS)':
 'VCCIO0_8': CDS_PINID='VCCIO0_8';
NODE_NAME     U249 H14
 '@S9S_MB_2U_LIB.S9S_MB_2U(SCH_1):PAGE202_I102@PURE_QUANTA.LCMXO3LF9400C5BG484C(CHIPS)':
 'VCCIO0_9': CDS_PINID='VCCIO0_9';
NET_NAME
'P3V3_AUX_FPGA_VCCIO1'
 '@S9S_MB_2U_LIB.S9S_MB_2U(SCH_1):P3V3_AUX_FPGA_VCCIO1':
 C_SIGNAL='@s9s_mb_2u_lib.s9s_mb_2u(sch_1):p3v3_aux_fpga_vccio1',
 CDS_GLOBAL_NET='TRUE';
NODE_NAME     C1933 1
 '@S9S_MB_2U_LIB.S9S_MB_2U(SCH_1):PAGE202_I12@PURE_QUANTA.Q_CAP(CHIPS)':
 'A': CDS_PINID='A';
NODE_NAME     C1930 1
 '@S9S_MB_2U_LIB.S9S_MB_2U(SCH_1):PAGE202_I37@PURE_QUANTA.Q_CAP(CHIPS)':
 'A': CDS_PINID='A';
NODE_NAME     C1927 1
 '@S9S_MB_2U_LIB.S9S_MB_2U(SCH_1):PAGE202_I38@PURE_QUANTA.Q_CAP(CHIPS)':
 'A': CDS_PINID='A';
NODE_NAME     C1918 1
 '@S9S_MB_2U_LIB.S9S_MB_2U(SCH_1):PAGE202_I39@PURE_QUANTA.Q_CAP(CHIPS)':
 'A': CDS_PINID='A';
NODE_NAME     C1915 1
 '@S9S_MB_2U_LIB.S9S_MB_2U(SCH_1):PAGE202_I40@PURE_QUANTA.Q_CAP(CHIPS)':
 'A': CDS_PINID='A';
NODE_NAME     C1906 1
 '@S9S_MB_2U_LIB.S9S_MB_2U(SCH_1):PAGE202_I45@PURE_QUANTA.Q_CAP(CHIPS)':
 'A': CDS_PINID='A';
NODE_NAME     C1902 1
 '@S9S_MB_2U_LIB.S9S_MB_2U(SCH_1):PAGE202_I46@PURE_QUANTA.Q_CAP(CHIPS)':
 'A': CDS_PINID='A';
NODE_NAME     C1896 1
 '@S9S_MB_2U_LIB.S9S_MB_2U(SCH_1):PAGE202_I47@PURE_QUANTA.Q_CAP(CHIPS)':
 'A': CDS_PINID='A';
NODE_NAME     C1911 1
 '@S9S_MB_2U_LIB.S9S_MB_2U(SCH_1):PAGE202_I48@PURE_QUANTA.Q_CAP(CHIPS)':
 'A': CDS_PINID='A';
NODE_NAME     C1946 1
 '@S9S_MB_2U_LIB.S9S_MB_2U(SCH_1):PAGE202_I65@PURE_QUANTA.Q_CAP(CHIPS)':
 'A': CDS_PINID='A';
NODE_NAME     C1939 1
 '@S9S_MB_2U_LIB.S9S_MB_2U(SCH_1):PAGE202_I66@PURE_QUANTA.Q_CAP(CHIPS)':
 'A': CDS_PINID='A';
NODE_NAME     R3348 2
 '@S9S_MB_2U_LIB.S9S_MB_2U(SCH_1):PAGE202_I67@PURE_QUANTA.Q_RES(CHIPS)':
 'B': CDS_PINID='B';
NODE_NAME     U249 F20
 '@S9S_MB_2U_LIB.S9S_MB_2U(SCH_1):PAGE202_I102@PURE_QUANTA.LCMXO3LF9400C5BG484C(CHIPS)':
 'VCCIO1_1': CDS_PINID='VCCIO1_1';
NODE_NAME     U249 J15
 '@S9S_MB_2U_LIB.S9S_MB_2U(SCH_1):PAGE202_I102@PURE_QUANTA.LCMXO3LF9400C5BG484C(CHIPS)':
 'VCCIO1_2': CDS_PINID='VCCIO1_2';
NODE_NAME     U249 K15
 '@S9S_MB_2U_LIB.S9S_MB_2U(SCH_1):PAGE202_I102@PURE_QUANTA.LCMXO3LF9400C5BG484C(CHIPS)':
 'VCCIO1_3': CDS_PINID='VCCIO1_3';
NODE_NAME     U249 L15
 '@S9S_MB_2U_LIB.S9S_MB_2U(SCH_1):PAGE202_I102@PURE_QUANTA.LCMXO3LF9400C5BG484C(CHIPS)':
 'VCCIO1_4': CDS_PINID='VCCIO1_4';
NODE_NAME     U249 M15
 '@S9S_MB_2U_LIB.S9S_MB_2U(SCH_1):PAGE202_I102@PURE_QUANTA.LCMXO3LF9400C5BG484C(CHIPS)':
 'VCCIO1_5': CDS_PINID='VCCIO1_5';
NODE_NAME     U249 M18
 '@S9S_MB_2U_LIB.S9S_MB_2U(SCH_1):PAGE202_I102@PURE_QUANTA.LCMXO3LF9400C5BG484C(CHIPS)':
 'VCCIO1_6': CDS_PINID='VCCIO1_6';
NODE_NAME     U249 N15
 '@S9S_MB_2U_LIB.S9S_MB_2U(SCH_1):PAGE202_I102@PURE_QUANTA.LCMXO3LF9400C5BG484C(CHIPS)':
 'VCCIO1_7': CDS_PINID='VCCIO1_7';
NODE_NAME     U249 P15
 '@S9S_MB_2U_LIB.S9S_MB_2U(SCH_1):PAGE202_I102@PURE_QUANTA.LCMXO3LF9400C5BG484C(CHIPS)':
 'VCCIO1_8': CDS_PINID='VCCIO1_8';
NODE_NAME     U249 V20
 '@S9S_MB_2U_LIB.S9S_MB_2U(SCH_1):PAGE202_I102@PURE_QUANTA.LCMXO3LF9400C5BG484C(CHIPS)':
 'VCCIO1_9': CDS_PINID='VCCIO1_9';
NET_NAME
'P3V3_AUX_FPGA_VCCIO2'
 '@S9S_MB_2U_LIB.S9S_MB_2U(SCH_1):P3V3_AUX_FPGA_VCCIO2':
 C_SIGNAL='@s9s_mb_2u_lib.s9s_mb_2u(sch_1):p3v3_aux_fpga_vccio2',
 CDS_GLOBAL_NET='TRUE';
NODE_NAME     C1146 1
 '@S9S_MB_2U_LIB.S9S_MB_2U(SCH_1):PAGE202_I15@PURE_QUANTA.Q_CAP(CHIPS)':
 'A': CDS_PINID='A';
NODE_NAME     C1142 1
 '@S9S_MB_2U_LIB.S9S_MB_2U(SCH_1):PAGE202_I49@PURE_QUANTA.Q_CAP(CHIPS)':
 'A': CDS_PINID='A';
NODE_NAME     C1138 1
 '@S9S_MB_2U_LIB.S9S_MB_2U(SCH_1):PAGE202_I50@PURE_QUANTA.Q_CAP(CHIPS)':
 'A': CDS_PINID='A';
NODE_NAME     C1133 1
 '@S9S_MB_2U_LIB.S9S_MB_2U(SCH_1):PAGE202_I51@PURE_QUANTA.Q_CAP(CHIPS)':
 'A': CDS_PINID='A';
NODE_NAME     C1127 1
 '@S9S_MB_2U_LIB.S9S_MB_2U(SCH_1):PAGE202_I52@PURE_QUANTA.Q_CAP(CHIPS)':
 'A': CDS_PINID='A';
NODE_NAME     C1122 1
 '@S9S_MB_2U_LIB.S9S_MB_2U(SCH_1):PAGE202_I56@PURE_QUANTA.Q_CAP(CHIPS)':
 'A': CDS_PINID='A';
NODE_NAME     C1900 1
 '@S9S_MB_2U_LIB.S9S_MB_2U(SCH_1):PAGE202_I57@PURE_QUANTA.Q_CAP(CHIPS)':
 'A': CDS_PINID='A';
NODE_NAME     C1894 1
 '@S9S_MB_2U_LIB.S9S_MB_2U(SCH_1):PAGE202_I58@PURE_QUANTA.Q_CAP(CHIPS)':
 'A': CDS_PINID='A';
NODE_NAME     C1909 1
 '@S9S_MB_2U_LIB.S9S_MB_2U(SCH_1):PAGE202_I59@PURE_QUANTA.Q_CAP(CHIPS)':
 'A': CDS_PINID='A';
NODE_NAME     C1944 1
 '@S9S_MB_2U_LIB.S9S_MB_2U(SCH_1):PAGE202_I70@PURE_QUANTA.Q_CAP(CHIPS)':
 'A': CDS_PINID='A';
NODE_NAME     C1937 1
 '@S9S_MB_2U_LIB.S9S_MB_2U(SCH_1):PAGE202_I71@PURE_QUANTA.Q_CAP(CHIPS)':
 'A': CDS_PINID='A';
NODE_NAME     R3347 2
 '@S9S_MB_2U_LIB.S9S_MB_2U(SCH_1):PAGE202_I72@PURE_QUANTA.Q_RES(CHIPS)':
 'B': CDS_PINID='B';
NODE_NAME     U249 R9
 '@S9S_MB_2U_LIB.S9S_MB_2U(SCH_1):PAGE202_I102@PURE_QUANTA.LCMXO3LF9400C5BG484C(CHIPS)':
 'VCCIO2_1': CDS_PINID='VCCIO2_1';
NODE_NAME     U249 R10
 '@S9S_MB_2U_LIB.S9S_MB_2U(SCH_1):PAGE202_I102@PURE_QUANTA.LCMXO3LF9400C5BG484C(CHIPS)':
 'VCCIO2_2': CDS_PINID='VCCIO2_2';
NODE_NAME     U249 R11
 '@S9S_MB_2U_LIB.S9S_MB_2U(SCH_1):PAGE202_I102@PURE_QUANTA.LCMXO3LF9400C5BG484C(CHIPS)':
 'VCCIO2_3': CDS_PINID='VCCIO2_3';
NODE_NAME     U249 R12
 '@S9S_MB_2U_LIB.S9S_MB_2U(SCH_1):PAGE202_I102@PURE_QUANTA.LCMXO3LF9400C5BG484C(CHIPS)':
 'VCCIO2_4': CDS_PINID='VCCIO2_4';
NODE_NAME     U249 R13
 '@S9S_MB_2U_LIB.S9S_MB_2U(SCH_1):PAGE202_I102@PURE_QUANTA.LCMXO3LF9400C5BG484C(CHIPS)':
 'VCCIO2_5': CDS_PINID='VCCIO2_5';
NODE_NAME     U249 R14
 '@S9S_MB_2U_LIB.S9S_MB_2U(SCH_1):PAGE202_I102@PURE_QUANTA.LCMXO3LF9400C5BG484C(CHIPS)':
 'VCCIO2_6': CDS_PINID='VCCIO2_6';
NODE_NAME     U249 W7
 '@S9S_MB_2U_LIB.S9S_MB_2U(SCH_1):PAGE202_I102@PURE_QUANTA.LCMXO3LF9400C5BG484C(CHIPS)':
 'VCCIO2_7': CDS_PINID='VCCIO2_7';
NODE_NAME     U249 W11
 '@S9S_MB_2U_LIB.S9S_MB_2U(SCH_1):PAGE202_I102@PURE_QUANTA.LCMXO3LF9400C5BG484C(CHIPS)':
 'VCCIO2_8': CDS_PINID='VCCIO2_8';
NODE_NAME     U249 W16
 '@S9S_MB_2U_LIB.S9S_MB_2U(SCH_1):PAGE202_I102@PURE_QUANTA.LCMXO3LF9400C5BG484C(CHIPS)':
 'VCCIO2_9': CDS_PINID='VCCIO2_9';
NODE_NAME     R4086 1
 '@S9S_MB_2U_LIB.S9S_MB_2U(SCH_1):PAGE312_I86@PURE_QUANTA.Q_RES(CHIPS)':
 'A': CDS_PINID='A';
NET_NAME
'P3V3_AUX_FPGA_VCCIO3'
 '@S9S_MB_2U_LIB.S9S_MB_2U(SCH_1):P3V3_AUX_FPGA_VCCIO3':
 C_SIGNAL='@s9s_mb_2u_lib.s9s_mb_2u(sch_1):p3v3_aux_fpga_vccio3',
 CDS_GLOBAL_NET='TRUE';
NODE_NAME     C1118 1
 '@S9S_MB_2U_LIB.S9S_MB_2U(SCH_1):PAGE202_I97@PURE_QUANTA.Q_CAP(CHIPS)':
 'A': CDS_PINID='A';
NODE_NAME     C1113 1
 '@S9S_MB_2U_LIB.S9S_MB_2U(SCH_1):PAGE202_I99@PURE_QUANTA.Q_CAP(CHIPS)':
 'A': CDS_PINID='A';
NODE_NAME     C1124 1
 '@S9S_MB_2U_LIB.S9S_MB_2U(SCH_1):PAGE202_I100@PURE_QUANTA.Q_CAP(CHIPS)':
 'A': CDS_PINID='A';
NODE_NAME     C1941 1
 '@S9S_MB_2U_LIB.S9S_MB_2U(SCH_1):PAGE202_I101@PURE_QUANTA.Q_CAP(CHIPS)':
 'A': CDS_PINID='A';
NODE_NAME     U249 N8
 '@S9S_MB_2U_LIB.S9S_MB_2U(SCH_1):PAGE202_I102@PURE_QUANTA.LCMXO3LF9400C5BG484C(CHIPS)':
 'VCCIO3_1': CDS_PINID='VCCIO3_1';
NODE_NAME     U249 P8
 '@S9S_MB_2U_LIB.S9S_MB_2U(SCH_1):PAGE202_I102@PURE_QUANTA.LCMXO3LF9400C5BG484C(CHIPS)':
 'VCCIO3_2': CDS_PINID='VCCIO3_2';
NODE_NAME     U249 V3
 '@S9S_MB_2U_LIB.S9S_MB_2U(SCH_1):PAGE202_I102@PURE_QUANTA.LCMXO3LF9400C5BG484C(CHIPS)':
 'VCCIO3_3': CDS_PINID='VCCIO3_3';
NODE_NAME     C1842 1
 '@S9S_MB_2U_LIB.S9S_MB_2U(SCH_1):PAGE202_I107@PURE_QUANTA.Q_CAP(CHIPS)':
 'A': CDS_PINID='A';
NODE_NAME     R3344 2
 '@S9S_MB_2U_LIB.S9S_MB_2U(SCH_1):PAGE202_I108@PURE_QUANTA.Q_RES(CHIPS)':
 'B': CDS_PINID='B';
NET_NAME
'P3V3_AUX_FPGA_VCCIO4'
 '@S9S_MB_2U_LIB.S9S_MB_2U(SCH_1):P3V3_AUX_FPGA_VCCIO4':
 C_SIGNAL='@s9s_mb_2u_lib.s9s_mb_2u(sch_1):p3v3_aux_fpga_vccio4',
 CDS_GLOBAL_NET='TRUE';
NODE_NAME     C1899 1
 '@S9S_MB_2U_LIB.S9S_MB_2U(SCH_1):PAGE202_I74@PURE_QUANTA.Q_CAP(CHIPS)':
 'A': CDS_PINID='A';
NODE_NAME     C1893 1
 '@S9S_MB_2U_LIB.S9S_MB_2U(SCH_1):PAGE202_I76@PURE_QUANTA.Q_CAP(CHIPS)':
 'A': CDS_PINID='A';
NODE_NAME     C1908 1
 '@S9S_MB_2U_LIB.S9S_MB_2U(SCH_1):PAGE202_I77@PURE_QUANTA.Q_CAP(CHIPS)':
 'A': CDS_PINID='A';
NODE_NAME     C1942 1
 '@S9S_MB_2U_LIB.S9S_MB_2U(SCH_1):PAGE202_I80@PURE_QUANTA.Q_CAP(CHIPS)':
 'A': CDS_PINID='A';
NODE_NAME     R3345 2
 '@S9S_MB_2U_LIB.S9S_MB_2U(SCH_1):PAGE202_I81@PURE_QUANTA.Q_RES(CHIPS)':
 'B': CDS_PINID='B';
NODE_NAME     C1935 1
 '@S9S_MB_2U_LIB.S9S_MB_2U(SCH_1):PAGE202_I82@PURE_QUANTA.Q_CAP(CHIPS)':
 'A': CDS_PINID='A';
NODE_NAME     U249 L8
 '@S9S_MB_2U_LIB.S9S_MB_2U(SCH_1):PAGE202_I102@PURE_QUANTA.LCMXO3LF9400C5BG484C(CHIPS)':
 'VCCIO4_1': CDS_PINID='VCCIO4_1';
NODE_NAME     U249 M8
 '@S9S_MB_2U_LIB.S9S_MB_2U(SCH_1):PAGE202_I102@PURE_QUANTA.LCMXO3LF9400C5BG484C(CHIPS)':
 'VCCIO4_2': CDS_PINID='VCCIO4_2';
NODE_NAME     U249 M3
 '@S9S_MB_2U_LIB.S9S_MB_2U(SCH_1):PAGE202_I102@PURE_QUANTA.LCMXO3LF9400C5BG484C(CHIPS)':
 'VCCIO4_3': CDS_PINID='VCCIO4_3';
NET_NAME
'P3V3_AUX_FPGA_VCCIO5'
 '@S9S_MB_2U_LIB.S9S_MB_2U(SCH_1):P3V3_AUX_FPGA_VCCIO5':
 C_SIGNAL='@s9s_mb_2u_lib.s9s_mb_2u(sch_1):p3v3_aux_fpga_vccio5',
 CDS_GLOBAL_NET='TRUE';
NODE_NAME     C1904 1
 '@S9S_MB_2U_LIB.S9S_MB_2U(SCH_1):PAGE202_I18@PURE_QUANTA.Q_CAP(CHIPS)':
 'A': CDS_PINID='A';
NODE_NAME     C1898 1
 '@S9S_MB_2U_LIB.S9S_MB_2U(SCH_1):PAGE202_I20@PURE_QUANTA.Q_CAP(CHIPS)':
 'A': CDS_PINID='A';
NODE_NAME     C1913 1
 '@S9S_MB_2U_LIB.S9S_MB_2U(SCH_1):PAGE202_I53@PURE_QUANTA.Q_CAP(CHIPS)':
 'A': CDS_PINID='A';
NODE_NAME     C1947 1
 '@S9S_MB_2U_LIB.S9S_MB_2U(SCH_1):PAGE202_I54@PURE_QUANTA.Q_CAP(CHIPS)':
 'A': CDS_PINID='A';
NODE_NAME     C1940 1
 '@S9S_MB_2U_LIB.S9S_MB_2U(SCH_1):PAGE202_I55@PURE_QUANTA.Q_CAP(CHIPS)':
 'A': CDS_PINID='A';
NODE_NAME     R3349 2
 '@S9S_MB_2U_LIB.S9S_MB_2U(SCH_1):PAGE202_I60@PURE_QUANTA.Q_RES(CHIPS)':
 'B': CDS_PINID='B';
NODE_NAME     U249 F3
 '@S9S_MB_2U_LIB.S9S_MB_2U(SCH_1):PAGE202_I102@PURE_QUANTA.LCMXO3LF9400C5BG484C(CHIPS)':
 'VCCIO5_1': CDS_PINID='VCCIO5_1';
NODE_NAME     U249 J8
 '@S9S_MB_2U_LIB.S9S_MB_2U(SCH_1):PAGE202_I102@PURE_QUANTA.LCMXO3LF9400C5BG484C(CHIPS)':
 'VCCIO5_2': CDS_PINID='VCCIO5_2';
NODE_NAME     U249 K8
 '@S9S_MB_2U_LIB.S9S_MB_2U(SCH_1):PAGE202_I102@PURE_QUANTA.LCMXO3LF9400C5BG484C(CHIPS)':
 'VCCIO5_3': CDS_PINID='VCCIO5_3';
NET_NAME
'P3V3_AUX_ILIM'
 '@S9S_MB_2U_LIB.S9S_MB_2U(SCH_1):P3V3_AUX_ILIM':
 C_SIGNAL='@s9s_mb_2u_lib.s9s_mb_2u(sch_1):p3v3_aux_ilim';
NODE_NAME     PR834 1
 '@S9S_MB_2U_LIB.S9S_MB_2U(SCH_1):PAGE245_I91@PURE_QUANTA.Q_RES(CHIPS)':
 'A': CDS_PINID='A';
NODE_NAME     PU9 1
 '@S9S_MB_2U_LIB.S9S_MB_2U(SCH_1):PAGE245_I95@PURE_QUANTA.IR3889MTRPBF(CHIPS)':
 'ILIM': CDS_PINID='ILIM';
NET_NAME
'P3V3_AUX_MODE'
 '@S9S_MB_2U_LIB.S9S_MB_2U(SCH_1):P3V3_AUX_MODE':
 C_SIGNAL='@s9s_mb_2u_lib.s9s_mb_2u(sch_1):p3v3_aux_mode';
NODE_NAME     PR832 1
 '@S9S_MB_2U_LIB.S9S_MB_2U(SCH_1):PAGE245_I84@PURE_QUANTA.Q_RES(CHIPS)':
 'A': CDS_PINID='A';
NODE_NAME     PU9 36
 '@S9S_MB_2U_LIB.S9S_MB_2U(SCH_1):PAGE245_I95@PURE_QUANTA.IR3889MTRPBF(CHIPS)':
 'TON||MODE': CDS_PINID='\ton||mode\';
NET_NAME
'P3V3_AUX_SS'
 '@S9S_MB_2U_LIB.S9S_MB_2U(SCH_1):P3V3_AUX_SS':
 C_SIGNAL='@s9s_mb_2u_lib.s9s_mb_2u(sch_1):p3v3_aux_ss';
NODE_NAME     PR833 1
 '@S9S_MB_2U_LIB.S9S_MB_2U(SCH_1):PAGE245_I89@PURE_QUANTA.Q_RES(CHIPS)':
 'A': CDS_PINID='A';
NODE_NAME     PU9 29
 '@S9S_MB_2U_LIB.S9S_MB_2U(SCH_1):PAGE245_I95@PURE_QUANTA.IR3889MTRPBF(CHIPS)':
 'SS||LATCH': CDS_PINID='\ss||latch\';
NET_NAME
'P3V3_AUX_USB_BUF'
 '@S9S_MB_2U_LIB.S9S_MB_2U(SCH_1):P3V3_AUX_USB_BUF':
 C_SIGNAL='@s9s_mb_2u_lib.s9s_mb_2u(sch_1):p3v3_aux_usb_buf';
NODE_NAME     L18 2
 '@S9S_MB_2U_LIB.S9S_MB_2U(SCH_1):PAGE162_I35@PURE_QUANTA.Q_INDUCTOR(CHIPS)':
 '2': CDS_PINID='\2\';
NODE_NAME     C2284 1
 '@S9S_MB_2U_LIB.S9S_MB_2U(SCH_1):PAGE162_I37@PURE_QUANTA.Q_CAP(CHIPS)':
 'A': CDS_PINID='A';
NODE_NAME     U309 5
 '@S9S_MB_2U_LIB.S9S_MB_2U(SCH_1):PAGE162_I43@PURE_QUANTA.PI3EQX1002EZREX(CHIPS)':
 'VDD_1': CDS_PINID='VDD_1';
NODE_NAME     U309 17
 '@S9S_MB_2U_LIB.S9S_MB_2U(SCH_1):PAGE162_I43@PURE_QUANTA.PI3EQX1002EZREX(CHIPS)':
 'VDD_2': CDS_PINID='VDD_2';
NODE_NAME     C2285 1
 '@S9S_MB_2U_LIB.S9S_MB_2U(SCH_1):PAGE162_I44@PURE_QUANTA.Q_CAP(CHIPS)':
 'A': CDS_PINID='A';
NODE_NAME     C2286 1
 '@S9S_MB_2U_LIB.S9S_MB_2U(SCH_1):PAGE162_I45@PURE_QUANTA.Q_CAP(CHIPS)':
 'A': CDS_PINID='A';
NET_NAME
'P3V3_AUX_USB_HUB'
 '@S9S_MB_2U_LIB.S9S_MB_2U(SCH_1):P3V3_AUX_USB_HUB':
 C_SIGNAL='@s9s_mb_2u_lib.s9s_mb_2u(sch_1):p3v3_aux_usb_hub';
NODE_NAME     U268 5
 '@S9S_MB_2U_LIB.S9S_MB_2U(SCH_1):PAGE155_I100@PURE_QUANTA.GL852GOHY60(CHIPS)':
 'AVDD'<0>: CDS_PINID='AVDD(0)';
NODE_NAME     U268 9
 '@S9S_MB_2U_LIB.S9S_MB_2U(SCH_1):PAGE155_I100@PURE_QUANTA.GL852GOHY60(CHIPS)':
 'AVDD'<1>: CDS_PINID='AVDD(1)';
NODE_NAME     U268 14
 '@S9S_MB_2U_LIB.S9S_MB_2U(SCH_1):PAGE155_I100@PURE_QUANTA.GL852GOHY60(CHIPS)':
 'AVDD'<2>: CDS_PINID='AVDD(2)';
NODE_NAME     U268 27
 '@S9S_MB_2U_LIB.S9S_MB_2U(SCH_1):PAGE155_I100@PURE_QUANTA.GL852GOHY60(CHIPS)':
 'V5': CDS_PINID='V5';
NODE_NAME     U268 28
 '@S9S_MB_2U_LIB.S9S_MB_2U(SCH_1):PAGE155_I100@PURE_QUANTA.GL852GOHY60(CHIPS)':
 'V33': CDS_PINID='V33';
NODE_NAME     C2034 1
 '@S9S_MB_2U_LIB.S9S_MB_2U(SCH_1):PAGE155_I142@PURE_QUANTA.Q_CAP(CHIPS)':
 'A': CDS_PINID='A';
NODE_NAME     C2033 1
 '@S9S_MB_2U_LIB.S9S_MB_2U(SCH_1):PAGE155_I143@PURE_QUANTA.Q_CAP(CHIPS)':
 'A': CDS_PINID='A';
NODE_NAME     C2032 1
 '@S9S_MB_2U_LIB.S9S_MB_2U(SCH_1):PAGE155_I145@PURE_QUANTA.Q_CAP(CHIPS)':
 'A': CDS_PINID='A';
NODE_NAME     C2035 1
 '@S9S_MB_2U_LIB.S9S_MB_2U(SCH_1):PAGE155_I147@PURE_QUANTA.Q_CAP(CHIPS)':
 'A': CDS_PINID='A';
NODE_NAME     C2031 1
 '@S9S_MB_2U_LIB.S9S_MB_2U(SCH_1):PAGE155_I148@PURE_QUANTA.Q_CAP(CHIPS)':
 'A': CDS_PINID='A';
NODE_NAME     R3655 2
 '@S9S_MB_2U_LIB.S9S_MB_2U(SCH_1):PAGE155_I161@PURE_QUANTA.Q_RES(CHIPS)':
 'B': CDS_PINID='B';
NODE_NAME     C2040 1
 '@S9S_MB_2U_LIB.S9S_MB_2U(SCH_1):PAGE155_I162@PURE_QUANTA.Q_CAP(CHIPS)':
 'A': CDS_PINID='A';
NODE_NAME     C2039 1
 '@S9S_MB_2U_LIB.S9S_MB_2U(SCH_1):PAGE155_I163@PURE_QUANTA.Q_CAP(CHIPS)':
 'A': CDS_PINID='A';
NODE_NAME     C2038 1
 '@S9S_MB_2U_LIB.S9S_MB_2U(SCH_1):PAGE155_I164@PURE_QUANTA.Q_CAP(CHIPS)':
 'A': CDS_PINID='A';
NODE_NAME     R3662 1
 '@S9S_MB_2U_LIB.S9S_MB_2U(SCH_1):PAGE155_I167@PURE_QUANTA.Q_RES(CHIPS)':
 'A': CDS_PINID='A';
NET_NAME
'P3V3_AUX_USB_HUB_2'
 '@S9S_MB_2U_LIB.S9S_MB_2U(SCH_1):P3V3_AUX_USB_HUB_2':
 C_SIGNAL='@s9s_mb_2u_lib.s9s_mb_2u(sch_1):p3v3_aux_usb_hub_2';
NODE_NAME     U313 5
 '@S9S_MB_2U_LIB.S9S_MB_2U(SCH_1):PAGE194_I40@PURE_QUANTA.GL852GOHY60(CHIPS)':
 'AVDD'<0>: CDS_PINID='AVDD(0)';
NODE_NAME     U313 9
 '@S9S_MB_2U_LIB.S9S_MB_2U(SCH_1):PAGE194_I40@PURE_QUANTA.GL852GOHY60(CHIPS)':
 'AVDD'<1>: CDS_PINID='AVDD(1)';
NODE_NAME     U313 14
 '@S9S_MB_2U_LIB.S9S_MB_2U(SCH_1):PAGE194_I40@PURE_QUANTA.GL852GOHY60(CHIPS)':
 'AVDD'<2>: CDS_PINID='AVDD(2)';
NODE_NAME     U313 27
 '@S9S_MB_2U_LIB.S9S_MB_2U(SCH_1):PAGE194_I40@PURE_QUANTA.GL852GOHY60(CHIPS)':
 'V5': CDS_PINID='V5';
NODE_NAME     U313 28
 '@S9S_MB_2U_LIB.S9S_MB_2U(SCH_1):PAGE194_I40@PURE_QUANTA.GL852GOHY60(CHIPS)':
 'V33': CDS_PINID='V33';
NODE_NAME     R4450 2
 '@S9S_MB_2U_LIB.S9S_MB_2U(SCH_1):PAGE194_I41@PURE_QUANTA.Q_RES(CHIPS)':
 'B': CDS_PINID='B';
NODE_NAME     C2313 1
 '@S9S_MB_2U_LIB.S9S_MB_2U(SCH_1):PAGE194_I43@PURE_QUANTA.Q_CAP(CHIPS)':
 'A': CDS_PINID='A';
NODE_NAME     C2314 1
 '@S9S_MB_2U_LIB.S9S_MB_2U(SCH_1):PAGE194_I45@PURE_QUANTA.Q_CAP(CHIPS)':
 'A': CDS_PINID='A';
NODE_NAME     C2315 1
 '@S9S_MB_2U_LIB.S9S_MB_2U(SCH_1):PAGE194_I46@PURE_QUANTA.Q_CAP(CHIPS)':
 'A': CDS_PINID='A';
NODE_NAME     C2316 1
 '@S9S_MB_2U_LIB.S9S_MB_2U(SCH_1):PAGE194_I47@PURE_QUANTA.Q_CAP(CHIPS)':
 'A': CDS_PINID='A';
NODE_NAME     C2318 1
 '@S9S_MB_2U_LIB.S9S_MB_2U(SCH_1):PAGE194_I49@PURE_QUANTA.Q_CAP(CHIPS)':
 'A': CDS_PINID='A';
NODE_NAME     R4462 1
 '@S9S_MB_2U_LIB.S9S_MB_2U(SCH_1):PAGE194_I50@PURE_QUANTA.Q_RES(CHIPS)':
 'A': CDS_PINID='A';
NODE_NAME     C2319 1
 '@S9S_MB_2U_LIB.S9S_MB_2U(SCH_1):PAGE194_I51@PURE_QUANTA.Q_CAP(CHIPS)':
 'A': CDS_PINID='A';
NODE_NAME     C2320 1
 '@S9S_MB_2U_LIB.S9S_MB_2U(SCH_1):PAGE194_I52@PURE_QUANTA.Q_CAP(CHIPS)':
 'A': CDS_PINID='A';
NODE_NAME     C2322 1
 '@S9S_MB_2U_LIB.S9S_MB_2U(SCH_1):PAGE194_I53@PURE_QUANTA.Q_CAP(CHIPS)':
 'A': CDS_PINID='A';
NET_NAME
'P3V3_AUX_VCC'
 '@S9S_MB_2U_LIB.S9S_MB_2U(SCH_1):P3V3_AUX_VCC':
 C_SIGNAL='@s9s_mb_2u_lib.s9s_mb_2u(sch_1):p3v3_aux_vcc';
NODE_NAME     PC591 1
 '@S9S_MB_2U_LIB.S9S_MB_2U(SCH_1):PAGE245_I93@PURE_QUANTA.Q_CAP(CHIPS)':
 'A': CDS_PINID='A';
NODE_NAME     PR389 2
 '@S9S_MB_2U_LIB.S9S_MB_2U(SCH_1):PAGE245_I94@PURE_QUANTA.Q_RES(CHIPS)':
 'B': CDS_PINID='B';
NODE_NAME     PU9 4
 '@S9S_MB_2U_LIB.S9S_MB_2U(SCH_1):PAGE245_I95@PURE_QUANTA.IR3889MTRPBF(CHIPS)':
 'VCC||LDO': CDS_PINID='\vcc||ldo\';
NET_NAME
'P3V3_AUX_VDRV'
 '@S9S_MB_2U_LIB.S9S_MB_2U(SCH_1):P3V3_AUX_VDRV':
 C_SIGNAL='@s9s_mb_2u_lib.s9s_mb_2u(sch_1):p3v3_aux_vdrv';
NODE_NAME     PC581 1
 '@S9S_MB_2U_LIB.S9S_MB_2U(SCH_1):PAGE245_I86@PURE_QUANTA.Q_CAP(CHIPS)':
 'A': CDS_PINID='A';
NODE_NAME     PR389 1
 '@S9S_MB_2U_LIB.S9S_MB_2U(SCH_1):PAGE245_I94@PURE_QUANTA.Q_RES(CHIPS)':
 'A': CDS_PINID='A';
NODE_NAME     PU9 5
 '@S9S_MB_2U_LIB.S9S_MB_2U(SCH_1):PAGE245_I95@PURE_QUANTA.IR3889MTRPBF(CHIPS)':
 'VDRV': CDS_PINID='VDRV';
NET_NAME
'P3V3_AUX_VOS'
 '@S9S_MB_2U_LIB.S9S_MB_2U(SCH_1):P3V3_AUX_VOS':
 C_SIGNAL='@s9s_mb_2u_lib.s9s_mb_2u(sch_1):p3v3_aux_vos';
NODE_NAME     PU9 28
 '@S9S_MB_2U_LIB.S9S_MB_2U(SCH_1):PAGE245_I95@PURE_QUANTA.IR3889MTRPBF(CHIPS)':
 'NC1': CDS_PINID='NC1';
NODE_NAME     PR836 1
 '@S9S_MB_2U_LIB.S9S_MB_2U(SCH_1):PAGE245_I121@PURE_QUANTA.Q_RES(CHIPS)':
 'A': CDS_PINID='A';
NET_NAME
'P3V3_DB2000_FB_VDD'
 '@S9S_MB_2U_LIB.S9S_MB_2U(SCH_1):P3V3_DB2000_FB_VDD':
 C_SIGNAL='@s9s_mb_2u_lib.s9s_mb_2u(sch_1):p3v3_db2000_fb_vdd';
NODE_NAME     R572 1
 '@S9S_MB_2U_LIB.S9S_MB_2U(SCH_1):PAGE195_I162@PURE_QUANTA.Q_RES(CHIPS)':
 'A': CDS_PINID='A';
NODE_NAME     R571 1
 '@S9S_MB_2U_LIB.S9S_MB_2U(SCH_1):PAGE195_I163@PURE_QUANTA.Q_RES(CHIPS)':
 'A': CDS_PINID='A';
NODE_NAME     L4 2
 '@S9S_MB_2U_LIB.S9S_MB_2U(SCH_1):PAGE195_I177@PURE_QUANTA.Q_INDUCTOR(CHIPS)':
 '2': CDS_PINID='\2\';
NET_NAME
'P3V3_DB2000_VDD'
 '@S9S_MB_2U_LIB.S9S_MB_2U(SCH_1):P3V3_DB2000_VDD':
 C_SIGNAL='@s9s_mb_2u_lib.s9s_mb_2u(sch_1):p3v3_db2000_vdd',
 CDS_GLOBAL_NET='TRUE';
NODE_NAME     U38 B2
 '@S9S_MB_2U_LIB.S9S_MB_2U(SCH_1):PAGE195_I119@PURE_QUANTA.9QXL2001BNHGI8(CHIPS)':
 'VDDO3.3_B2': CDS_PINID='\vddo3.3_b2\';
NODE_NAME     U38 B11
 '@S9S_MB_2U_LIB.S9S_MB_2U(SCH_1):PAGE195_I119@PURE_QUANTA.9QXL2001BNHGI8(CHIPS)':
 'VDDO3.3_B11': CDS_PINID='\vddo3.3_b11\';
NODE_NAME     U38 L2
 '@S9S_MB_2U_LIB.S9S_MB_2U(SCH_1):PAGE195_I119@PURE_QUANTA.9QXL2001BNHGI8(CHIPS)':
 'VDDO3.3_L2': CDS_PINID='\vddo3.3_l2\';
NODE_NAME     U38 L11
 '@S9S_MB_2U_LIB.S9S_MB_2U(SCH_1):PAGE195_I119@PURE_QUANTA.9QXL2001BNHGI8(CHIPS)':
 'VDDO3.3_L11': CDS_PINID='\vddo3.3_l11\';
NODE_NAME     L3 2
 '@S9S_MB_2U_LIB.S9S_MB_2U(SCH_1):PAGE195_I170@PURE_QUANTA.Q_INDUCTOR(CHIPS)':
 '2': CDS_PINID='\2\';
NODE_NAME     C204 1
 '@S9S_MB_2U_LIB.S9S_MB_2U(SCH_1):PAGE195_I171@PURE_QUANTA.Q_CAP(CHIPS)':
 'A': CDS_PINID='A';
NODE_NAME     C205 1
 '@S9S_MB_2U_LIB.S9S_MB_2U(SCH_1):PAGE195_I172@PURE_QUANTA.Q_CAP(CHIPS)':
 'A': CDS_PINID='A';
NODE_NAME     C206 1
 '@S9S_MB_2U_LIB.S9S_MB_2U(SCH_1):PAGE195_I173@PURE_QUANTA.Q_CAP(CHIPS)':
 'A': CDS_PINID='A';
NODE_NAME     C207 1
 '@S9S_MB_2U_LIB.S9S_MB_2U(SCH_1):PAGE195_I174@PURE_QUANTA.Q_CAP(CHIPS)':
 'A': CDS_PINID='A';
NODE_NAME     C1409 1
 '@S9S_MB_2U_LIB.S9S_MB_2U(SCH_1):PAGE195_I419@PURE_QUANTA.Q_CAP(CHIPS)':
 'A': CDS_PINID='A';
NET_NAME
'P3V3_DB2000_VDDA'
 '@S9S_MB_2U_LIB.S9S_MB_2U(SCH_1):P3V3_DB2000_VDDA':
 C_SIGNAL='@s9s_mb_2u_lib.s9s_mb_2u(sch_1):p3v3_db2000_vdda',
 CDS_GLOBAL_NET='TRUE';
NODE_NAME     U38 B6
 '@S9S_MB_2U_LIB.S9S_MB_2U(SCH_1):PAGE195_I119@PURE_QUANTA.9QXL2001BNHGI8(CHIPS)':
 'VDDA3.3': CDS_PINID='\vdda3.3\';
NODE_NAME     R572 2
 '@S9S_MB_2U_LIB.S9S_MB_2U(SCH_1):PAGE195_I162@PURE_QUANTA.Q_RES(CHIPS)':
 'B': CDS_PINID='B';
NODE_NAME     C209 1
 '@S9S_MB_2U_LIB.S9S_MB_2U(SCH_1):PAGE195_I164@PURE_QUANTA.Q_CAP(CHIPS)':
 'A': CDS_PINID='A';
NODE_NAME     C211 1
 '@S9S_MB_2U_LIB.S9S_MB_2U(SCH_1):PAGE195_I165@PURE_QUANTA.Q_CAP(CHIPS)':
 'A': CDS_PINID='A';
NET_NAME
'P3V3_DB2000_VDDR'
 '@S9S_MB_2U_LIB.S9S_MB_2U(SCH_1):P3V3_DB2000_VDDR':
 C_SIGNAL='@s9s_mb_2u_lib.s9s_mb_2u(sch_1):p3v3_db2000_vddr',
 CDS_GLOBAL_NET='TRUE';
NODE_NAME     U38 H2
 '@S9S_MB_2U_LIB.S9S_MB_2U(SCH_1):PAGE195_I119@PURE_QUANTA.9QXL2001BNHGI8(CHIPS)':
 'VDDR3.3': CDS_PINID='\vddr3.3\';
NODE_NAME     R571 2
 '@S9S_MB_2U_LIB.S9S_MB_2U(SCH_1):PAGE195_I163@PURE_QUANTA.Q_RES(CHIPS)':
 'B': CDS_PINID='B';
NODE_NAME     C208 1
 '@S9S_MB_2U_LIB.S9S_MB_2U(SCH_1):PAGE195_I167@PURE_QUANTA.Q_CAP(CHIPS)':
 'A': CDS_PINID='A';
NODE_NAME     C210 1
 '@S9S_MB_2U_LIB.S9S_MB_2U(SCH_1):PAGE195_I168@PURE_QUANTA.Q_CAP(CHIPS)':
 'A': CDS_PINID='A';
NET_NAME
'P3V3_E1S_0'
 '@S9S_MB_2U_LIB.S9S_MB_2U(SCH_1):P3V3_E1S_0':
 C_SIGNAL='@s9s_mb_2u_lib.s9s_mb_2u(sch_1):p3v3_e1s_0',
 CDS_GLOBAL_NET='TRUE';
NODE_NAME     R3532 1
 '@S9S_MB_2U_LIB.S9S_MB_2U(SCH_1):PAGE183_I78@PURE_QUANTA.Q_RES(CHIPS)':
 'A': CDS_PINID='A';
NODE_NAME     R3530 1
 '@S9S_MB_2U_LIB.S9S_MB_2U(SCH_1):PAGE183_I80@PURE_QUANTA.Q_RES(CHIPS)':
 'A': CDS_PINID='A';
NODE_NAME     C1998 1
 '@S9S_MB_2U_LIB.S9S_MB_2U(SCH_1):PAGE183_I82@PURE_QUANTA.Q_CAP(CHIPS)':
 'A': CDS_PINID='A';
NODE_NAME     R3760 1
 '@S9S_MB_2U_LIB.S9S_MB_2U(SCH_1):PAGE295_I134@PURE_QUANTA.Q_RES(CHIPS)':
 'A': CDS_PINID='A';
NODE_NAME     U279 1
 '@S9S_MB_2U_LIB.S9S_MB_2U(SCH_1):PAGE183_I93@PURE_QUANTA.PCA9617ADP(CHIPS)':
 'VCCA': CDS_PINID='VCCA';
NODE_NAME     C1283 1
 '@S9S_MB_2U_LIB.S9S_MB_2U(SCH_1):PAGE297_I245@PURE_QUANTA.Q_CAP(CHIPS)':
 'A': CDS_PINID='A';
NODE_NAME     C1282 1
 '@S9S_MB_2U_LIB.S9S_MB_2U(SCH_1):PAGE297_I247@PURE_QUANTA.Q_CAP(CHIPS)':
 'A': CDS_PINID='A';
NODE_NAME     R2317 1
 '@S9S_MB_2U_LIB.S9S_MB_2U(SCH_1):PAGE297_I264@PURE_QUANTA.Q_RES(CHIPS)':
 'A': CDS_PINID='A';
NODE_NAME     R1673 1
 '@S9S_MB_2U_LIB.S9S_MB_2U(SCH_1):PAGE297_I312@PURE_QUANTA.Q_RES(CHIPS)':
 'A': CDS_PINID='A';
NODE_NAME     R2287 1
 '@S9S_MB_2U_LIB.S9S_MB_2U(SCH_1):PAGE297_I313@PURE_QUANTA.Q_RES(CHIPS)':
 'A': CDS_PINID='A';
NODE_NAME     J90 B11
 '@S9S_MB_2U_LIB.S9S_MB_2U(SCH_1):PAGE297_I318@PURE_QUANTA.SCONN56_123276793(CHIPS)':
 'P3V3_AUX': CDS_PINID='P3V3_AUX';
NODE_NAME     R3767 1
 '@S9S_MB_2U_LIB.S9S_MB_2U(SCH_1):PAGE295_I153@PURE_QUANTA.Q_RES(CHIPS)':
 'A': CDS_PINID='A';
NODE_NAME     C2378 1
 '@S9S_MB_2U_LIB.S9S_MB_2U(SCH_1):PAGE297_I327@PURE_QUANTA.Q_CAP(CHIPS)':
 'A': CDS_PINID='A';
NODE_NAME     U336 3
 '@S9S_MB_2U_LIB.S9S_MB_2U(SCH_1):PAGE297_I329@PURE_QUANTA.APX80929SAG7(CHIPS)':
 'VCC': CDS_PINID='VCC';
NET_NAME
'P3V3_E1S_0_EN_G'
 '@S9S_MB_2U_LIB.S9S_MB_2U(SCH_1):P3V3_E1S_0_EN_G':
 C_SIGNAL='@s9s_mb_2u_lib.s9s_mb_2u(sch_1):p3v3_e1s_0_en_g';
NODE_NAME     Q126 5
 '@S9S_MB_2U_LIB.S9S_MB_2U(SCH_1):PAGE324_I4@PURE_QUANTA.MOSFET_NCH_DUAL(CHIPS)':
 'G2': CDS_PINID='G2';
NODE_NAME     R4072 2
 '@S9S_MB_2U_LIB.S9S_MB_2U(SCH_1):PAGE324_I6@PURE_QUANTA.Q_RES(CHIPS)':
 'B': CDS_PINID='B';
NODE_NAME     Q126 6
 '@S9S_MB_2U_LIB.S9S_MB_2U(SCH_1):PAGE324_I3@PURE_QUANTA.MOSFET_NCH_DUAL(CHIPS)':
 'D1': CDS_PINID='D1';
NET_NAME
'P3V3_E1S_0_R'
 '@S9S_MB_2U_LIB.S9S_MB_2U(SCH_1):P3V3_E1S_0_R':
 C_SIGNAL='@s9s_mb_2u_lib.s9s_mb_2u(sch_1):p3v3_e1s_0_r',
 CDS_GLOBAL_NET='TRUE';
NODE_NAME     U276 11
 '@S9S_MB_2U_LIB.S9S_MB_2U(SCH_1):PAGE295_I129@PURE_QUANTA.INA230AIRGTR(CHIPS)':
 'BUS': CDS_PINID='\bus\';
NODE_NAME     R3758 1
 '@S9S_MB_2U_LIB.S9S_MB_2U(SCH_1):PAGE295_I132@PURE_QUANTA.Q_RES(CHIPS)':
 'A': CDS_PINID='A';
NODE_NAME     C2069 1
 '@S9S_MB_2U_LIB.S9S_MB_2U(SCH_1):PAGE295_I142@PURE_QUANTA.Q_CAP(CHIPS)':
 'A': CDS_PINID='A';
NODE_NAME     PR4527 1
 '@S9S_MB_2U_LIB.S9S_MB_2U(SCH_1):PAGE324_I43@PURE_QUANTA.Q_RES(CHIPS)':
 'A': CDS_PINID='A';
NODE_NAME     PD113 C
 '@S9S_MB_2U_LIB.S9S_MB_2U(SCH_1):PAGE324_I46@PURE_QUANTA.SCHOTTKY_AC(CHIPS)':
 'C': CDS_PINID='C';
NODE_NAME     PC2204 1
 '@S9S_MB_2U_LIB.S9S_MB_2U(SCH_1):PAGE323_I34@PURE_QUANTA.Q_CAP(CHIPS)':
 'A': CDS_PINID='A';
NODE_NAME     PU293 6_7
 '@S9S_MB_2U_LIB.S9S_MB_2U(SCH_1):PAGE323_I31@PURE_QUANTA.MP5016GQHLZ(CHIPS)':
 'SOURCE': CDS_PINID='SOURCE';
NODE_NAME     R3767 2
 '@S9S_MB_2U_LIB.S9S_MB_2U(SCH_1):PAGE295_I153@PURE_QUANTA.Q_RES(CHIPS)':
 'B': CDS_PINID='B';
NODE_NAME     PU295 A4
 '@S9S_MB_2U_LIB.S9S_MB_2U(SCH_1):PAGE324_I35@PURE_QUANTA.MAX15090BEWIT(CHIPS)':
 'OUT_A4': CDS_PINID='OUT_A4';
NODE_NAME     PU295 B4
 '@S9S_MB_2U_LIB.S9S_MB_2U(SCH_1):PAGE324_I35@PURE_QUANTA.MAX15090BEWIT(CHIPS)':
 'OUT_B4': CDS_PINID='OUT_B4';
NODE_NAME     PU295 B6
 '@S9S_MB_2U_LIB.S9S_MB_2U(SCH_1):PAGE324_I35@PURE_QUANTA.MAX15090BEWIT(CHIPS)':
 'OUT_B6': CDS_PINID='OUT_B6';
NODE_NAME     PU295 C4
 '@S9S_MB_2U_LIB.S9S_MB_2U(SCH_1):PAGE324_I35@PURE_QUANTA.MAX15090BEWIT(CHIPS)':
 'OUT_C4': CDS_PINID='OUT_C4';
NODE_NAME     PU295 C6
 '@S9S_MB_2U_LIB.S9S_MB_2U(SCH_1):PAGE324_I35@PURE_QUANTA.MAX15090BEWIT(CHIPS)':
 'OUT_C6': CDS_PINID='OUT_C6';
NODE_NAME     PU295 D4
 '@S9S_MB_2U_LIB.S9S_MB_2U(SCH_1):PAGE324_I35@PURE_QUANTA.MAX15090BEWIT(CHIPS)':
 'OUT_D4': CDS_PINID='OUT_D4';
NODE_NAME     PU295 D6
 '@S9S_MB_2U_LIB.S9S_MB_2U(SCH_1):PAGE324_I35@PURE_QUANTA.MAX15090BEWIT(CHIPS)':
 'OUT_D6': CDS_PINID='OUT_D6';
NODE_NAME     PC2213 1
 '@S9S_MB_2U_LIB.S9S_MB_2U(SCH_1):PAGE324_I42@PURE_QUANTA.Q_CAP(CHIPS)':
 'A': CDS_PINID='A';
NODE_NAME     PC2218 1
 '@S9S_MB_2U_LIB.S9S_MB_2U(SCH_1):PAGE324_I52@PURE_QUANTA.Q_CAP(CHIPS)':
 'A': CDS_PINID='A';
NODE_NAME     PC2220 1
 '@S9S_MB_2U_LIB.S9S_MB_2U(SCH_1):PAGE324_I53@PURE_QUANTA.Q_CAP(CHIPS)':
 'A': CDS_PINID='A';
NET_NAME
'P3V3_E1S_CB_0'
 '@S9S_MB_2U_LIB.S9S_MB_2U(SCH_1):P3V3_E1S_CB_0':
 C_SIGNAL='@s9s_mb_2u_lib.s9s_mb_2u(sch_1):p3v3_e1s_cb_0';
NODE_NAME     PR3969 1
 '@S9S_MB_2U_LIB.S9S_MB_2U(SCH_1):PAGE324_I34@PURE_QUANTA.Q_RES(CHIPS)':
 'A': CDS_PINID='A';
NODE_NAME     PU295 B1
 '@S9S_MB_2U_LIB.S9S_MB_2U(SCH_1):PAGE324_I35@PURE_QUANTA.MAX15090BEWIT(CHIPS)':
 'CB': CDS_PINID='CB';
NET_NAME
'P3V3_E1S_DVDT_0'
 '@S9S_MB_2U_LIB.S9S_MB_2U(SCH_1):P3V3_E1S_DVDT_0':
 C_SIGNAL='@s9s_mb_2u_lib.s9s_mb_2u(sch_1):p3v3_e1s_dvdt_0';
NODE_NAME     PC2201 1
 '@S9S_MB_2U_LIB.S9S_MB_2U(SCH_1):PAGE323_I30@PURE_QUANTA.Q_CAP(CHIPS)':
 'A': CDS_PINID='A';
NODE_NAME     PU293 10
 '@S9S_MB_2U_LIB.S9S_MB_2U(SCH_1):PAGE323_I31@PURE_QUANTA.MP5016GQHLZ(CHIPS)':
 'DV_DT': CDS_PINID='DV_DT';
NET_NAME
'P3V3_E1S_EN_0_R2'
 '@S9S_MB_2U_LIB.S9S_MB_2U(SCH_1):P3V3_E1S_EN_0_R2':
 C_SIGNAL='@s9s_mb_2u_lib.s9s_mb_2u(sch_1):p3v3_e1s_en_0_r2';
NODE_NAME     R3946 2
 '@S9S_MB_2U_LIB.S9S_MB_2U(SCH_1):PAGE323_I5@PURE_QUANTA.Q_RES(CHIPS)':
 'B': CDS_PINID='B';
NODE_NAME     PU293 9
 '@S9S_MB_2U_LIB.S9S_MB_2U(SCH_1):PAGE323_I31@PURE_QUANTA.MP5016GQHLZ(CHIPS)':
 'EN': CDS_PINID='EN';
NET_NAME
'P3V3_E1S_EN_1_R'
 '@S9S_MB_2U_LIB.S9S_MB_2U(SCH_1):P3V3_E1S_EN_1_R':
 C_SIGNAL='@s9s_mb_2u_lib.s9s_mb_2u(sch_1):p3v3_e1s_en_1_r';
NODE_NAME     R4063 2
 '@S9S_MB_2U_LIB.S9S_MB_2U(SCH_1):PAGE324_I1@PURE_QUANTA.Q_RES(CHIPS)':
 'B': CDS_PINID='B';
NODE_NAME     Q126 2
 '@S9S_MB_2U_LIB.S9S_MB_2U(SCH_1):PAGE324_I3@PURE_QUANTA.MOSFET_NCH_DUAL(CHIPS)':
 'G1': CDS_PINID='G1';
NET_NAME
'P3V3_E1S_FAULT_0'
 '@S9S_MB_2U_LIB.S9S_MB_2U(SCH_1):P3V3_E1S_FAULT_0':
 C_SIGNAL='@s9s_mb_2u_lib.s9s_mb_2u(sch_1):p3v3_e1s_fault_0';
NODE_NAME     R3977 2
 '@S9S_MB_2U_LIB.S9S_MB_2U(SCH_1):PAGE324_I48@PURE_QUANTA.Q_RES(CHIPS)':
 'B': CDS_PINID='B';
NODE_NAME     PU295 C7
 '@S9S_MB_2U_LIB.S9S_MB_2U(SCH_1):PAGE324_I35@PURE_QUANTA.MAX15090BEWIT(CHIPS)':
 'FAULT#': CDS_PINID='\fault#\';
NET_NAME
'P3V3_E1S_GATE_0'
 '@S9S_MB_2U_LIB.S9S_MB_2U(SCH_1):P3V3_E1S_GATE_0':
 C_SIGNAL='@s9s_mb_2u_lib.s9s_mb_2u(sch_1):p3v3_e1s_gate_0';
NODE_NAME     PR4527 2
 '@S9S_MB_2U_LIB.S9S_MB_2U(SCH_1):PAGE324_I43@PURE_QUANTA.Q_RES(CHIPS)':
 'B': CDS_PINID='B';
NODE_NAME     PC2216 1
 '@S9S_MB_2U_LIB.S9S_MB_2U(SCH_1):PAGE324_I45@PURE_QUANTA.Q_CAP(CHIPS)':
 'A': CDS_PINID='A';
NODE_NAME     PU295 A6
 '@S9S_MB_2U_LIB.S9S_MB_2U(SCH_1):PAGE324_I35@PURE_QUANTA.MAX15090BEWIT(CHIPS)':
 'GATE': CDS_PINID='GATE';
NODE_NAME     PC2213 2
 '@S9S_MB_2U_LIB.S9S_MB_2U(SCH_1):PAGE324_I42@PURE_QUANTA.Q_CAP(CHIPS)':
 'B': CDS_PINID='B';
NET_NAME
'P3V3_E1S_GATE_0_PU293'
 '@S9S_MB_2U_LIB.S9S_MB_2U(SCH_1):P3V3_E1S_GATE_0_PU293':
 C_SIGNAL='@s9s_mb_2u_lib.s9s_mb_2u(sch_1):p3v3_e1s_gate_0_pu293';
NODE_NAME     PC2203 1
 '@S9S_MB_2U_LIB.S9S_MB_2U(SCH_1):PAGE323_I32@PURE_QUANTA.Q_CAP(CHIPS)':
 'A': CDS_PINID='A';
NODE_NAME     PU293 8
 '@S9S_MB_2U_LIB.S9S_MB_2U(SCH_1):PAGE323_I31@PURE_QUANTA.MP5016GQHLZ(CHIPS)':
 'GATE': CDS_PINID='GATE';
NET_NAME
'P3V3_E1S_ILIMIT_0'
 '@S9S_MB_2U_LIB.S9S_MB_2U(SCH_1):P3V3_E1S_ILIMIT_0':
 C_SIGNAL='@s9s_mb_2u_lib.s9s_mb_2u(sch_1):p3v3_e1s_ilimit_0';
NODE_NAME     PU293 4
 '@S9S_MB_2U_LIB.S9S_MB_2U(SCH_1):PAGE323_I31@PURE_QUANTA.MP5016GQHLZ(CHIPS)':
 'ILIMIT': CDS_PINID='ILIMIT';
NODE_NAME     PR3947 2
 '@S9S_MB_2U_LIB.S9S_MB_2U(SCH_1):PAGE323_I6@PURE_QUANTA.Q_RES(CHIPS)':
 'B': CDS_PINID='B';
NET_NAME
'P3V3_E1S_MODE_0'
 '@S9S_MB_2U_LIB.S9S_MB_2U(SCH_1):P3V3_E1S_MODE_0':
 C_SIGNAL='@s9s_mb_2u_lib.s9s_mb_2u(sch_1):p3v3_e1s_mode_0';
NODE_NAME     PC2197 1
 '@S9S_MB_2U_LIB.S9S_MB_2U(SCH_1):PAGE323_I3@PURE_QUANTA.Q_CAP(CHIPS)':
 'A': CDS_PINID='A';
NODE_NAME     PR3945 1
 '@S9S_MB_2U_LIB.S9S_MB_2U(SCH_1):PAGE323_I4@PURE_QUANTA.Q_RES(CHIPS)':
 'A': CDS_PINID='A';
NODE_NAME     PU293 5
 '@S9S_MB_2U_LIB.S9S_MB_2U(SCH_1):PAGE323_I31@PURE_QUANTA.MP5016GQHLZ(CHIPS)':
 'MODE': CDS_PINID='MODE';
NET_NAME
'P3V3_E1S_OV_0'
 '@S9S_MB_2U_LIB.S9S_MB_2U(SCH_1):P3V3_E1S_OV_0':
 C_SIGNAL='@s9s_mb_2u_lib.s9s_mb_2u(sch_1):p3v3_e1s_ov_0';
NODE_NAME     PR3965 1
 '@S9S_MB_2U_LIB.S9S_MB_2U(SCH_1):PAGE324_I13@PURE_QUANTA.Q_RES(CHIPS)':
 'A': CDS_PINID='A';
NODE_NAME     PR3964 2
 '@S9S_MB_2U_LIB.S9S_MB_2U(SCH_1):PAGE324_I14@PURE_QUANTA.Q_RES(CHIPS)':
 'B': CDS_PINID='B';
NODE_NAME     PU295 D3
 '@S9S_MB_2U_LIB.S9S_MB_2U(SCH_1):PAGE324_I35@PURE_QUANTA.MAX15090BEWIT(CHIPS)':
 'OV': CDS_PINID='OV';
NET_NAME
'P3V3_E1S_PWRGD_0'
 '@S9S_MB_2U_LIB.S9S_MB_2U(SCH_1):P3V3_E1S_PWRGD_0':
 C_SIGNAL='@s9s_mb_2u_lib.s9s_mb_2u(sch_1):p3v3_e1s_pwrgd_0';
NODE_NAME     R3973 1
 '@S9S_MB_2U_LIB.S9S_MB_2U(SCH_1):PAGE324_I44@PURE_QUANTA.Q_RES(CHIPS)':
 'A': CDS_PINID='A';
NODE_NAME     PU295 D7
 '@S9S_MB_2U_LIB.S9S_MB_2U(SCH_1):PAGE324_I35@PURE_QUANTA.MAX15090BEWIT(CHIPS)':
 'PG': CDS_PINID='PG';
NET_NAME
'P3V3_E1S_REG_0'
 '@S9S_MB_2U_LIB.S9S_MB_2U(SCH_1):P3V3_E1S_REG_0':
 C_SIGNAL='@s9s_mb_2u_lib.s9s_mb_2u(sch_1):p3v3_e1s_reg_0';
NODE_NAME     PU295 D1
 '@S9S_MB_2U_LIB.S9S_MB_2U(SCH_1):PAGE324_I35@PURE_QUANTA.MAX15090BEWIT(CHIPS)':
 'REG': CDS_PINID='REG';
NODE_NAME     PC2212 2
 '@S9S_MB_2U_LIB.S9S_MB_2U(SCH_1):PAGE324_I38@PURE_QUANTA.Q_CAP(CHIPS)':
 'B': CDS_PINID='B';
NET_NAME
'P3V3_E1S_SENSE_0'
 '@S9S_MB_2U_LIB.S9S_MB_2U(SCH_1):P3V3_E1S_SENSE_0':
 C_SIGNAL='@s9s_mb_2u_lib.s9s_mb_2u(sch_1):p3v3_e1s_sense_0';
NODE_NAME     PR3971 1
 '@S9S_MB_2U_LIB.S9S_MB_2U(SCH_1):PAGE324_I41@PURE_QUANTA.Q_RES(CHIPS)':
 'A': CDS_PINID='A';
NODE_NAME     PU295 A1
 '@S9S_MB_2U_LIB.S9S_MB_2U(SCH_1):PAGE324_I35@PURE_QUANTA.MAX15090BEWIT(CHIPS)':
 'ISENSE': CDS_PINID='ISENSE';
NET_NAME
'P3V3_E1S_UV_0'
 '@S9S_MB_2U_LIB.S9S_MB_2U(SCH_1):P3V3_E1S_UV_0':
 C_SIGNAL='@s9s_mb_2u_lib.s9s_mb_2u(sch_1):p3v3_e1s_uv_0';
NODE_NAME     PR3964 1
 '@S9S_MB_2U_LIB.S9S_MB_2U(SCH_1):PAGE324_I14@PURE_QUANTA.Q_RES(CHIPS)':
 'A': CDS_PINID='A';
NODE_NAME     R3959 2
 '@S9S_MB_2U_LIB.S9S_MB_2U(SCH_1):PAGE324_I15@PURE_QUANTA.Q_RES(CHIPS)':
 'B': CDS_PINID='B';
NODE_NAME     PR3963 2
 '@S9S_MB_2U_LIB.S9S_MB_2U(SCH_1):PAGE324_I18@PURE_QUANTA.Q_RES(CHIPS)':
 'B': CDS_PINID='B';
NODE_NAME     PU295 D2
 '@S9S_MB_2U_LIB.S9S_MB_2U(SCH_1):PAGE324_I35@PURE_QUANTA.MAX15090BEWIT(CHIPS)':
 'UV': CDS_PINID='UV';
NET_NAME
'P3V3_E1S_UV_0_R'
 '@S9S_MB_2U_LIB.S9S_MB_2U(SCH_1):P3V3_E1S_UV_0_R':
 C_SIGNAL='@s9s_mb_2u_lib.s9s_mb_2u(sch_1):p3v3_e1s_uv_0_r';
NODE_NAME     Q126 3
 '@S9S_MB_2U_LIB.S9S_MB_2U(SCH_1):PAGE324_I4@PURE_QUANTA.MOSFET_NCH_DUAL(CHIPS)':
 'D2': CDS_PINID='D2';
NODE_NAME     R3959 1
 '@S9S_MB_2U_LIB.S9S_MB_2U(SCH_1):PAGE324_I15@PURE_QUANTA.Q_RES(CHIPS)':
 'A': CDS_PINID='A';
NET_NAME
'P3V3_E1S_VCC_0'
 '@S9S_MB_2U_LIB.S9S_MB_2U(SCH_1):P3V3_E1S_VCC_0':
 C_SIGNAL='@s9s_mb_2u_lib.s9s_mb_2u(sch_1):p3v3_e1s_vcc_0';
NODE_NAME     PR3967 2
 '@S9S_MB_2U_LIB.S9S_MB_2U(SCH_1):PAGE324_I39@PURE_QUANTA.Q_RES(CHIPS)':
 'B': CDS_PINID='B';
NODE_NAME     PC2210 1
 '@S9S_MB_2U_LIB.S9S_MB_2U(SCH_1):PAGE324_I37@PURE_QUANTA.Q_CAP(CHIPS)':
 'A': CDS_PINID='A';
NODE_NAME     PU295 A2
 '@S9S_MB_2U_LIB.S9S_MB_2U(SCH_1):PAGE324_I35@PURE_QUANTA.MAX15090BEWIT(CHIPS)':
 'VCC': CDS_PINID='VCC';
NET_NAME
'P3V3_M2_0'
 '@S9S_MB_2U_LIB.S9S_MB_2U(SCH_1):P3V3_M2_0':
 C_SIGNAL='@s9s_mb_2u_lib.s9s_mb_2u(sch_1):p3v3_m2_0',
 CDS_GLOBAL_NET='TRUE';
NODE_NAME     C1920 1
 '@S9S_MB_2U_LIB.S9S_MB_2U(SCH_1):PAGE182_I88@PURE_QUANTA.Q_CAP(CHIPS)':
 'A': CDS_PINID='A';
NODE_NAME     C1921 1
 '@S9S_MB_2U_LIB.S9S_MB_2U(SCH_1):PAGE182_I90@PURE_QUANTA.Q_CAP(CHIPS)':
 'A': CDS_PINID='A';
NODE_NAME     C1922 1
 '@S9S_MB_2U_LIB.S9S_MB_2U(SCH_1):PAGE182_I96@PURE_QUANTA.Q_CAP(CHIPS)':
 'A': CDS_PINID='A';
NODE_NAME     C1923 1
 '@S9S_MB_2U_LIB.S9S_MB_2U(SCH_1):PAGE182_I97@PURE_QUANTA.Q_CAP(CHIPS)':
 'A': CDS_PINID='A';
NODE_NAME     C1924 1
 '@S9S_MB_2U_LIB.S9S_MB_2U(SCH_1):PAGE182_I98@PURE_QUANTA.Q_CAP(CHIPS)':
 'A': CDS_PINID='A';
NODE_NAME     C1925 1
 '@S9S_MB_2U_LIB.S9S_MB_2U(SCH_1):PAGE182_I100@PURE_QUANTA.Q_CAP(CHIPS)':
 'A': CDS_PINID='A';
NODE_NAME     J59 2
 '@S9S_MB_2U_LIB.S9S_MB_2U(SCH_1):PAGE182_I178@PURE_QUANTA.SCONN75K_APCI0155P004A(CHIPS)':
 '3.3V_1': CDS_PINID='\3.3v_1\';
NODE_NAME     J59 4
 '@S9S_MB_2U_LIB.S9S_MB_2U(SCH_1):PAGE182_I178@PURE_QUANTA.SCONN75K_APCI0155P004A(CHIPS)':
 '3.3V_2': CDS_PINID='\3.3v_2\';
NODE_NAME     J59 12
 '@S9S_MB_2U_LIB.S9S_MB_2U(SCH_1):PAGE182_I178@PURE_QUANTA.SCONN75K_APCI0155P004A(CHIPS)':
 '3.3V_3': CDS_PINID='\3.3v_3\';
NODE_NAME     J59 14
 '@S9S_MB_2U_LIB.S9S_MB_2U(SCH_1):PAGE182_I178@PURE_QUANTA.SCONN75K_APCI0155P004A(CHIPS)':
 '3.3V_4': CDS_PINID='\3.3v_4\';
NODE_NAME     J59 16
 '@S9S_MB_2U_LIB.S9S_MB_2U(SCH_1):PAGE182_I178@PURE_QUANTA.SCONN75K_APCI0155P004A(CHIPS)':
 '3.3V_5': CDS_PINID='\3.3v_5\';
NODE_NAME     J59 18
 '@S9S_MB_2U_LIB.S9S_MB_2U(SCH_1):PAGE182_I178@PURE_QUANTA.SCONN75K_APCI0155P004A(CHIPS)':
 '3.3V_6': CDS_PINID='\3.3v_6\';
NODE_NAME     J59 70
 '@S9S_MB_2U_LIB.S9S_MB_2U(SCH_1):PAGE182_I178@PURE_QUANTA.SCONN75K_APCI0155P004A(CHIPS)':
 '3.3V_7': CDS_PINID='\3.3v_7\';
NODE_NAME     J59 72
 '@S9S_MB_2U_LIB.S9S_MB_2U(SCH_1):PAGE182_I178@PURE_QUANTA.SCONN75K_APCI0155P004A(CHIPS)':
 '3.3V_8': CDS_PINID='\3.3v_8\';
NODE_NAME     J59 74
 '@S9S_MB_2U_LIB.S9S_MB_2U(SCH_1):PAGE182_I178@PURE_QUANTA.SCONN75K_APCI0155P004A(CHIPS)':
 '3.3V_9': CDS_PINID='\3.3v_9\';
NODE_NAME     R3575 1
 '@S9S_MB_2U_LIB.S9S_MB_2U(SCH_1):PAGE163_I33@PURE_QUANTA.Q_RES(CHIPS)':
 'A': CDS_PINID='A';
NODE_NAME     R3295 1
 '@S9S_MB_2U_LIB.S9S_MB_2U(SCH_1):PAGE182_I317@PURE_QUANTA.Q_RES(CHIPS)':
 'A': CDS_PINID='A';
NODE_NAME     R3634 1
 '@S9S_MB_2U_LIB.S9S_MB_2U(SCH_1):PAGE163_I128@PURE_QUANTA.Q_RES(CHIPS)':
 'A': CDS_PINID='A';
NET_NAME
'P3V3_MAX11617_VDD'
 '@S9S_MB_2U_LIB.S9S_MB_2U(SCH_1):P3V3_MAX11617 _VDD':
 C_SIGNAL='@s9s_mb_2u_lib.s9s_mb_2u(sch_1):\p3v3_max11617 _vdd\';
NODE_NAME     U193 16
 '@S9S_MB_2U_LIB.S9S_MB_2U(SCH_1):PAGE239_I57@PURE_QUANTA.MAX11617EEET(CHIPS)':
 'VDD': CDS_PINID='VDD';
NODE_NAME     C1757 1
 '@S9S_MB_2U_LIB.S9S_MB_2U(SCH_1):PAGE239_I58@PURE_QUANTA.Q_CAP(CHIPS)':
 'A': CDS_PINID='A';
NODE_NAME     C1768 1
 '@S9S_MB_2U_LIB.S9S_MB_2U(SCH_1):PAGE239_I61@PURE_QUANTA.Q_CAP(CHIPS)':
 'A': CDS_PINID='A';
NODE_NAME     L15 1
 '@S9S_MB_2U_LIB.S9S_MB_2U(SCH_1):PAGE239_I62@PURE_QUANTA.Q_INDUCTOR(CHIPS)':
 '1': CDS_PINID='\1\';
NET_NAME
'P3V3_OCP_1_EN_G'
 '@S9S_MB_2U_LIB.S9S_MB_2U(SCH_1):P3V3_OCP_1_EN_G':
 C_SIGNAL='@s9s_mb_2u_lib.s9s_mb_2u(sch_1):p3v3_ocp_1_en_g';
NODE_NAME     R4070 2
 '@S9S_MB_2U_LIB.S9S_MB_2U(SCH_1):PAGE153_I62@PURE_QUANTA.Q_RES(CHIPS)':
 'B': CDS_PINID='B';
NODE_NAME     Q124 6
 '@S9S_MB_2U_LIB.S9S_MB_2U(SCH_1):PAGE153_I21@PURE_QUANTA.MOSFET_NCH_DUAL(CHIPS)':
 'D1': CDS_PINID='D1';
NODE_NAME     Q124 5
 '@S9S_MB_2U_LIB.S9S_MB_2U(SCH_1):PAGE153_I36@PURE_QUANTA.MOSFET_NCH_DUAL(CHIPS)':
 'G2': CDS_PINID='G2';
NET_NAME
'P3V3_OCP_2_EN_G'
 '@S9S_MB_2U_LIB.S9S_MB_2U(SCH_1):P3V3_OCP_2_EN_G':
 C_SIGNAL='@s9s_mb_2u_lib.s9s_mb_2u(sch_1):p3v3_ocp_2_en_g';
NODE_NAME     Q119 6
 '@S9S_MB_2U_LIB.S9S_MB_2U(SCH_1):PAGE131_I38@PURE_QUANTA.MOSFET_NCH_DUAL(CHIPS)':
 'D1': CDS_PINID='D1';
NODE_NAME     R4067 2
 '@S9S_MB_2U_LIB.S9S_MB_2U(SCH_1):PAGE131_I40@PURE_QUANTA.Q_RES(CHIPS)':
 'B': CDS_PINID='B';
NODE_NAME     Q119 5
 '@S9S_MB_2U_LIB.S9S_MB_2U(SCH_1):PAGE131_I42@PURE_QUANTA.MOSFET_NCH_DUAL(CHIPS)':
 'G2': CDS_PINID='G2';
NET_NAME
'P3V3_OCP_CB_1'
 '@S9S_MB_2U_LIB.S9S_MB_2U(SCH_1):P3V3_OCP_CB_1':
 C_SIGNAL='@s9s_mb_2u_lib.s9s_mb_2u(sch_1):p3v3_ocp_cb_1';
NODE_NAME     PR3780 1
 '@S9S_MB_2U_LIB.S9S_MB_2U(SCH_1):PAGE153_I60@PURE_QUANTA.Q_RES(CHIPS)':
 'A': CDS_PINID='A';
NODE_NAME     PU202 B1
 '@S9S_MB_2U_LIB.S9S_MB_2U(SCH_1):PAGE153_I61@PURE_QUANTA.MAX15090BEWIT(CHIPS)':
 'CB': CDS_PINID='CB';
NET_NAME
'P3V3_OCP_CB_2'
 '@S9S_MB_2U_LIB.S9S_MB_2U(SCH_1):P3V3_OCP_CB_2':
 C_SIGNAL='@s9s_mb_2u_lib.s9s_mb_2u(sch_1):p3v3_ocp_cb_2';
NODE_NAME     PR3822 1
 '@S9S_MB_2U_LIB.S9S_MB_2U(SCH_1):PAGE131_I89@PURE_QUANTA.Q_RES(CHIPS)':
 'A': CDS_PINID='A';
NODE_NAME     PU200 B1
 '@S9S_MB_2U_LIB.S9S_MB_2U(SCH_1):PAGE131_I90@PURE_QUANTA.MAX15090BEWIT(CHIPS)':
 'CB': CDS_PINID='CB';
NET_NAME
'P3V3_OCP_DVDT_1'
 '@S9S_MB_2U_LIB.S9S_MB_2U(SCH_1):P3V3_OCP_DVDT_1':
 C_SIGNAL='@s9s_mb_2u_lib.s9s_mb_2u(sch_1):p3v3_ocp_dvdt_1';
NODE_NAME     PC2161 1
 '@S9S_MB_2U_LIB.S9S_MB_2U(SCH_1):PAGE236_I49@PURE_QUANTA.Q_CAP(CHIPS)':
 'A': CDS_PINID='A';
NODE_NAME     PU205 10
 '@S9S_MB_2U_LIB.S9S_MB_2U(SCH_1):PAGE236_I50@PURE_QUANTA.MP5016GQHLZ(CHIPS)':
 'DV_DT': CDS_PINID='DV_DT';
NET_NAME
'P3V3_OCP_DVDT_2'
 '@S9S_MB_2U_LIB.S9S_MB_2U(SCH_1):P3V3_OCP_DVDT_2':
 C_SIGNAL='@s9s_mb_2u_lib.s9s_mb_2u(sch_1):p3v3_ocp_dvdt_2';
NODE_NAME     PC1321 1
 '@S9S_MB_2U_LIB.S9S_MB_2U(SCH_1):PAGE237_I50@PURE_QUANTA.Q_CAP(CHIPS)':
 'A': CDS_PINID='A';
NODE_NAME     PU207 10
 '@S9S_MB_2U_LIB.S9S_MB_2U(SCH_1):PAGE237_I51@PURE_QUANTA.MP5016GQHLZ(CHIPS)':
 'DV_DT': CDS_PINID='DV_DT';
NET_NAME
'P3V3_OCP_EN_1_R'
 '@S9S_MB_2U_LIB.S9S_MB_2U(SCH_1):P3V3_OCP_EN_1_R':
 C_SIGNAL='@s9s_mb_2u_lib.s9s_mb_2u(sch_1):p3v3_ocp_en_1_r';
NODE_NAME     R4069 1
 '@S9S_MB_2U_LIB.S9S_MB_2U(SCH_1):PAGE153_I20@PURE_QUANTA.Q_RES(CHIPS)':
 'A': CDS_PINID='A';
NODE_NAME     R5487 2
 '@S9S_MB_2U_LIB.S9S_MB_2U(SCH_1):PAGE153_I19@PURE_QUANTA.Q_RES(CHIPS)':
 'B': CDS_PINID='B';
NODE_NAME     Q124 2
 '@S9S_MB_2U_LIB.S9S_MB_2U(SCH_1):PAGE153_I21@PURE_QUANTA.MOSFET_NCH_DUAL(CHIPS)':
 'G1': CDS_PINID='G1';
NET_NAME
'P3V3_OCP_EN_1_R2'
 '@S9S_MB_2U_LIB.S9S_MB_2U(SCH_1):P3V3_OCP_EN_1_R2':
 C_SIGNAL='@s9s_mb_2u_lib.s9s_mb_2u(sch_1):p3v3_ocp_en_1_r2';
NODE_NAME     R3845 2
 '@S9S_MB_2U_LIB.S9S_MB_2U(SCH_1):PAGE236_I46@PURE_QUANTA.Q_RES(CHIPS)':
 'B': CDS_PINID='B';
NODE_NAME     PU205 9
 '@S9S_MB_2U_LIB.S9S_MB_2U(SCH_1):PAGE236_I50@PURE_QUANTA.MP5016GQHLZ(CHIPS)':
 'EN': CDS_PINID='EN';
NET_NAME
'P3V3_OCP_EN_2'
 '@S9S_MB_2U_LIB.S9S_MB_2U(SCH_1):P3V3_OCP_EN_2':
 C_SIGNAL='@s9s_mb_2u_lib.s9s_mb_2u(sch_1):p3v3_ocp_en_2';
NODE_NAME     R3631 2
 '@S9S_MB_2U_LIB.S9S_MB_2U(SCH_1):PAGE237_I44@PURE_QUANTA.Q_RES(CHIPS)':
 'B': CDS_PINID='B';
NODE_NAME     PU207 9
 '@S9S_MB_2U_LIB.S9S_MB_2U(SCH_1):PAGE237_I51@PURE_QUANTA.MP5016GQHLZ(CHIPS)':
 'EN': CDS_PINID='EN';
NET_NAME
'P3V3_OCP_EN_2_R'
 '@S9S_MB_2U_LIB.S9S_MB_2U(SCH_1):P3V3_OCP_EN_2_R':
 C_SIGNAL='@s9s_mb_2u_lib.s9s_mb_2u(sch_1):p3v3_ocp_en_2_r';
NODE_NAME     Q119 2
 '@S9S_MB_2U_LIB.S9S_MB_2U(SCH_1):PAGE131_I38@PURE_QUANTA.MOSFET_NCH_DUAL(CHIPS)':
 'G1': CDS_PINID='G1';
NODE_NAME     R4060 2
 '@S9S_MB_2U_LIB.S9S_MB_2U(SCH_1):PAGE131_I35@PURE_QUANTA.Q_RES(CHIPS)':
 'B': CDS_PINID='B';
NODE_NAME     R4066 1
 '@S9S_MB_2U_LIB.S9S_MB_2U(SCH_1):PAGE131_I37@PURE_QUANTA.Q_RES(CHIPS)':
 'A': CDS_PINID='A';
NET_NAME
'P3V3_OCP_FAULT_1'
 '@S9S_MB_2U_LIB.S9S_MB_2U(SCH_1):P3V3_OCP_FAULT_1':
 C_SIGNAL='@s9s_mb_2u_lib.s9s_mb_2u(sch_1):p3v3_ocp_fault_1';
NODE_NAME     PU202 C7
 '@S9S_MB_2U_LIB.S9S_MB_2U(SCH_1):PAGE153_I61@PURE_QUANTA.MAX15090BEWIT(CHIPS)':
 'FAULT#': CDS_PINID='\fault#\';
NODE_NAME     R3796 2
 '@S9S_MB_2U_LIB.S9S_MB_2U(SCH_1):PAGE153_I108@PURE_QUANTA.Q_RES(CHIPS)':
 'B': CDS_PINID='B';
NET_NAME
'P3V3_OCP_FAULT_2'
 '@S9S_MB_2U_LIB.S9S_MB_2U(SCH_1):P3V3_OCP_FAULT_2':
 C_SIGNAL='@s9s_mb_2u_lib.s9s_mb_2u(sch_1):p3v3_ocp_fault_2';
NODE_NAME     PU200 C7
 '@S9S_MB_2U_LIB.S9S_MB_2U(SCH_1):PAGE131_I90@PURE_QUANTA.MAX15090BEWIT(CHIPS)':
 'FAULT#': CDS_PINID='\fault#\';
NODE_NAME     R3833 2
 '@S9S_MB_2U_LIB.S9S_MB_2U(SCH_1):PAGE131_I108@PURE_QUANTA.Q_RES(CHIPS)':
 'B': CDS_PINID='B';
NET_NAME
'P3V3_OCP_GATE_1'
 '@S9S_MB_2U_LIB.S9S_MB_2U(SCH_1):P3V3_OCP_GATE_1':
 C_SIGNAL='@s9s_mb_2u_lib.s9s_mb_2u(sch_1):p3v3_ocp_gate_1';
NODE_NAME     PC2162 1
 '@S9S_MB_2U_LIB.S9S_MB_2U(SCH_1):PAGE236_I52@PURE_QUANTA.Q_CAP(CHIPS)':
 'A': CDS_PINID='A';
NODE_NAME     PU205 8
 '@S9S_MB_2U_LIB.S9S_MB_2U(SCH_1):PAGE236_I50@PURE_QUANTA.MP5016GQHLZ(CHIPS)':
 'GATE': CDS_PINID='GATE';
NET_NAME
'P3V3_OCP_GATE_2'
 '@S9S_MB_2U_LIB.S9S_MB_2U(SCH_1):P3V3_OCP_GATE_2':
 C_SIGNAL='@s9s_mb_2u_lib.s9s_mb_2u(sch_1):p3v3_ocp_gate_2';
NODE_NAME     PU200 A6
 '@S9S_MB_2U_LIB.S9S_MB_2U(SCH_1):PAGE131_I90@PURE_QUANTA.MAX15090BEWIT(CHIPS)':
 'GATE': CDS_PINID='GATE';
NODE_NAME     PC2151 1
 '@S9S_MB_2U_LIB.S9S_MB_2U(SCH_1):PAGE131_I96@PURE_QUANTA.Q_CAP(CHIPS)':
 'A': CDS_PINID='A';
NODE_NAME     PC2149 2
 '@S9S_MB_2U_LIB.S9S_MB_2U(SCH_1):PAGE131_I105@PURE_QUANTA.Q_CAP(CHIPS)':
 'B': CDS_PINID='B';
NODE_NAME     PR4523 2
 '@S9S_MB_2U_LIB.S9S_MB_2U(SCH_1):PAGE131_I106@PURE_QUANTA.Q_RES(CHIPS)':
 'B': CDS_PINID='B';
NET_NAME
'P3V3_OCP_GATE_PU202_1'
 '@S9S_MB_2U_LIB.S9S_MB_2U(SCH_1):P3V3_OCP_GATE_PU202_1':
 C_SIGNAL='@s9s_mb_2u_lib.s9s_mb_2u(sch_1):p3v3_ocp_gate_pu202_1';
NODE_NAME     PC2089 1
 '@S9S_MB_2U_LIB.S9S_MB_2U(SCH_1):PAGE153_I107@PURE_QUANTA.Q_CAP(CHIPS)':
 'A': CDS_PINID='A';
NODE_NAME     PC2144 2
 '@S9S_MB_2U_LIB.S9S_MB_2U(SCH_1):PAGE153_I101@PURE_QUANTA.Q_CAP(CHIPS)':
 'B': CDS_PINID='B';
NODE_NAME     PR4525 2
 '@S9S_MB_2U_LIB.S9S_MB_2U(SCH_1):PAGE153_I103@PURE_QUANTA.Q_RES(CHIPS)':
 'B': CDS_PINID='B';
NODE_NAME     PU202 A6
 '@S9S_MB_2U_LIB.S9S_MB_2U(SCH_1):PAGE153_I61@PURE_QUANTA.MAX15090BEWIT(CHIPS)':
 'GATE': CDS_PINID='GATE';
NET_NAME
'P3V3_OCP_GATE_PU207_2'
 '@S9S_MB_2U_LIB.S9S_MB_2U(SCH_1):P3V3_OCP_GATE_PU207_2':
 C_SIGNAL='@s9s_mb_2u_lib.s9s_mb_2u(sch_1):p3v3_ocp_gate_pu207_2';
NODE_NAME     PC1322 1
 '@S9S_MB_2U_LIB.S9S_MB_2U(SCH_1):PAGE237_I54@PURE_QUANTA.Q_CAP(CHIPS)':
 'A': CDS_PINID='A';
NODE_NAME     PU207 8
 '@S9S_MB_2U_LIB.S9S_MB_2U(SCH_1):PAGE237_I51@PURE_QUANTA.MP5016GQHLZ(CHIPS)':
 'GATE': CDS_PINID='GATE';
NET_NAME
'P3V3_OCP_ILIMIT_1'
 '@S9S_MB_2U_LIB.S9S_MB_2U(SCH_1):P3V3_OCP_ILIMIT_1':
 C_SIGNAL='@s9s_mb_2u_lib.s9s_mb_2u(sch_1):p3v3_ocp_ilimit_1';
NODE_NAME     PU205 4
 '@S9S_MB_2U_LIB.S9S_MB_2U(SCH_1):PAGE236_I50@PURE_QUANTA.MP5016GQHLZ(CHIPS)':
 'ILIMIT': CDS_PINID='ILIMIT';
NODE_NAME     PR3846 2
 '@S9S_MB_2U_LIB.S9S_MB_2U(SCH_1):PAGE236_I45@PURE_QUANTA.Q_RES(CHIPS)':
 'B': CDS_PINID='B';
NET_NAME
'P3V3_OCP_ILIMIT_2'
 '@S9S_MB_2U_LIB.S9S_MB_2U(SCH_1):P3V3_OCP_ILIMIT_2':
 C_SIGNAL='@s9s_mb_2u_lib.s9s_mb_2u(sch_1):p3v3_ocp_ilimit_2';
NODE_NAME     PR3856 2
 '@S9S_MB_2U_LIB.S9S_MB_2U(SCH_1):PAGE237_I46@PURE_QUANTA.Q_RES(CHIPS)':
 'B': CDS_PINID='B';
NODE_NAME     PU207 4
 '@S9S_MB_2U_LIB.S9S_MB_2U(SCH_1):PAGE237_I51@PURE_QUANTA.MP5016GQHLZ(CHIPS)':
 'ILIMIT': CDS_PINID='ILIMIT';
NET_NAME
'P3V3_OCP_MODE_1'
 '@S9S_MB_2U_LIB.S9S_MB_2U(SCH_1):P3V3_OCP_MODE_1':
 C_SIGNAL='@s9s_mb_2u_lib.s9s_mb_2u(sch_1):p3v3_ocp_mode_1';
NODE_NAME     PC2157 1
 '@S9S_MB_2U_LIB.S9S_MB_2U(SCH_1):PAGE236_I42@PURE_QUANTA.Q_CAP(CHIPS)':
 'A': CDS_PINID='A';
NODE_NAME     PR3844 1
 '@S9S_MB_2U_LIB.S9S_MB_2U(SCH_1):PAGE236_I43@PURE_QUANTA.Q_RES(CHIPS)':
 'A': CDS_PINID='A';
NODE_NAME     PU205 5
 '@S9S_MB_2U_LIB.S9S_MB_2U(SCH_1):PAGE236_I50@PURE_QUANTA.MP5016GQHLZ(CHIPS)':
 'MODE': CDS_PINID='MODE';
NET_NAME
'P3V3_OCP_MODE_2'
 '@S9S_MB_2U_LIB.S9S_MB_2U(SCH_1):P3V3_OCP_MODE_2':
 C_SIGNAL='@s9s_mb_2u_lib.s9s_mb_2u(sch_1):p3v3_ocp_mode_2';
NODE_NAME     PR3855 1
 '@S9S_MB_2U_LIB.S9S_MB_2U(SCH_1):PAGE237_I43@PURE_QUANTA.Q_RES(CHIPS)':
 'A': CDS_PINID='A';
NODE_NAME     PC2168 1
 '@S9S_MB_2U_LIB.S9S_MB_2U(SCH_1):PAGE237_I35@PURE_QUANTA.Q_CAP(CHIPS)':
 'A': CDS_PINID='A';
NODE_NAME     PU207 5
 '@S9S_MB_2U_LIB.S9S_MB_2U(SCH_1):PAGE237_I51@PURE_QUANTA.MP5016GQHLZ(CHIPS)':
 'MODE': CDS_PINID='MODE';
NET_NAME
'P3V3_OCP_OV_1'
 '@S9S_MB_2U_LIB.S9S_MB_2U(SCH_1):P3V3_OCP_OV_1':
 C_SIGNAL='@s9s_mb_2u_lib.s9s_mb_2u(sch_1):p3v3_ocp_ov_1';
NODE_NAME     PR3791 1
 '@S9S_MB_2U_LIB.S9S_MB_2U(SCH_1):PAGE153_I58@PURE_QUANTA.Q_RES(CHIPS)':
 'A': CDS_PINID='A';
NODE_NAME     PU202 D3
 '@S9S_MB_2U_LIB.S9S_MB_2U(SCH_1):PAGE153_I61@PURE_QUANTA.MAX15090BEWIT(CHIPS)':
 'OV': CDS_PINID='OV';
NODE_NAME     PR3790 2
 '@S9S_MB_2U_LIB.S9S_MB_2U(SCH_1):PAGE153_I68@PURE_QUANTA.Q_RES(CHIPS)':
 'B': CDS_PINID='B';
NET_NAME
'P3V3_OCP_OV_2'
 '@S9S_MB_2U_LIB.S9S_MB_2U(SCH_1):P3V3_OCP_OV_2':
 C_SIGNAL='@s9s_mb_2u_lib.s9s_mb_2u(sch_1):p3v3_ocp_ov_2';
NODE_NAME     PR3812 1
 '@S9S_MB_2U_LIB.S9S_MB_2U(SCH_1):PAGE131_I48@PURE_QUANTA.Q_RES(CHIPS)':
 'A': CDS_PINID='A';
NODE_NAME     PU200 D3
 '@S9S_MB_2U_LIB.S9S_MB_2U(SCH_1):PAGE131_I90@PURE_QUANTA.MAX15090BEWIT(CHIPS)':
 'OV': CDS_PINID='OV';
NODE_NAME     PR3829 2
 '@S9S_MB_2U_LIB.S9S_MB_2U(SCH_1):PAGE131_I50@PURE_QUANTA.Q_RES(CHIPS)':
 'B': CDS_PINID='B';
NET_NAME
'P3V3_OCP_PWRGD_1'
 '@S9S_MB_2U_LIB.S9S_MB_2U(SCH_1):P3V3_OCP_PWRGD_1':
 C_SIGNAL='@s9s_mb_2u_lib.s9s_mb_2u(sch_1):p3v3_ocp_pwrgd_1';
NODE_NAME     R3794 1
 '@S9S_MB_2U_LIB.S9S_MB_2U(SCH_1):PAGE153_I105@PURE_QUANTA.Q_RES(CHIPS)':
 'A': CDS_PINID='A';
NODE_NAME     PU202 D7
 '@S9S_MB_2U_LIB.S9S_MB_2U(SCH_1):PAGE153_I61@PURE_QUANTA.MAX15090BEWIT(CHIPS)':
 'PG': CDS_PINID='PG';
NET_NAME
'P3V3_OCP_PWRGD_2'
 '@S9S_MB_2U_LIB.S9S_MB_2U(SCH_1):P3V3_OCP_PWRGD_2':
 C_SIGNAL='@s9s_mb_2u_lib.s9s_mb_2u(sch_1):p3v3_ocp_pwrgd_2';
NODE_NAME     R3832 1
 '@S9S_MB_2U_LIB.S9S_MB_2U(SCH_1):PAGE131_I97@PURE_QUANTA.Q_RES(CHIPS)':
 'A': CDS_PINID='A';
NODE_NAME     PU200 D7
 '@S9S_MB_2U_LIB.S9S_MB_2U(SCH_1):PAGE131_I90@PURE_QUANTA.MAX15090BEWIT(CHIPS)':
 'PG': CDS_PINID='PG';
NET_NAME
'P3V3_OCP_REG_1'
 '@S9S_MB_2U_LIB.S9S_MB_2U(SCH_1):P3V3_OCP_REG_1':
 C_SIGNAL='@s9s_mb_2u_lib.s9s_mb_2u(sch_1):p3v3_ocp_reg_1';
NODE_NAME     PC2093 2
 '@S9S_MB_2U_LIB.S9S_MB_2U(SCH_1):PAGE153_I72@PURE_QUANTA.Q_CAP(CHIPS)':
 'B': CDS_PINID='B';
NODE_NAME     PU202 D1
 '@S9S_MB_2U_LIB.S9S_MB_2U(SCH_1):PAGE153_I61@PURE_QUANTA.MAX15090BEWIT(CHIPS)':
 'REG': CDS_PINID='REG';
NET_NAME
'P3V3_OCP_REG_2'
 '@S9S_MB_2U_LIB.S9S_MB_2U(SCH_1):P3V3_OCP_REG_2':
 C_SIGNAL='@s9s_mb_2u_lib.s9s_mb_2u(sch_1):p3v3_ocp_reg_2';
NODE_NAME     PC2147 2
 '@S9S_MB_2U_LIB.S9S_MB_2U(SCH_1):PAGE131_I87@PURE_QUANTA.Q_CAP(CHIPS)':
 'B': CDS_PINID='B';
NODE_NAME     PU200 D1
 '@S9S_MB_2U_LIB.S9S_MB_2U(SCH_1):PAGE131_I90@PURE_QUANTA.MAX15090BEWIT(CHIPS)':
 'REG': CDS_PINID='REG';
NET_NAME
'P3V3_OCP_SENSE_1'
 '@S9S_MB_2U_LIB.S9S_MB_2U(SCH_1):P3V3_OCP_SENSE_1':
 C_SIGNAL='@s9s_mb_2u_lib.s9s_mb_2u(sch_1):p3v3_ocp_sense_1';
NODE_NAME     PR5481 1
 '@S9S_MB_2U_LIB.S9S_MB_2U(SCH_1):PAGE153_I102@PURE_QUANTA.Q_RES(CHIPS)':
 'A': CDS_PINID='A';
NODE_NAME     PU202 A1
 '@S9S_MB_2U_LIB.S9S_MB_2U(SCH_1):PAGE153_I61@PURE_QUANTA.MAX15090BEWIT(CHIPS)':
 'ISENSE': CDS_PINID='ISENSE';
NET_NAME
'P3V3_OCP_SENSE_2'
 '@S9S_MB_2U_LIB.S9S_MB_2U(SCH_1):P3V3_OCP_SENSE_2':
 C_SIGNAL='@s9s_mb_2u_lib.s9s_mb_2u(sch_1):p3v3_ocp_sense_2';
NODE_NAME     PU200 A1
 '@S9S_MB_2U_LIB.S9S_MB_2U(SCH_1):PAGE131_I90@PURE_QUANTA.MAX15090BEWIT(CHIPS)':
 'ISENSE': CDS_PINID='ISENSE';
NODE_NAME     PR3824 1
 '@S9S_MB_2U_LIB.S9S_MB_2U(SCH_1):PAGE131_I95@PURE_QUANTA.Q_RES(CHIPS)':
 'A': CDS_PINID='A';
NET_NAME
'P3V3_OCP_SFF'
 '@S9S_MB_2U_LIB.S9S_MB_2U(SCH_1):P3V3_OCP_SFF':
 C_SIGNAL='@s9s_mb_2u_lib.s9s_mb_2u(sch_1):p3v3_ocp_sff',
 CDS_GLOBAL_NET='TRUE';
NODE_NAME     R1592 1
 '@S9S_MB_2U_LIB.S9S_MB_2U(SCH_1):PAGE152_I37@PURE_QUANTA.Q_RES(CHIPS)':
 'A': CDS_PINID='A';
NODE_NAME     R1824 1
 '@S9S_MB_2U_LIB.S9S_MB_2U(SCH_1):PAGE152_I62@PURE_QUANTA.Q_RES(CHIPS)':
 'A': CDS_PINID='A';
NODE_NAME     R409 1
 '@S9S_MB_2U_LIB.S9S_MB_2U(SCH_1):PAGE150_I5@PURE_QUANTA.Q_RES(CHIPS)':
 'A': CDS_PINID='A';
NODE_NAME     R414 1
 '@S9S_MB_2U_LIB.S9S_MB_2U(SCH_1):PAGE150_I6@PURE_QUANTA.Q_RES(CHIPS)':
 'A': CDS_PINID='A';
NODE_NAME     C1237 1
 '@S9S_MB_2U_LIB.S9S_MB_2U(SCH_1):PAGE150_I114@PURE_QUANTA.Q_CAP(CHIPS)':
 'A': CDS_PINID='A';
NODE_NAME     C1238 1
 '@S9S_MB_2U_LIB.S9S_MB_2U(SCH_1):PAGE150_I115@PURE_QUANTA.Q_CAP(CHIPS)':
 'A': CDS_PINID='A';
NODE_NAME     C1239 1
 '@S9S_MB_2U_LIB.S9S_MB_2U(SCH_1):PAGE150_I116@PURE_QUANTA.Q_CAP(CHIPS)':
 'A': CDS_PINID='A';
NODE_NAME     C1240 1
 '@S9S_MB_2U_LIB.S9S_MB_2U(SCH_1):PAGE150_I168@PURE_QUANTA.Q_CAP(CHIPS)':
 'A': CDS_PINID='A';
NODE_NAME     C1862 1
 '@S9S_MB_2U_LIB.S9S_MB_2U(SCH_1):PAGE216_I23@PURE_QUANTA.Q_CAP(CHIPS)':
 'A': CDS_PINID='A';
NODE_NAME     U236 8
 '@S9S_MB_2U_LIB.S9S_MB_2U(SCH_1):PAGE216_I28@PURE_QUANTA.PCA9617ADP(CHIPS)':
 'VCCB': CDS_PINID='VCCB';
NODE_NAME     R3501 1
 '@S9S_MB_2U_LIB.S9S_MB_2U(SCH_1):PAGE216_I30@PURE_QUANTA.Q_RES(CHIPS)':
 'A': CDS_PINID='A';
NODE_NAME     R3500 1
 '@S9S_MB_2U_LIB.S9S_MB_2U(SCH_1):PAGE216_I31@PURE_QUANTA.Q_RES(CHIPS)':
 'A': CDS_PINID='A';
NODE_NAME     R3603 1
 '@S9S_MB_2U_LIB.S9S_MB_2U(SCH_1):PAGE295_I43@PURE_QUANTA.Q_RES(CHIPS)':
 'A': CDS_PINID='A';
NODE_NAME     J37 B11
 '@S9S_MB_2U_LIB.S9S_MB_2U(SCH_1):PAGE150_I199@PURE_QUANTA.SCONN168_ME1016810202011(CHIPS)':
 '+3.3V_EDGE': CDS_PINID='\+3.3v_edge\';
NODE_NAME     R423 2
 '@S9S_MB_2U_LIB.S9S_MB_2U(SCH_1):PAGE150_I212@PURE_QUANTA.Q_RES(CHIPS)':
 'B': CDS_PINID='B';
NODE_NAME     R421 2
 '@S9S_MB_2U_LIB.S9S_MB_2U(SCH_1):PAGE150_I217@PURE_QUANTA.Q_RES(CHIPS)':
 'B': CDS_PINID='B';
NODE_NAME     R420 2
 '@S9S_MB_2U_LIB.S9S_MB_2U(SCH_1):PAGE150_I218@PURE_QUANTA.Q_RES(CHIPS)':
 'B': CDS_PINID='B';
NODE_NAME     U52 3
 '@S9S_MB_2U_LIB.S9S_MB_2U(SCH_1):PAGE154_I228@PURE_QUANTA.APX80929SAG7(CHIPS)':
 'VCC': CDS_PINID='VCC';
NODE_NAME     C580 1
 '@S9S_MB_2U_LIB.S9S_MB_2U(SCH_1):PAGE154_I229@PURE_QUANTA.Q_CAP(CHIPS)':
 'A': CDS_PINID='A';
NODE_NAME     R3645 1
 '@S9S_MB_2U_LIB.S9S_MB_2U(SCH_1):PAGE295_I152@PURE_QUANTA.Q_RES(CHIPS)':
 'A': CDS_PINID='A';
NET_NAME
'P3V3_OCP_SFF_R'
 '@S9S_MB_2U_LIB.S9S_MB_2U(SCH_1):P3V3_OCP_SFF_R':
 C_SIGNAL='@s9s_mb_2u_lib.s9s_mb_2u(sch_1):p3v3_ocp_sff_r',
 CDS_GLOBAL_NET='TRUE';
NODE_NAME     U266 11
 '@S9S_MB_2U_LIB.S9S_MB_2U(SCH_1):PAGE295_I30@PURE_QUANTA.INA230AIRGTR(CHIPS)':
 'BUS': CDS_PINID='\bus\';
NODE_NAME     R3602 1
 '@S9S_MB_2U_LIB.S9S_MB_2U(SCH_1):PAGE295_I41@PURE_QUANTA.Q_RES(CHIPS)':
 'A': CDS_PINID='A';
NODE_NAME     C2024 1
 '@S9S_MB_2U_LIB.S9S_MB_2U(SCH_1):PAGE295_I50@PURE_QUANTA.Q_CAP(CHIPS)':
 'A': CDS_PINID='A';
NODE_NAME     PU205 6_7
 '@S9S_MB_2U_LIB.S9S_MB_2U(SCH_1):PAGE236_I50@PURE_QUANTA.MP5016GQHLZ(CHIPS)':
 'SOURCE': CDS_PINID='SOURCE';
NODE_NAME     PC2144 1
 '@S9S_MB_2U_LIB.S9S_MB_2U(SCH_1):PAGE153_I101@PURE_QUANTA.Q_CAP(CHIPS)':
 'A': CDS_PINID='A';
NODE_NAME     PR4525 1
 '@S9S_MB_2U_LIB.S9S_MB_2U(SCH_1):PAGE153_I103@PURE_QUANTA.Q_RES(CHIPS)':
 'A': CDS_PINID='A';
NODE_NAME     PD103 C
 '@S9S_MB_2U_LIB.S9S_MB_2U(SCH_1):PAGE153_I104@PURE_QUANTA.SCHOTTKY_AC(CHIPS)':
 'C': CDS_PINID='C';
NODE_NAME     PC2163 1
 '@S9S_MB_2U_LIB.S9S_MB_2U(SCH_1):PAGE236_I54@PURE_QUANTA.Q_CAP(CHIPS)':
 'A': CDS_PINID='A';
NODE_NAME     R3645 2
 '@S9S_MB_2U_LIB.S9S_MB_2U(SCH_1):PAGE295_I152@PURE_QUANTA.Q_RES(CHIPS)':
 'B': CDS_PINID='B';
NODE_NAME     PU202 A4
 '@S9S_MB_2U_LIB.S9S_MB_2U(SCH_1):PAGE153_I61@PURE_QUANTA.MAX15090BEWIT(CHIPS)':
 'OUT_A4': CDS_PINID='OUT_A4';
NODE_NAME     PU202 B4
 '@S9S_MB_2U_LIB.S9S_MB_2U(SCH_1):PAGE153_I61@PURE_QUANTA.MAX15090BEWIT(CHIPS)':
 'OUT_B4': CDS_PINID='OUT_B4';
NODE_NAME     PU202 B6
 '@S9S_MB_2U_LIB.S9S_MB_2U(SCH_1):PAGE153_I61@PURE_QUANTA.MAX15090BEWIT(CHIPS)':
 'OUT_B6': CDS_PINID='OUT_B6';
NODE_NAME     PU202 C4
 '@S9S_MB_2U_LIB.S9S_MB_2U(SCH_1):PAGE153_I61@PURE_QUANTA.MAX15090BEWIT(CHIPS)':
 'OUT_C4': CDS_PINID='OUT_C4';
NODE_NAME     PU202 C6
 '@S9S_MB_2U_LIB.S9S_MB_2U(SCH_1):PAGE153_I61@PURE_QUANTA.MAX15090BEWIT(CHIPS)':
 'OUT_C6': CDS_PINID='OUT_C6';
NODE_NAME     PU202 D4
 '@S9S_MB_2U_LIB.S9S_MB_2U(SCH_1):PAGE153_I61@PURE_QUANTA.MAX15090BEWIT(CHIPS)':
 'OUT_D4': CDS_PINID='OUT_D4';
NODE_NAME     PU202 D6
 '@S9S_MB_2U_LIB.S9S_MB_2U(SCH_1):PAGE153_I61@PURE_QUANTA.MAX15090BEWIT(CHIPS)':
 'OUT_D6': CDS_PINID='OUT_D6';
NODE_NAME     PC2091 1
 '@S9S_MB_2U_LIB.S9S_MB_2U(SCH_1):PAGE153_I111@PURE_QUANTA.Q_CAP(CHIPS)':
 'A': CDS_PINID='A';
NODE_NAME     PC2081 1
 '@S9S_MB_2U_LIB.S9S_MB_2U(SCH_1):PAGE153_I113@PURE_QUANTA.Q_CAP(CHIPS)':
 'A': CDS_PINID='A';
NET_NAME
'P3V3_OCP_UV_1'
 '@S9S_MB_2U_LIB.S9S_MB_2U(SCH_1):P3V3_OCP_UV_1':
 C_SIGNAL='@s9s_mb_2u_lib.s9s_mb_2u(sch_1):p3v3_ocp_uv_1';
NODE_NAME     PR3789 2
 '@S9S_MB_2U_LIB.S9S_MB_2U(SCH_1):PAGE153_I70@PURE_QUANTA.Q_RES(CHIPS)':
 'B': CDS_PINID='B';
NODE_NAME     PU202 D2
 '@S9S_MB_2U_LIB.S9S_MB_2U(SCH_1):PAGE153_I61@PURE_QUANTA.MAX15090BEWIT(CHIPS)':
 'UV': CDS_PINID='UV';
NODE_NAME     R3785 2
 '@S9S_MB_2U_LIB.S9S_MB_2U(SCH_1):PAGE153_I64@PURE_QUANTA.Q_RES(CHIPS)':
 'B': CDS_PINID='B';
NODE_NAME     PR3790 1
 '@S9S_MB_2U_LIB.S9S_MB_2U(SCH_1):PAGE153_I68@PURE_QUANTA.Q_RES(CHIPS)':
 'A': CDS_PINID='A';
NET_NAME
'P3V3_OCP_UV_1_R1'
 '@S9S_MB_2U_LIB.S9S_MB_2U(SCH_1):P3V3_OCP_UV_1_R1':
 C_SIGNAL='@s9s_mb_2u_lib.s9s_mb_2u(sch_1):p3v3_ocp_uv_1_r1';
NODE_NAME     Q124 3
 '@S9S_MB_2U_LIB.S9S_MB_2U(SCH_1):PAGE153_I36@PURE_QUANTA.MOSFET_NCH_DUAL(CHIPS)':
 'D2': CDS_PINID='D2';
NODE_NAME     R3785 1
 '@S9S_MB_2U_LIB.S9S_MB_2U(SCH_1):PAGE153_I64@PURE_QUANTA.Q_RES(CHIPS)':
 'A': CDS_PINID='A';
NET_NAME
'P3V3_OCP_UV_2'
 '@S9S_MB_2U_LIB.S9S_MB_2U(SCH_1):P3V3_OCP_UV_2':
 C_SIGNAL='@s9s_mb_2u_lib.s9s_mb_2u(sch_1):p3v3_ocp_uv_2';
NODE_NAME     R3807 2
 '@S9S_MB_2U_LIB.S9S_MB_2U(SCH_1):PAGE131_I47@PURE_QUANTA.Q_RES(CHIPS)':
 'B': CDS_PINID='B';
NODE_NAME     PU200 D2
 '@S9S_MB_2U_LIB.S9S_MB_2U(SCH_1):PAGE131_I90@PURE_QUANTA.MAX15090BEWIT(CHIPS)':
 'UV': CDS_PINID='UV';
NODE_NAME     PR3829 1
 '@S9S_MB_2U_LIB.S9S_MB_2U(SCH_1):PAGE131_I50@PURE_QUANTA.Q_RES(CHIPS)':
 'A': CDS_PINID='A';
NODE_NAME     PR3795 2
 '@S9S_MB_2U_LIB.S9S_MB_2U(SCH_1):PAGE131_I53@PURE_QUANTA.Q_RES(CHIPS)':
 'B': CDS_PINID='B';
NET_NAME
'P3V3_OCP_UV_2_R1'
 '@S9S_MB_2U_LIB.S9S_MB_2U(SCH_1):P3V3_OCP_UV_2_R1':
 C_SIGNAL='@s9s_mb_2u_lib.s9s_mb_2u(sch_1):p3v3_ocp_uv_2_r1';
NODE_NAME     Q119 3
 '@S9S_MB_2U_LIB.S9S_MB_2U(SCH_1):PAGE131_I42@PURE_QUANTA.MOSFET_NCH_DUAL(CHIPS)':
 'D2': CDS_PINID='D2';
NODE_NAME     R3807 1
 '@S9S_MB_2U_LIB.S9S_MB_2U(SCH_1):PAGE131_I47@PURE_QUANTA.Q_RES(CHIPS)':
 'A': CDS_PINID='A';
NET_NAME
'P3V3_OCP_V3_2'
 '@S9S_MB_2U_LIB.S9S_MB_2U(SCH_1):P3V3_OCP_V3_2':
 C_SIGNAL='@s9s_mb_2u_lib.s9s_mb_2u(sch_1):p3v3_ocp_v3_2',
 CDS_GLOBAL_NET='TRUE';
NODE_NAME     R3166 1
 '@S9S_MB_2U_LIB.S9S_MB_2U(SCH_1):PAGE146_I23@PURE_QUANTA.Q_RES(CHIPS)':
 'A': CDS_PINID='A';
NODE_NAME     R3162 1
 '@S9S_MB_2U_LIB.S9S_MB_2U(SCH_1):PAGE146_I26@PURE_QUANTA.Q_RES(CHIPS)':
 'A': CDS_PINID='A';
NODE_NAME     R3182 1
 '@S9S_MB_2U_LIB.S9S_MB_2U(SCH_1):PAGE156_I6@PURE_QUANTA.Q_RES(CHIPS)':
 'A': CDS_PINID='A';
NODE_NAME     R3183 1
 '@S9S_MB_2U_LIB.S9S_MB_2U(SCH_1):PAGE156_I7@PURE_QUANTA.Q_RES(CHIPS)':
 'A': CDS_PINID='A';
NODE_NAME     R3173 2
 '@S9S_MB_2U_LIB.S9S_MB_2U(SCH_1):PAGE146_I165@PURE_QUANTA.Q_RES(CHIPS)':
 'B': CDS_PINID='B';
NODE_NAME     C1835 1
 '@S9S_MB_2U_LIB.S9S_MB_2U(SCH_1):PAGE146_I173@PURE_QUANTA.Q_CAP(CHIPS)':
 'A': CDS_PINID='A';
NODE_NAME     C1836 1
 '@S9S_MB_2U_LIB.S9S_MB_2U(SCH_1):PAGE146_I174@PURE_QUANTA.Q_CAP(CHIPS)':
 'A': CDS_PINID='A';
NODE_NAME     C1837 1
 '@S9S_MB_2U_LIB.S9S_MB_2U(SCH_1):PAGE146_I175@PURE_QUANTA.Q_CAP(CHIPS)':
 'A': CDS_PINID='A';
NODE_NAME     C1838 1
 '@S9S_MB_2U_LIB.S9S_MB_2U(SCH_1):PAGE146_I177@PURE_QUANTA.Q_CAP(CHIPS)':
 'A': CDS_PINID='A';
NODE_NAME     U235 8
 '@S9S_MB_2U_LIB.S9S_MB_2U(SCH_1):PAGE216_I5@PURE_QUANTA.PCA9617ADP(CHIPS)':
 'VCCB': CDS_PINID='VCCB';
NODE_NAME     C1861 1
 '@S9S_MB_2U_LIB.S9S_MB_2U(SCH_1):PAGE216_I11@PURE_QUANTA.Q_CAP(CHIPS)':
 'A': CDS_PINID='A';
NODE_NAME     R3520 1
 '@S9S_MB_2U_LIB.S9S_MB_2U(SCH_1):PAGE216_I33@PURE_QUANTA.Q_RES(CHIPS)':
 'A': CDS_PINID='A';
NODE_NAME     R3519 1
 '@S9S_MB_2U_LIB.S9S_MB_2U(SCH_1):PAGE216_I34@PURE_QUANTA.Q_RES(CHIPS)':
 'A': CDS_PINID='A';
NODE_NAME     R3571 1
 '@S9S_MB_2U_LIB.S9S_MB_2U(SCH_1):PAGE163_I110@PURE_QUANTA.Q_RES(CHIPS)':
 'A': CDS_PINID='A';
NODE_NAME     J35 B11
 '@S9S_MB_2U_LIB.S9S_MB_2U(SCH_1):PAGE146_I303@PURE_QUANTA.SCONN168_ME1016810202011(CHIPS)':
 '+3.3V_EDGE': CDS_PINID='\+3.3v_edge\';
NODE_NAME     R3174 2
 '@S9S_MB_2U_LIB.S9S_MB_2U(SCH_1):PAGE146_I333@PURE_QUANTA.Q_RES(CHIPS)':
 'B': CDS_PINID='B';
NODE_NAME     R3176 2
 '@S9S_MB_2U_LIB.S9S_MB_2U(SCH_1):PAGE146_I336@PURE_QUANTA.Q_RES(CHIPS)':
 'B': CDS_PINID='B';
NODE_NAME     U216 3
 '@S9S_MB_2U_LIB.S9S_MB_2U(SCH_1):PAGE132_I85@PURE_QUANTA.APX80929SAG7(CHIPS)':
 'VCC': CDS_PINID='VCC';
NODE_NAME     C1819 1
 '@S9S_MB_2U_LIB.S9S_MB_2U(SCH_1):PAGE132_I87@PURE_QUANTA.Q_CAP(CHIPS)':
 'A': CDS_PINID='A';
NODE_NAME     R3633 1
 '@S9S_MB_2U_LIB.S9S_MB_2U(SCH_1):PAGE163_I127@PURE_QUANTA.Q_RES(CHIPS)':
 'A': CDS_PINID='A';
NET_NAME
'P3V3_OCP_V3_2_R'
 '@S9S_MB_2U_LIB.S9S_MB_2U(SCH_1):P3V3_OCP_V3_2_R':
 C_SIGNAL='@s9s_mb_2u_lib.s9s_mb_2u(sch_1):p3v3_ocp_v3_2_r',
 CDS_GLOBAL_NET='TRUE';
NODE_NAME     U263 11
 '@S9S_MB_2U_LIB.S9S_MB_2U(SCH_1):PAGE163_I94@PURE_QUANTA.INA230AIRGTR(CHIPS)':
 'BUS': CDS_PINID='\bus\';
NODE_NAME     R3570 1
 '@S9S_MB_2U_LIB.S9S_MB_2U(SCH_1):PAGE163_I109@PURE_QUANTA.Q_RES(CHIPS)':
 'A': CDS_PINID='A';
NODE_NAME     C2017 1
 '@S9S_MB_2U_LIB.S9S_MB_2U(SCH_1):PAGE163_I114@PURE_QUANTA.Q_CAP(CHIPS)':
 'A': CDS_PINID='A';
NODE_NAME     PU200 A4
 '@S9S_MB_2U_LIB.S9S_MB_2U(SCH_1):PAGE131_I90@PURE_QUANTA.MAX15090BEWIT(CHIPS)':
 'OUT_A4': CDS_PINID='OUT_A4';
NODE_NAME     PU200 B4
 '@S9S_MB_2U_LIB.S9S_MB_2U(SCH_1):PAGE131_I90@PURE_QUANTA.MAX15090BEWIT(CHIPS)':
 'OUT_B4': CDS_PINID='OUT_B4';
NODE_NAME     PU200 B6
 '@S9S_MB_2U_LIB.S9S_MB_2U(SCH_1):PAGE131_I90@PURE_QUANTA.MAX15090BEWIT(CHIPS)':
 'OUT_B6': CDS_PINID='OUT_B6';
NODE_NAME     PU200 C4
 '@S9S_MB_2U_LIB.S9S_MB_2U(SCH_1):PAGE131_I90@PURE_QUANTA.MAX15090BEWIT(CHIPS)':
 'OUT_C4': CDS_PINID='OUT_C4';
NODE_NAME     PU200 C6
 '@S9S_MB_2U_LIB.S9S_MB_2U(SCH_1):PAGE131_I90@PURE_QUANTA.MAX15090BEWIT(CHIPS)':
 'OUT_C6': CDS_PINID='OUT_C6';
NODE_NAME     PU200 D4
 '@S9S_MB_2U_LIB.S9S_MB_2U(SCH_1):PAGE131_I90@PURE_QUANTA.MAX15090BEWIT(CHIPS)':
 'OUT_D4': CDS_PINID='OUT_D4';
NODE_NAME     PU200 D6
 '@S9S_MB_2U_LIB.S9S_MB_2U(SCH_1):PAGE131_I90@PURE_QUANTA.MAX15090BEWIT(CHIPS)':
 'OUT_D6': CDS_PINID='OUT_D6';
NODE_NAME     PC2149 1
 '@S9S_MB_2U_LIB.S9S_MB_2U(SCH_1):PAGE131_I105@PURE_QUANTA.Q_CAP(CHIPS)':
 'A': CDS_PINID='A';
NODE_NAME     PD109 C
 '@S9S_MB_2U_LIB.S9S_MB_2U(SCH_1):PAGE131_I107@PURE_QUANTA.SCHOTTKY_AC(CHIPS)':
 'C': CDS_PINID='C';
NODE_NAME     PC2137 1
 '@S9S_MB_2U_LIB.S9S_MB_2U(SCH_1):PAGE131_I109@PURE_QUANTA.Q_CAP(CHIPS)':
 'A': CDS_PINID='A';
NODE_NAME     PU207 6_7
 '@S9S_MB_2U_LIB.S9S_MB_2U(SCH_1):PAGE237_I51@PURE_QUANTA.MP5016GQHLZ(CHIPS)':
 'SOURCE': CDS_PINID='SOURCE';
NODE_NAME     PC2173 1
 '@S9S_MB_2U_LIB.S9S_MB_2U(SCH_1):PAGE237_I56@PURE_QUANTA.Q_CAP(CHIPS)':
 'A': CDS_PINID='A';
NODE_NAME     R3633 2
 '@S9S_MB_2U_LIB.S9S_MB_2U(SCH_1):PAGE163_I127@PURE_QUANTA.Q_RES(CHIPS)':
 'B': CDS_PINID='B';
NODE_NAME     PC2142 1
 '@S9S_MB_2U_LIB.S9S_MB_2U(SCH_1):PAGE131_I113@PURE_QUANTA.Q_CAP(CHIPS)':
 'A': CDS_PINID='A';
NODE_NAME     PR4523 1
 '@S9S_MB_2U_LIB.S9S_MB_2U(SCH_1):PAGE131_I106@PURE_QUANTA.Q_RES(CHIPS)':
 'A': CDS_PINID='A';
NET_NAME
'P3V3_OCP_VCC_1'
 '@S9S_MB_2U_LIB.S9S_MB_2U(SCH_1):P3V3_OCP_VCC_1':
 C_SIGNAL='@s9s_mb_2u_lib.s9s_mb_2u(sch_1):p3v3_ocp_vcc_1';
NODE_NAME     PC2086 1
 '@S9S_MB_2U_LIB.S9S_MB_2U(SCH_1):PAGE153_I71@PURE_QUANTA.Q_CAP(CHIPS)':
 'A': CDS_PINID='A';
NODE_NAME     PU202 A2
 '@S9S_MB_2U_LIB.S9S_MB_2U(SCH_1):PAGE153_I61@PURE_QUANTA.MAX15090BEWIT(CHIPS)':
 'VCC': CDS_PINID='VCC';
NODE_NAME     PR3798 2
 '@S9S_MB_2U_LIB.S9S_MB_2U(SCH_1):PAGE153_I73@PURE_QUANTA.Q_RES(CHIPS)':
 'B': CDS_PINID='B';
NET_NAME
'P3V3_OCP_VCC_2'
 '@S9S_MB_2U_LIB.S9S_MB_2U(SCH_1):P3V3_OCP_VCC_2':
 C_SIGNAL='@s9s_mb_2u_lib.s9s_mb_2u(sch_1):p3v3_ocp_vcc_2';
NODE_NAME     PU200 A2
 '@S9S_MB_2U_LIB.S9S_MB_2U(SCH_1):PAGE131_I90@PURE_QUANTA.MAX15090BEWIT(CHIPS)':
 'VCC': CDS_PINID='VCC';
NODE_NAME     PR3782 2
 '@S9S_MB_2U_LIB.S9S_MB_2U(SCH_1):PAGE131_I92@PURE_QUANTA.Q_RES(CHIPS)':
 'B': CDS_PINID='B';
NODE_NAME     PC190 1
 '@S9S_MB_2U_LIB.S9S_MB_2U(SCH_1):PAGE131_I91@PURE_QUANTA.Q_CAP(CHIPS)':
 'A': CDS_PINID='A';
NET_NAME
'P3V3_PDB_AUX_ADC'
 '@S9S_MB_2U_LIB.S9S_MB_2U(SCH_1):P3V3_PDB_AUX_ADC':
 C_SIGNAL='@s9s_mb_2u_lib.s9s_mb_2u(sch_1):p3v3_pdb_aux_adc';
NODE_NAME     R4567 1
 '@S9S_MB_2U_LIB.S9S_MB_2U(SCH_1):PAGE239_I348@PURE_QUANTA.Q_RES(CHIPS)':
 'A': CDS_PINID='A';
NODE_NAME     J45 A3
 '@S9S_MB_2U_LIB.S9S_MB_2U(SCH_1):PAGE233_I12@PURE_QUANTA.CONN60_101062636003K02LF(CHIPS)':
 'A3': CDS_PINID='A3';
NET_NAME
'P3V3_PDB_AUX_ADC_MAM'
 '@S9S_MB_2U_LIB.S9S_MB_2U(SCH_1):P3V3_PDB_AUX_ADC_MAM':
 C_SIGNAL='@s9s_mb_2u_lib.s9s_mb_2u(sch_1):p3v3_pdb_aux_adc_mam';
NODE_NAME     U193 11
 '@S9S_MB_2U_LIB.S9S_MB_2U(SCH_1):PAGE239_I57@PURE_QUANTA.MAX11617EEET(CHIPS)':
 'AIN6': CDS_PINID='AIN6';
NODE_NAME     C2045 1
 '@S9S_MB_2U_LIB.S9S_MB_2U(SCH_1):PAGE239_I236@PURE_QUANTA.Q_CAP(CHIPS)':
 'A': CDS_PINID='A';
NODE_NAME     R3687 2
 '@S9S_MB_2U_LIB.S9S_MB_2U(SCH_1):PAGE239_I240@PURE_QUANTA.Q_RES(CHIPS)':
 'B': CDS_PINID='B';
NET_NAME
'P3V3_PDB_AUX_ADC_TIC'
 '@S9S_MB_2U_LIB.S9S_MB_2U(SCH_1):P3V3_PDB_AUX_ADC_TIC':
 C_SIGNAL='@s9s_mb_2u_lib.s9s_mb_2u(sch_1):p3v3_pdb_aux_adc_tic';
NODE_NAME     U269 10
 '@S9S_MB_2U_LIB.S9S_MB_2U(SCH_1):PAGE239_I103@PURE_QUANTA.ADC128D818CIMTXNOPB(CHIPS)':
 'IN6': CDS_PINID='IN6';
NODE_NAME     C2050 1
 '@S9S_MB_2U_LIB.S9S_MB_2U(SCH_1):PAGE239_I238@PURE_QUANTA.Q_CAP(CHIPS)':
 'A': CDS_PINID='A';
NODE_NAME     R3688 2
 '@S9S_MB_2U_LIB.S9S_MB_2U(SCH_1):PAGE239_I241@PURE_QUANTA.Q_RES(CHIPS)':
 'B': CDS_PINID='B';
NET_NAME
'P3V3_PWRGD_CLKGEN'
 '@S9S_MB_2U_LIB.S9S_MB_2U(SCH_1):P3V3_PWRGD_CLKGEN':
 C_SIGNAL='@s9s_mb_2u_lib.s9s_mb_2u(sch_1):p3v3_pwrgd_clkgen';
NODE_NAME     R4080 2
 '@S9S_MB_2U_LIB.S9S_MB_2U(SCH_1):PAGE201_I142@PURE_QUANTA.Q_RES(CHIPS)':
 'B': CDS_PINID='B';
NODE_NAME     U247 22
 '@S9S_MB_2U_LIB.S9S_MB_2U(SCH_1):PAGE201_I167@PURE_QUANTA.9FGL0251DKILFT(CHIPS)':
 '^CKPWRGD_PD#': CDS_PINID='\^ckpwrgd_pd#\';
NET_NAME
'P3V3_RTC_AUX'
 '@S9S_MB_2U_LIB.S9S_MB_2U(SCH_1):P3V3_RTC_AUX':
 C_SIGNAL='@s9s_mb_2u_lib.s9s_mb_2u(sch_1):p3v3_rtc_aux',
 CDS_GLOBAL_NET='TRUE';
NODE_NAME     U62 3
 '@S9S_MB_2U_LIB.S9S_MB_2U(SCH_1):PAGE177_I64@PURE_QUANTA.BAS70057F(CHIPS)':
 'C': CDS_PINID='C';
NODE_NAME     C611 1
 '@S9S_MB_2U_LIB.S9S_MB_2U(SCH_1):PAGE177_I65@PURE_QUANTA.Q_CAP(CHIPS)':
 'A': CDS_PINID='A';
NODE_NAME     R1202 1
 '@S9S_MB_2U_LIB.S9S_MB_2U(SCH_1):PAGE177_I70@PURE_QUANTA.Q_RES(CHIPS)':
 'A': CDS_PINID='A';
NODE_NAME     U4 AH15
 '@S9S_MB_2U_LIB.S9S_MB_2U(SCH_1):PAGE178_I11@PURE_QUANTA.EMMITSBURG_REV0P9(CHIPS)':
 'VCCRTC': CDS_PINID='VCCRTC';
NODE_NAME     R2966 1
 '@S9S_MB_2U_LIB.S9S_MB_2U(SCH_1):PAGE174_I96@PURE_QUANTA.Q_RES(CHIPS)':
 'A': CDS_PINID='A';
NODE_NAME     R1340 1
 '@S9S_MB_2U_LIB.S9S_MB_2U(SCH_1):PAGE189_I127@PURE_QUANTA.Q_RES(CHIPS)':
 'A': CDS_PINID='A';
NET_NAME
'P3V_BAT'
 '@S9S_MB_2U_LIB.S9S_MB_2U(SCH_1):P3V_BAT':
 C_SIGNAL='@s9s_mb_2u_lib.s9s_mb_2u(sch_1):p3v_bat';
NODE_NAME     R1203 1
 '@S9S_MB_2U_LIB.S9S_MB_2U(SCH_1):PAGE177_I62@PURE_QUANTA.Q_RES(CHIPS)':
 'A': CDS_PINID='A';
NODE_NAME     BT1 1
 '@S9S_MB_2U_LIB.S9S_MB_2U(SCH_1):PAGE177_I63@PURE_QUANTA.CONN2_AAABAT029Y19(CHIPS)':
 '1': CDS_PINID='\1\';
NET_NAME
'P3V_BAT_R'
 '@S9S_MB_2U_LIB.S9S_MB_2U(SCH_1):P3V_BAT_R':
 C_SIGNAL='@s9s_mb_2u_lib.s9s_mb_2u(sch_1):p3v_bat_r',
 CDS_GLOBAL_NET='TRUE';
NODE_NAME     R1203 2
 '@S9S_MB_2U_LIB.S9S_MB_2U(SCH_1):PAGE177_I62@PURE_QUANTA.Q_RES(CHIPS)':
 'B': CDS_PINID='B';
NODE_NAME     U62 1
 '@S9S_MB_2U_LIB.S9S_MB_2U(SCH_1):PAGE177_I64@PURE_QUANTA.BAS70057F(CHIPS)':
 'B': CDS_PINID='B';
NODE_NAME     R2994 2
 '@S9S_MB_2U_LIB.S9S_MB_2U(SCH_1):PAGE227_I58@PURE_QUANTA.Q_RES(CHIPS)':
 'B': CDS_PINID='B';
NET_NAME
'P3V_BAT_R1'
 '@S9S_MB_2U_LIB.S9S_MB_2U(SCH_1):P3V_BAT_R1':
 C_SIGNAL='@s9s_mb_2u_lib.s9s_mb_2u(sch_1):p3v_bat_r1';
NODE_NAME     R2994 1
 '@S9S_MB_2U_LIB.S9S_MB_2U(SCH_1):PAGE227_I58@PURE_QUANTA.Q_RES(CHIPS)':
 'A': CDS_PINID='A';
NODE_NAME     J41 B41
 '@S9S_MB_2U_LIB.S9S_MB_2U(SCH_1):PAGE227_I173@PURE_QUANTA.SCONN168_ME1016810202011(CHIPS)':
 'GND_B41': CDS_PINID='GND_B41';
NET_NAME
'P5E_CPU0_PE0_RX_DN<0>'
 '@S9S_MB_2U_LIB.S9S_MB_2U(SCH_1):P5E_CPU0_PE0_RX_DN'<0>:
 C_SIGNAL='@s9s_mb_2u_lib.s9s_mb_2u(sch_1):p5e_cpu0_pe0_rx_dn(0)';
NODE_NAME     U2 K10
 '@S9S_MB_2U_LIB.S9S_MB_2U(SCH_1):PAGE29_I37@PURE_QUANTA.SOCKET4677_AZIF0045P001C01CS(CHIPS)':
 'PE0_RX_DN0': CDS_PINID='PE0_RX_DN0';
NODE_NAME     J107 B8
 '@S9S_MB_2U_LIB.S9S_MB_2U(SCH_1):PAGE317_I38@PURE_QUANTA.CONN112_10137002101LF(CHIPS)':
 'B8': CDS_PINID='B8';
NET_NAME
'P5E_CPU0_PE0_RX_DN<10>'
 '@S9S_MB_2U_LIB.S9S_MB_2U(SCH_1):P5E_CPU0_PE0_RX_DN'<10>:
 C_SIGNAL='@s9s_mb_2u_lib.s9s_mb_2u(sch_1):p5e_cpu0_pe0_rx_dn(10)';
NODE_NAME     U2 AK10
 '@S9S_MB_2U_LIB.S9S_MB_2U(SCH_1):PAGE29_I37@PURE_QUANTA.SOCKET4677_AZIF0045P001C01CS(CHIPS)':
 'PE0_RX_DN10': CDS_PINID='PE0_RX_DN10';
NODE_NAME     J108 B6
 '@S9S_MB_2U_LIB.S9S_MB_2U(SCH_1):PAGE320_I76@PURE_QUANTA.CONN112_10137002101LF(CHIPS)':
 'B6': CDS_PINID='B6';
NET_NAME
'P5E_CPU0_PE0_RX_DN<11>'
 '@S9S_MB_2U_LIB.S9S_MB_2U(SCH_1):P5E_CPU0_PE0_RX_DN'<11>:
 C_SIGNAL='@s9s_mb_2u_lib.s9s_mb_2u(sch_1):p5e_cpu0_pe0_rx_dn(11)';
NODE_NAME     U2 AM10
 '@S9S_MB_2U_LIB.S9S_MB_2U(SCH_1):PAGE29_I37@PURE_QUANTA.SOCKET4677_AZIF0045P001C01CS(CHIPS)':
 'PE0_RX_DN11': CDS_PINID='PE0_RX_DN11';
NODE_NAME     J108 D5
 '@S9S_MB_2U_LIB.S9S_MB_2U(SCH_1):PAGE320_I76@PURE_QUANTA.CONN112_10137002101LF(CHIPS)':
 'D5': CDS_PINID='D5';
NET_NAME
'P5E_CPU0_PE0_RX_DN<12>'
 '@S9S_MB_2U_LIB.S9S_MB_2U(SCH_1):P5E_CPU0_PE0_RX_DN'<12>:
 C_SIGNAL='@s9s_mb_2u_lib.s9s_mb_2u(sch_1):p5e_cpu0_pe0_rx_dn(12)';
NODE_NAME     U2 AP10
 '@S9S_MB_2U_LIB.S9S_MB_2U(SCH_1):PAGE29_I37@PURE_QUANTA.SOCKET4677_AZIF0045P001C01CS(CHIPS)':
 'PE0_RX_DN12': CDS_PINID='PE0_RX_DN12';
NODE_NAME     J108 B4
 '@S9S_MB_2U_LIB.S9S_MB_2U(SCH_1):PAGE320_I57@PURE_QUANTA.CONN112_10137002101LF(CHIPS)':
 'B4': CDS_PINID='B4';
NET_NAME
'P5E_CPU0_PE0_RX_DN<13>'
 '@S9S_MB_2U_LIB.S9S_MB_2U(SCH_1):P5E_CPU0_PE0_RX_DN'<13>:
 C_SIGNAL='@s9s_mb_2u_lib.s9s_mb_2u(sch_1):p5e_cpu0_pe0_rx_dn(13)';
NODE_NAME     U2 AU9
 '@S9S_MB_2U_LIB.S9S_MB_2U(SCH_1):PAGE29_I37@PURE_QUANTA.SOCKET4677_AZIF0045P001C01CS(CHIPS)':
 'PE0_RX_DN13': CDS_PINID='PE0_RX_DN13';
NODE_NAME     J108 C3
 '@S9S_MB_2U_LIB.S9S_MB_2U(SCH_1):PAGE320_I57@PURE_QUANTA.CONN112_10137002101LF(CHIPS)':
 'C3': CDS_PINID='C3';
NET_NAME
'P5E_CPU0_PE0_RX_DN<14>'
 '@S9S_MB_2U_LIB.S9S_MB_2U(SCH_1):P5E_CPU0_PE0_RX_DN'<14>:
 C_SIGNAL='@s9s_mb_2u_lib.s9s_mb_2u(sch_1):p5e_cpu0_pe0_rx_dn(14)';
NODE_NAME     U2 AV10
 '@S9S_MB_2U_LIB.S9S_MB_2U(SCH_1):PAGE29_I37@PURE_QUANTA.SOCKET4677_AZIF0045P001C01CS(CHIPS)':
 'PE0_RX_DN14': CDS_PINID='PE0_RX_DN14';
NODE_NAME     J108 B2
 '@S9S_MB_2U_LIB.S9S_MB_2U(SCH_1):PAGE320_I57@PURE_QUANTA.CONN112_10137002101LF(CHIPS)':
 'B2': CDS_PINID='B2';
NET_NAME
'P5E_CPU0_PE0_RX_DN<15>'
 '@S9S_MB_2U_LIB.S9S_MB_2U(SCH_1):P5E_CPU0_PE0_RX_DN'<15>:
 C_SIGNAL='@s9s_mb_2u_lib.s9s_mb_2u(sch_1):p5e_cpu0_pe0_rx_dn(15)';
NODE_NAME     U2 BA9
 '@S9S_MB_2U_LIB.S9S_MB_2U(SCH_1):PAGE29_I37@PURE_QUANTA.SOCKET4677_AZIF0045P001C01CS(CHIPS)':
 'PE0_RX_DN15': CDS_PINID='PE0_RX_DN15';
NODE_NAME     J108 C1
 '@S9S_MB_2U_LIB.S9S_MB_2U(SCH_1):PAGE320_I57@PURE_QUANTA.CONN112_10137002101LF(CHIPS)':
 'C1': CDS_PINID='C1';
NET_NAME
'P5E_CPU0_PE0_RX_DN<1>'
 '@S9S_MB_2U_LIB.S9S_MB_2U(SCH_1):P5E_CPU0_PE0_RX_DN'<1>:
 C_SIGNAL='@s9s_mb_2u_lib.s9s_mb_2u(sch_1):p5e_cpu0_pe0_rx_dn(1)';
NODE_NAME     U2 M10
 '@S9S_MB_2U_LIB.S9S_MB_2U(SCH_1):PAGE29_I37@PURE_QUANTA.SOCKET4677_AZIF0045P001C01CS(CHIPS)':
 'PE0_RX_DN1': CDS_PINID='PE0_RX_DN1';
NODE_NAME     J107 D7
 '@S9S_MB_2U_LIB.S9S_MB_2U(SCH_1):PAGE317_I38@PURE_QUANTA.CONN112_10137002101LF(CHIPS)':
 'D7': CDS_PINID='D7';
NET_NAME
'P5E_CPU0_PE0_RX_DN<2>'
 '@S9S_MB_2U_LIB.S9S_MB_2U(SCH_1):P5E_CPU0_PE0_RX_DN'<2>:
 C_SIGNAL='@s9s_mb_2u_lib.s9s_mb_2u(sch_1):p5e_cpu0_pe0_rx_dn(2)';
NODE_NAME     U2 P10
 '@S9S_MB_2U_LIB.S9S_MB_2U(SCH_1):PAGE29_I37@PURE_QUANTA.SOCKET4677_AZIF0045P001C01CS(CHIPS)':
 'PE0_RX_DN2': CDS_PINID='PE0_RX_DN2';
NODE_NAME     J107 B6
 '@S9S_MB_2U_LIB.S9S_MB_2U(SCH_1):PAGE317_I38@PURE_QUANTA.CONN112_10137002101LF(CHIPS)':
 'B6': CDS_PINID='B6';
NET_NAME
'P5E_CPU0_PE0_RX_DN<3>'
 '@S9S_MB_2U_LIB.S9S_MB_2U(SCH_1):P5E_CPU0_PE0_RX_DN'<3>:
 C_SIGNAL='@s9s_mb_2u_lib.s9s_mb_2u(sch_1):p5e_cpu0_pe0_rx_dn(3)';
NODE_NAME     U2 T10
 '@S9S_MB_2U_LIB.S9S_MB_2U(SCH_1):PAGE29_I37@PURE_QUANTA.SOCKET4677_AZIF0045P001C01CS(CHIPS)':
 'PE0_RX_DN3': CDS_PINID='PE0_RX_DN3';
NODE_NAME     J107 D5
 '@S9S_MB_2U_LIB.S9S_MB_2U(SCH_1):PAGE317_I38@PURE_QUANTA.CONN112_10137002101LF(CHIPS)':
 'D5': CDS_PINID='D5';
NET_NAME
'P5E_CPU0_PE0_RX_DN<4>'
 '@S9S_MB_2U_LIB.S9S_MB_2U(SCH_1):P5E_CPU0_PE0_RX_DN'<4>:
 C_SIGNAL='@s9s_mb_2u_lib.s9s_mb_2u(sch_1):p5e_cpu0_pe0_rx_dn(4)';
NODE_NAME     U2 V10
 '@S9S_MB_2U_LIB.S9S_MB_2U(SCH_1):PAGE29_I37@PURE_QUANTA.SOCKET4677_AZIF0045P001C01CS(CHIPS)':
 'PE0_RX_DN4': CDS_PINID='PE0_RX_DN4';
NODE_NAME     J107 B4
 '@S9S_MB_2U_LIB.S9S_MB_2U(SCH_1):PAGE317_I58@PURE_QUANTA.CONN112_10137002101LF(CHIPS)':
 'B4': CDS_PINID='B4';
NET_NAME
'P5E_CPU0_PE0_RX_DN<5>'
 '@S9S_MB_2U_LIB.S9S_MB_2U(SCH_1):P5E_CPU0_PE0_RX_DN'<5>:
 C_SIGNAL='@s9s_mb_2u_lib.s9s_mb_2u(sch_1):p5e_cpu0_pe0_rx_dn(5)';
NODE_NAME     U2 AA9
 '@S9S_MB_2U_LIB.S9S_MB_2U(SCH_1):PAGE29_I37@PURE_QUANTA.SOCKET4677_AZIF0045P001C01CS(CHIPS)':
 'PE0_RX_DN5': CDS_PINID='PE0_RX_DN5';
NODE_NAME     J107 C3
 '@S9S_MB_2U_LIB.S9S_MB_2U(SCH_1):PAGE317_I58@PURE_QUANTA.CONN112_10137002101LF(CHIPS)':
 'C3': CDS_PINID='C3';
NET_NAME
'P5E_CPU0_PE0_RX_DN<6>'
 '@S9S_MB_2U_LIB.S9S_MB_2U(SCH_1):P5E_CPU0_PE0_RX_DN'<6>:
 C_SIGNAL='@s9s_mb_2u_lib.s9s_mb_2u(sch_1):p5e_cpu0_pe0_rx_dn(6)';
NODE_NAME     U2 AB10
 '@S9S_MB_2U_LIB.S9S_MB_2U(SCH_1):PAGE29_I37@PURE_QUANTA.SOCKET4677_AZIF0045P001C01CS(CHIPS)':
 'PE0_RX_DN6': CDS_PINID='PE0_RX_DN6';
NODE_NAME     J107 B2
 '@S9S_MB_2U_LIB.S9S_MB_2U(SCH_1):PAGE317_I58@PURE_QUANTA.CONN112_10137002101LF(CHIPS)':
 'B2': CDS_PINID='B2';
NET_NAME
'P5E_CPU0_PE0_RX_DN<7>'
 '@S9S_MB_2U_LIB.S9S_MB_2U(SCH_1):P5E_CPU0_PE0_RX_DN'<7>:
 C_SIGNAL='@s9s_mb_2u_lib.s9s_mb_2u(sch_1):p5e_cpu0_pe0_rx_dn(7)';
NODE_NAME     U2 AE9
 '@S9S_MB_2U_LIB.S9S_MB_2U(SCH_1):PAGE29_I37@PURE_QUANTA.SOCKET4677_AZIF0045P001C01CS(CHIPS)':
 'PE0_RX_DN7': CDS_PINID='PE0_RX_DN7';
NODE_NAME     J107 C1
 '@S9S_MB_2U_LIB.S9S_MB_2U(SCH_1):PAGE317_I58@PURE_QUANTA.CONN112_10137002101LF(CHIPS)':
 'C1': CDS_PINID='C1';
NET_NAME
'P5E_CPU0_PE0_RX_DN<8>'
 '@S9S_MB_2U_LIB.S9S_MB_2U(SCH_1):P5E_CPU0_PE0_RX_DN'<8>:
 C_SIGNAL='@s9s_mb_2u_lib.s9s_mb_2u(sch_1):p5e_cpu0_pe0_rx_dn(8)';
NODE_NAME     U2 AF10
 '@S9S_MB_2U_LIB.S9S_MB_2U(SCH_1):PAGE29_I37@PURE_QUANTA.SOCKET4677_AZIF0045P001C01CS(CHIPS)':
 'PE0_RX_DN8': CDS_PINID='PE0_RX_DN8';
NODE_NAME     J108 B8
 '@S9S_MB_2U_LIB.S9S_MB_2U(SCH_1):PAGE320_I76@PURE_QUANTA.CONN112_10137002101LF(CHIPS)':
 'B8': CDS_PINID='B8';
NET_NAME
'P5E_CPU0_PE0_RX_DN<9>'
 '@S9S_MB_2U_LIB.S9S_MB_2U(SCH_1):P5E_CPU0_PE0_RX_DN'<9>:
 C_SIGNAL='@s9s_mb_2u_lib.s9s_mb_2u(sch_1):p5e_cpu0_pe0_rx_dn(9)';
NODE_NAME     U2 AJ9
 '@S9S_MB_2U_LIB.S9S_MB_2U(SCH_1):PAGE29_I37@PURE_QUANTA.SOCKET4677_AZIF0045P001C01CS(CHIPS)':
 'PE0_RX_DN9': CDS_PINID='PE0_RX_DN9';
NODE_NAME     J108 C7
 '@S9S_MB_2U_LIB.S9S_MB_2U(SCH_1):PAGE320_I76@PURE_QUANTA.CONN112_10137002101LF(CHIPS)':
 'C7': CDS_PINID='C7';
NET_NAME
'P5E_CPU0_PE0_RX_DP<0>'
 '@S9S_MB_2U_LIB.S9S_MB_2U(SCH_1):P5E_CPU0_PE0_RX_DP'<0>:
 C_SIGNAL='@s9s_mb_2u_lib.s9s_mb_2u(sch_1):p5e_cpu0_pe0_rx_dp(0)';
NODE_NAME     U2 L11
 '@S9S_MB_2U_LIB.S9S_MB_2U(SCH_1):PAGE29_I37@PURE_QUANTA.SOCKET4677_AZIF0045P001C01CS(CHIPS)':
 'PE0_RX_DP0': CDS_PINID='PE0_RX_DP0';
NODE_NAME     J107 C8
 '@S9S_MB_2U_LIB.S9S_MB_2U(SCH_1):PAGE317_I38@PURE_QUANTA.CONN112_10137002101LF(CHIPS)':
 'C8': CDS_PINID='C8';
NET_NAME
'P5E_CPU0_PE0_RX_DP<10>'
 '@S9S_MB_2U_LIB.S9S_MB_2U(SCH_1):P5E_CPU0_PE0_RX_DP'<10>:
 C_SIGNAL='@s9s_mb_2u_lib.s9s_mb_2u(sch_1):p5e_cpu0_pe0_rx_dp(10)';
NODE_NAME     U2 AL11
 '@S9S_MB_2U_LIB.S9S_MB_2U(SCH_1):PAGE29_I37@PURE_QUANTA.SOCKET4677_AZIF0045P001C01CS(CHIPS)':
 'PE0_RX_DP10': CDS_PINID='PE0_RX_DP10';
NODE_NAME     J108 C6
 '@S9S_MB_2U_LIB.S9S_MB_2U(SCH_1):PAGE320_I76@PURE_QUANTA.CONN112_10137002101LF(CHIPS)':
 'C6': CDS_PINID='C6';
NET_NAME
'P5E_CPU0_PE0_RX_DP<11>'
 '@S9S_MB_2U_LIB.S9S_MB_2U(SCH_1):P5E_CPU0_PE0_RX_DP'<11>:
 C_SIGNAL='@s9s_mb_2u_lib.s9s_mb_2u(sch_1):p5e_cpu0_pe0_rx_dp(11)';
NODE_NAME     U2 AN9
 '@S9S_MB_2U_LIB.S9S_MB_2U(SCH_1):PAGE29_I37@PURE_QUANTA.SOCKET4677_AZIF0045P001C01CS(CHIPS)':
 'PE0_RX_DP11': CDS_PINID='PE0_RX_DP11';
NODE_NAME     J108 C5
 '@S9S_MB_2U_LIB.S9S_MB_2U(SCH_1):PAGE320_I76@PURE_QUANTA.CONN112_10137002101LF(CHIPS)':
 'C5': CDS_PINID='C5';
NET_NAME
'P5E_CPU0_PE0_RX_DP<12>'
 '@S9S_MB_2U_LIB.S9S_MB_2U(SCH_1):P5E_CPU0_PE0_RX_DP'<12>:
 C_SIGNAL='@s9s_mb_2u_lib.s9s_mb_2u(sch_1):p5e_cpu0_pe0_rx_dp(12)';
NODE_NAME     U2 AR11
 '@S9S_MB_2U_LIB.S9S_MB_2U(SCH_1):PAGE29_I37@PURE_QUANTA.SOCKET4677_AZIF0045P001C01CS(CHIPS)':
 'PE0_RX_DP12': CDS_PINID='PE0_RX_DP12';
NODE_NAME     J108 C4
 '@S9S_MB_2U_LIB.S9S_MB_2U(SCH_1):PAGE320_I57@PURE_QUANTA.CONN112_10137002101LF(CHIPS)':
 'C4': CDS_PINID='C4';
NET_NAME
'P5E_CPU0_PE0_RX_DP<13>'
 '@S9S_MB_2U_LIB.S9S_MB_2U(SCH_1):P5E_CPU0_PE0_RX_DP'<13>:
 C_SIGNAL='@s9s_mb_2u_lib.s9s_mb_2u(sch_1):p5e_cpu0_pe0_rx_dp(13)';
NODE_NAME     U2 AT10
 '@S9S_MB_2U_LIB.S9S_MB_2U(SCH_1):PAGE29_I37@PURE_QUANTA.SOCKET4677_AZIF0045P001C01CS(CHIPS)':
 'PE0_RX_DP13': CDS_PINID='PE0_RX_DP13';
NODE_NAME     J108 D3
 '@S9S_MB_2U_LIB.S9S_MB_2U(SCH_1):PAGE320_I57@PURE_QUANTA.CONN112_10137002101LF(CHIPS)':
 'D3': CDS_PINID='D3';
NET_NAME
'P5E_CPU0_PE0_RX_DP<14>'
 '@S9S_MB_2U_LIB.S9S_MB_2U(SCH_1):P5E_CPU0_PE0_RX_DP'<14>:
 C_SIGNAL='@s9s_mb_2u_lib.s9s_mb_2u(sch_1):p5e_cpu0_pe0_rx_dp(14)';
NODE_NAME     U2 AW11
 '@S9S_MB_2U_LIB.S9S_MB_2U(SCH_1):PAGE29_I37@PURE_QUANTA.SOCKET4677_AZIF0045P001C01CS(CHIPS)':
 'PE0_RX_DP14': CDS_PINID='PE0_RX_DP14';
NODE_NAME     J108 C2
 '@S9S_MB_2U_LIB.S9S_MB_2U(SCH_1):PAGE320_I57@PURE_QUANTA.CONN112_10137002101LF(CHIPS)':
 'C2': CDS_PINID='C2';
NET_NAME
'P5E_CPU0_PE0_RX_DP<15>'
 '@S9S_MB_2U_LIB.S9S_MB_2U(SCH_1):P5E_CPU0_PE0_RX_DP'<15>:
 C_SIGNAL='@s9s_mb_2u_lib.s9s_mb_2u(sch_1):p5e_cpu0_pe0_rx_dp(15)';
NODE_NAME     U2 AY10
 '@S9S_MB_2U_LIB.S9S_MB_2U(SCH_1):PAGE29_I37@PURE_QUANTA.SOCKET4677_AZIF0045P001C01CS(CHIPS)':
 'PE0_RX_DP15': CDS_PINID='PE0_RX_DP15';
NODE_NAME     J108 D1
 '@S9S_MB_2U_LIB.S9S_MB_2U(SCH_1):PAGE320_I57@PURE_QUANTA.CONN112_10137002101LF(CHIPS)':
 'D1': CDS_PINID='D1';
NET_NAME
'P5E_CPU0_PE0_RX_DP<1>'
 '@S9S_MB_2U_LIB.S9S_MB_2U(SCH_1):P5E_CPU0_PE0_RX_DP'<1>:
 C_SIGNAL='@s9s_mb_2u_lib.s9s_mb_2u(sch_1):p5e_cpu0_pe0_rx_dp(1)';
NODE_NAME     U2 N9
 '@S9S_MB_2U_LIB.S9S_MB_2U(SCH_1):PAGE29_I37@PURE_QUANTA.SOCKET4677_AZIF0045P001C01CS(CHIPS)':
 'PE0_RX_DP1': CDS_PINID='PE0_RX_DP1';
NODE_NAME     J107 C7
 '@S9S_MB_2U_LIB.S9S_MB_2U(SCH_1):PAGE317_I38@PURE_QUANTA.CONN112_10137002101LF(CHIPS)':
 'C7': CDS_PINID='C7';
NET_NAME
'P5E_CPU0_PE0_RX_DP<2>'
 '@S9S_MB_2U_LIB.S9S_MB_2U(SCH_1):P5E_CPU0_PE0_RX_DP'<2>:
 C_SIGNAL='@s9s_mb_2u_lib.s9s_mb_2u(sch_1):p5e_cpu0_pe0_rx_dp(2)';
NODE_NAME     U2 R11
 '@S9S_MB_2U_LIB.S9S_MB_2U(SCH_1):PAGE29_I37@PURE_QUANTA.SOCKET4677_AZIF0045P001C01CS(CHIPS)':
 'PE0_RX_DP2': CDS_PINID='PE0_RX_DP2';
NODE_NAME     J107 C6
 '@S9S_MB_2U_LIB.S9S_MB_2U(SCH_1):PAGE317_I38@PURE_QUANTA.CONN112_10137002101LF(CHIPS)':
 'C6': CDS_PINID='C6';
NET_NAME
'P5E_CPU0_PE0_RX_DP<3>'
 '@S9S_MB_2U_LIB.S9S_MB_2U(SCH_1):P5E_CPU0_PE0_RX_DP'<3>:
 C_SIGNAL='@s9s_mb_2u_lib.s9s_mb_2u(sch_1):p5e_cpu0_pe0_rx_dp(3)';
NODE_NAME     U2 U9
 '@S9S_MB_2U_LIB.S9S_MB_2U(SCH_1):PAGE29_I37@PURE_QUANTA.SOCKET4677_AZIF0045P001C01CS(CHIPS)':
 'PE0_RX_DP3': CDS_PINID='PE0_RX_DP3';
NODE_NAME     J107 C5
 '@S9S_MB_2U_LIB.S9S_MB_2U(SCH_1):PAGE317_I38@PURE_QUANTA.CONN112_10137002101LF(CHIPS)':
 'C5': CDS_PINID='C5';
NET_NAME
'P5E_CPU0_PE0_RX_DP<4>'
 '@S9S_MB_2U_LIB.S9S_MB_2U(SCH_1):P5E_CPU0_PE0_RX_DP'<4>:
 C_SIGNAL='@s9s_mb_2u_lib.s9s_mb_2u(sch_1):p5e_cpu0_pe0_rx_dp(4)';
NODE_NAME     U2 W11
 '@S9S_MB_2U_LIB.S9S_MB_2U(SCH_1):PAGE29_I37@PURE_QUANTA.SOCKET4677_AZIF0045P001C01CS(CHIPS)':
 'PE0_RX_DP4': CDS_PINID='PE0_RX_DP4';
NODE_NAME     J107 C4
 '@S9S_MB_2U_LIB.S9S_MB_2U(SCH_1):PAGE317_I58@PURE_QUANTA.CONN112_10137002101LF(CHIPS)':
 'C4': CDS_PINID='C4';
NET_NAME
'P5E_CPU0_PE0_RX_DP<5>'
 '@S9S_MB_2U_LIB.S9S_MB_2U(SCH_1):P5E_CPU0_PE0_RX_DP'<5>:
 C_SIGNAL='@s9s_mb_2u_lib.s9s_mb_2u(sch_1):p5e_cpu0_pe0_rx_dp(5)';
NODE_NAME     U2 Y10
 '@S9S_MB_2U_LIB.S9S_MB_2U(SCH_1):PAGE29_I37@PURE_QUANTA.SOCKET4677_AZIF0045P001C01CS(CHIPS)':
 'PE0_RX_DP5': CDS_PINID='PE0_RX_DP5';
NODE_NAME     J107 D3
 '@S9S_MB_2U_LIB.S9S_MB_2U(SCH_1):PAGE317_I58@PURE_QUANTA.CONN112_10137002101LF(CHIPS)':
 'D3': CDS_PINID='D3';
NET_NAME
'P5E_CPU0_PE0_RX_DP<6>'
 '@S9S_MB_2U_LIB.S9S_MB_2U(SCH_1):P5E_CPU0_PE0_RX_DP'<6>:
 C_SIGNAL='@s9s_mb_2u_lib.s9s_mb_2u(sch_1):p5e_cpu0_pe0_rx_dp(6)';
NODE_NAME     U2 AC11
 '@S9S_MB_2U_LIB.S9S_MB_2U(SCH_1):PAGE29_I37@PURE_QUANTA.SOCKET4677_AZIF0045P001C01CS(CHIPS)':
 'PE0_RX_DP6': CDS_PINID='PE0_RX_DP6';
NODE_NAME     J107 C2
 '@S9S_MB_2U_LIB.S9S_MB_2U(SCH_1):PAGE317_I58@PURE_QUANTA.CONN112_10137002101LF(CHIPS)':
 'C2': CDS_PINID='C2';
NET_NAME
'P5E_CPU0_PE0_RX_DP<7>'
 '@S9S_MB_2U_LIB.S9S_MB_2U(SCH_1):P5E_CPU0_PE0_RX_DP'<7>:
 C_SIGNAL='@s9s_mb_2u_lib.s9s_mb_2u(sch_1):p5e_cpu0_pe0_rx_dp(7)';
NODE_NAME     U2 AD10
 '@S9S_MB_2U_LIB.S9S_MB_2U(SCH_1):PAGE29_I37@PURE_QUANTA.SOCKET4677_AZIF0045P001C01CS(CHIPS)':
 'PE0_RX_DP7': CDS_PINID='PE0_RX_DP7';
NODE_NAME     J107 D1
 '@S9S_MB_2U_LIB.S9S_MB_2U(SCH_1):PAGE317_I58@PURE_QUANTA.CONN112_10137002101LF(CHIPS)':
 'D1': CDS_PINID='D1';
NET_NAME
'P5E_CPU0_PE0_RX_DP<8>'
 '@S9S_MB_2U_LIB.S9S_MB_2U(SCH_1):P5E_CPU0_PE0_RX_DP'<8>:
 C_SIGNAL='@s9s_mb_2u_lib.s9s_mb_2u(sch_1):p5e_cpu0_pe0_rx_dp(8)';
NODE_NAME     U2 AG11
 '@S9S_MB_2U_LIB.S9S_MB_2U(SCH_1):PAGE29_I37@PURE_QUANTA.SOCKET4677_AZIF0045P001C01CS(CHIPS)':
 'PE0_RX_DP8': CDS_PINID='PE0_RX_DP8';
NODE_NAME     J108 C8
 '@S9S_MB_2U_LIB.S9S_MB_2U(SCH_1):PAGE320_I76@PURE_QUANTA.CONN112_10137002101LF(CHIPS)':
 'C8': CDS_PINID='C8';
NET_NAME
'P5E_CPU0_PE0_RX_DP<9>'
 '@S9S_MB_2U_LIB.S9S_MB_2U(SCH_1):P5E_CPU0_PE0_RX_DP'<9>:
 C_SIGNAL='@s9s_mb_2u_lib.s9s_mb_2u(sch_1):p5e_cpu0_pe0_rx_dp(9)';
NODE_NAME     U2 AH10
 '@S9S_MB_2U_LIB.S9S_MB_2U(SCH_1):PAGE29_I37@PURE_QUANTA.SOCKET4677_AZIF0045P001C01CS(CHIPS)':
 'PE0_RX_DP9': CDS_PINID='PE0_RX_DP9';
NODE_NAME     J108 D7
 '@S9S_MB_2U_LIB.S9S_MB_2U(SCH_1):PAGE320_I76@PURE_QUANTA.CONN112_10137002101LF(CHIPS)':
 'D7': CDS_PINID='D7';
NET_NAME
'P5E_CPU0_PE0_TX_C_DN<0>'
 '@S9S_MB_2U_LIB.S9S_MB_2U(SCH_1):P5E_CPU0_PE0_TX_C_DN'<0>:
 C_SIGNAL='@s9s_mb_2u_lib.s9s_mb_2u(sch_1):p5e_cpu0_pe0_tx_c_dn(0)';
NODE_NAME     C932 1
 '@S9S_MB_2U_LIB.S9S_MB_2U(SCH_1):PAGE164_I21@PURE_QUANTA.Q_CAP_DIFFBUS(CHIPS)':
 '1': CDS_PINID='\1\';
NODE_NAME     J107 H8
 '@S9S_MB_2U_LIB.S9S_MB_2U(SCH_1):PAGE317_I38@PURE_QUANTA.CONN112_10137002101LF(CHIPS)':
 'H8': CDS_PINID='H8';
NET_NAME
'P5E_CPU0_PE0_TX_C_DN<10>'
 '@S9S_MB_2U_LIB.S9S_MB_2U(SCH_1):P5E_CPU0_PE0_TX_C_DN'<10>:
 C_SIGNAL='@s9s_mb_2u_lib.s9s_mb_2u(sch_1):p5e_cpu0_pe0_tx_c_dn(10)';
NODE_NAME     C912 1
 '@S9S_MB_2U_LIB.S9S_MB_2U(SCH_1):PAGE164_I58@PURE_QUANTA.Q_CAP_DIFFBUS(CHIPS)':
 '1': CDS_PINID='\1\';
NODE_NAME     J108 H6
 '@S9S_MB_2U_LIB.S9S_MB_2U(SCH_1):PAGE320_I76@PURE_QUANTA.CONN112_10137002101LF(CHIPS)':
 'H6': CDS_PINID='H6';
NET_NAME
'P5E_CPU0_PE0_TX_C_DN<11>'
 '@S9S_MB_2U_LIB.S9S_MB_2U(SCH_1):P5E_CPU0_PE0_TX_C_DN'<11>:
 C_SIGNAL='@s9s_mb_2u_lib.s9s_mb_2u(sch_1):p5e_cpu0_pe0_tx_c_dn(11)';
NODE_NAME     C910 1
 '@S9S_MB_2U_LIB.S9S_MB_2U(SCH_1):PAGE164_I60@PURE_QUANTA.Q_CAP_DIFFBUS(CHIPS)':
 '1': CDS_PINID='\1\';
NODE_NAME     J108 I5
 '@S9S_MB_2U_LIB.S9S_MB_2U(SCH_1):PAGE320_I76@PURE_QUANTA.CONN112_10137002101LF(CHIPS)':
 'I5': CDS_PINID='I5';
NET_NAME
'P5E_CPU0_PE0_TX_C_DN<12>'
 '@S9S_MB_2U_LIB.S9S_MB_2U(SCH_1):P5E_CPU0_PE0_TX_C_DN'<12>:
 C_SIGNAL='@s9s_mb_2u_lib.s9s_mb_2u(sch_1):p5e_cpu0_pe0_tx_c_dn(12)';
NODE_NAME     C908 1
 '@S9S_MB_2U_LIB.S9S_MB_2U(SCH_1):PAGE164_I62@PURE_QUANTA.Q_CAP_DIFFBUS(CHIPS)':
 '1': CDS_PINID='\1\';
NODE_NAME     J108 H4
 '@S9S_MB_2U_LIB.S9S_MB_2U(SCH_1):PAGE320_I57@PURE_QUANTA.CONN112_10137002101LF(CHIPS)':
 'H4': CDS_PINID='H4';
NET_NAME
'P5E_CPU0_PE0_TX_C_DN<13>'
 '@S9S_MB_2U_LIB.S9S_MB_2U(SCH_1):P5E_CPU0_PE0_TX_C_DN'<13>:
 C_SIGNAL='@s9s_mb_2u_lib.s9s_mb_2u(sch_1):p5e_cpu0_pe0_tx_c_dn(13)';
NODE_NAME     C906 1
 '@S9S_MB_2U_LIB.S9S_MB_2U(SCH_1):PAGE164_I63@PURE_QUANTA.Q_CAP_DIFFBUS(CHIPS)':
 '1': CDS_PINID='\1\';
NODE_NAME     J108 I3
 '@S9S_MB_2U_LIB.S9S_MB_2U(SCH_1):PAGE320_I57@PURE_QUANTA.CONN112_10137002101LF(CHIPS)':
 'I3': CDS_PINID='I3';
NET_NAME
'P5E_CPU0_PE0_TX_C_DN<14>'
 '@S9S_MB_2U_LIB.S9S_MB_2U(SCH_1):P5E_CPU0_PE0_TX_C_DN'<14>:
 C_SIGNAL='@s9s_mb_2u_lib.s9s_mb_2u(sch_1):p5e_cpu0_pe0_tx_c_dn(14)';
NODE_NAME     C904 1
 '@S9S_MB_2U_LIB.S9S_MB_2U(SCH_1):PAGE164_I66@PURE_QUANTA.Q_CAP_DIFFBUS(CHIPS)':
 '1': CDS_PINID='\1\';
NODE_NAME     J108 H2
 '@S9S_MB_2U_LIB.S9S_MB_2U(SCH_1):PAGE320_I57@PURE_QUANTA.CONN112_10137002101LF(CHIPS)':
 'H2': CDS_PINID='H2';
NET_NAME
'P5E_CPU0_PE0_TX_C_DN<15>'
 '@S9S_MB_2U_LIB.S9S_MB_2U(SCH_1):P5E_CPU0_PE0_TX_C_DN'<15>:
 C_SIGNAL='@s9s_mb_2u_lib.s9s_mb_2u(sch_1):p5e_cpu0_pe0_tx_c_dn(15)';
NODE_NAME     C902 1
 '@S9S_MB_2U_LIB.S9S_MB_2U(SCH_1):PAGE164_I68@PURE_QUANTA.Q_CAP_DIFFBUS(CHIPS)':
 '1': CDS_PINID='\1\';
NODE_NAME     J108 I1
 '@S9S_MB_2U_LIB.S9S_MB_2U(SCH_1):PAGE320_I57@PURE_QUANTA.CONN112_10137002101LF(CHIPS)':
 'I1': CDS_PINID='I1';
NET_NAME
'P5E_CPU0_PE0_TX_C_DN<1>'
 '@S9S_MB_2U_LIB.S9S_MB_2U(SCH_1):P5E_CPU0_PE0_TX_C_DN'<1>:
 C_SIGNAL='@s9s_mb_2u_lib.s9s_mb_2u(sch_1):p5e_cpu0_pe0_tx_c_dn(1)';
NODE_NAME     C930 1
 '@S9S_MB_2U_LIB.S9S_MB_2U(SCH_1):PAGE164_I24@PURE_QUANTA.Q_CAP_DIFFBUS(CHIPS)':
 '1': CDS_PINID='\1\';
NODE_NAME     J107 I7
 '@S9S_MB_2U_LIB.S9S_MB_2U(SCH_1):PAGE317_I38@PURE_QUANTA.CONN112_10137002101LF(CHIPS)':
 'I7': CDS_PINID='I7';
NET_NAME
'P5E_CPU0_PE0_TX_C_DN<2>'
 '@S9S_MB_2U_LIB.S9S_MB_2U(SCH_1):P5E_CPU0_PE0_TX_C_DN'<2>:
 C_SIGNAL='@s9s_mb_2u_lib.s9s_mb_2u(sch_1):p5e_cpu0_pe0_tx_c_dn(2)';
NODE_NAME     C928 1
 '@S9S_MB_2U_LIB.S9S_MB_2U(SCH_1):PAGE164_I25@PURE_QUANTA.Q_CAP_DIFFBUS(CHIPS)':
 '1': CDS_PINID='\1\';
NODE_NAME     J107 H6
 '@S9S_MB_2U_LIB.S9S_MB_2U(SCH_1):PAGE317_I38@PURE_QUANTA.CONN112_10137002101LF(CHIPS)':
 'H6': CDS_PINID='H6';
NET_NAME
'P5E_CPU0_PE0_TX_C_DN<3>'
 '@S9S_MB_2U_LIB.S9S_MB_2U(SCH_1):P5E_CPU0_PE0_TX_C_DN'<3>:
 C_SIGNAL='@s9s_mb_2u_lib.s9s_mb_2u(sch_1):p5e_cpu0_pe0_tx_c_dn(3)';
NODE_NAME     C926 1
 '@S9S_MB_2U_LIB.S9S_MB_2U(SCH_1):PAGE164_I28@PURE_QUANTA.Q_CAP_DIFFBUS(CHIPS)':
 '1': CDS_PINID='\1\';
NODE_NAME     J107 I5
 '@S9S_MB_2U_LIB.S9S_MB_2U(SCH_1):PAGE317_I38@PURE_QUANTA.CONN112_10137002101LF(CHIPS)':
 'I5': CDS_PINID='I5';
NET_NAME
'P5E_CPU0_PE0_TX_C_DN<4>'
 '@S9S_MB_2U_LIB.S9S_MB_2U(SCH_1):P5E_CPU0_PE0_TX_C_DN'<4>:
 C_SIGNAL='@s9s_mb_2u_lib.s9s_mb_2u(sch_1):p5e_cpu0_pe0_tx_c_dn(4)';
NODE_NAME     C924 1
 '@S9S_MB_2U_LIB.S9S_MB_2U(SCH_1):PAGE164_I30@PURE_QUANTA.Q_CAP_DIFFBUS(CHIPS)':
 '1': CDS_PINID='\1\';
NODE_NAME     J107 H4
 '@S9S_MB_2U_LIB.S9S_MB_2U(SCH_1):PAGE317_I58@PURE_QUANTA.CONN112_10137002101LF(CHIPS)':
 'H4': CDS_PINID='H4';
NET_NAME
'P5E_CPU0_PE0_TX_C_DN<5>'
 '@S9S_MB_2U_LIB.S9S_MB_2U(SCH_1):P5E_CPU0_PE0_TX_C_DN'<5>:
 C_SIGNAL='@s9s_mb_2u_lib.s9s_mb_2u(sch_1):p5e_cpu0_pe0_tx_c_dn(5)';
NODE_NAME     C922 1
 '@S9S_MB_2U_LIB.S9S_MB_2U(SCH_1):PAGE164_I32@PURE_QUANTA.Q_CAP_DIFFBUS(CHIPS)':
 '1': CDS_PINID='\1\';
NODE_NAME     J107 I3
 '@S9S_MB_2U_LIB.S9S_MB_2U(SCH_1):PAGE317_I58@PURE_QUANTA.CONN112_10137002101LF(CHIPS)':
 'I3': CDS_PINID='I3';
NET_NAME
'P5E_CPU0_PE0_TX_C_DN<6>'
 '@S9S_MB_2U_LIB.S9S_MB_2U(SCH_1):P5E_CPU0_PE0_TX_C_DN'<6>:
 C_SIGNAL='@s9s_mb_2u_lib.s9s_mb_2u(sch_1):p5e_cpu0_pe0_tx_c_dn(6)';
NODE_NAME     C920 1
 '@S9S_MB_2U_LIB.S9S_MB_2U(SCH_1):PAGE164_I34@PURE_QUANTA.Q_CAP_DIFFBUS(CHIPS)':
 '1': CDS_PINID='\1\';
NODE_NAME     J107 H2
 '@S9S_MB_2U_LIB.S9S_MB_2U(SCH_1):PAGE317_I58@PURE_QUANTA.CONN112_10137002101LF(CHIPS)':
 'H2': CDS_PINID='H2';
NET_NAME
'P5E_CPU0_PE0_TX_C_DN<7>'
 '@S9S_MB_2U_LIB.S9S_MB_2U(SCH_1):P5E_CPU0_PE0_TX_C_DN'<7>:
 C_SIGNAL='@s9s_mb_2u_lib.s9s_mb_2u(sch_1):p5e_cpu0_pe0_tx_c_dn(7)';
NODE_NAME     C918 1
 '@S9S_MB_2U_LIB.S9S_MB_2U(SCH_1):PAGE164_I35@PURE_QUANTA.Q_CAP_DIFFBUS(CHIPS)':
 '1': CDS_PINID='\1\';
NODE_NAME     J107 I1
 '@S9S_MB_2U_LIB.S9S_MB_2U(SCH_1):PAGE317_I58@PURE_QUANTA.CONN112_10137002101LF(CHIPS)':
 'I1': CDS_PINID='I1';
NET_NAME
'P5E_CPU0_PE0_TX_C_DN<8>'
 '@S9S_MB_2U_LIB.S9S_MB_2U(SCH_1):P5E_CPU0_PE0_TX_C_DN'<8>:
 C_SIGNAL='@s9s_mb_2u_lib.s9s_mb_2u(sch_1):p5e_cpu0_pe0_tx_c_dn(8)';
NODE_NAME     C916 1
 '@S9S_MB_2U_LIB.S9S_MB_2U(SCH_1):PAGE164_I53@PURE_QUANTA.Q_CAP_DIFFBUS(CHIPS)':
 '1': CDS_PINID='\1\';
NODE_NAME     J108 H8
 '@S9S_MB_2U_LIB.S9S_MB_2U(SCH_1):PAGE320_I76@PURE_QUANTA.CONN112_10137002101LF(CHIPS)':
 'H8': CDS_PINID='H8';
NET_NAME
'P5E_CPU0_PE0_TX_C_DN<9>'
 '@S9S_MB_2U_LIB.S9S_MB_2U(SCH_1):P5E_CPU0_PE0_TX_C_DN'<9>:
 C_SIGNAL='@s9s_mb_2u_lib.s9s_mb_2u(sch_1):p5e_cpu0_pe0_tx_c_dn(9)';
NODE_NAME     C914 1
 '@S9S_MB_2U_LIB.S9S_MB_2U(SCH_1):PAGE164_I56@PURE_QUANTA.Q_CAP_DIFFBUS(CHIPS)':
 '1': CDS_PINID='\1\';
NODE_NAME     J108 I7
 '@S9S_MB_2U_LIB.S9S_MB_2U(SCH_1):PAGE320_I76@PURE_QUANTA.CONN112_10137002101LF(CHIPS)':
 'I7': CDS_PINID='I7';
NET_NAME
'P5E_CPU0_PE0_TX_C_DP<0>'
 '@S9S_MB_2U_LIB.S9S_MB_2U(SCH_1):P5E_CPU0_PE0_TX_C_DP'<0>:
 C_SIGNAL='@s9s_mb_2u_lib.s9s_mb_2u(sch_1):p5e_cpu0_pe0_tx_c_dp(0)';
NODE_NAME     C933 1
 '@S9S_MB_2U_LIB.S9S_MB_2U(SCH_1):PAGE164_I22@PURE_QUANTA.Q_CAP_DIFFBUS(CHIPS)':
 '1': CDS_PINID='\1\';
NODE_NAME     J107 I8
 '@S9S_MB_2U_LIB.S9S_MB_2U(SCH_1):PAGE317_I38@PURE_QUANTA.CONN112_10137002101LF(CHIPS)':
 'I8': CDS_PINID='I8';
NET_NAME
'P5E_CPU0_PE0_TX_C_DP<10>'
 '@S9S_MB_2U_LIB.S9S_MB_2U(SCH_1):P5E_CPU0_PE0_TX_C_DP'<10>:
 C_SIGNAL='@s9s_mb_2u_lib.s9s_mb_2u(sch_1):p5e_cpu0_pe0_tx_c_dp(10)';
NODE_NAME     C913 1
 '@S9S_MB_2U_LIB.S9S_MB_2U(SCH_1):PAGE164_I57@PURE_QUANTA.Q_CAP_DIFFBUS(CHIPS)':
 '1': CDS_PINID='\1\';
NODE_NAME     J108 I6
 '@S9S_MB_2U_LIB.S9S_MB_2U(SCH_1):PAGE320_I76@PURE_QUANTA.CONN112_10137002101LF(CHIPS)':
 'I6': CDS_PINID='I6';
NET_NAME
'P5E_CPU0_PE0_TX_C_DP<11>'
 '@S9S_MB_2U_LIB.S9S_MB_2U(SCH_1):P5E_CPU0_PE0_TX_C_DP'<11>:
 C_SIGNAL='@s9s_mb_2u_lib.s9s_mb_2u(sch_1):p5e_cpu0_pe0_tx_c_dp(11)';
NODE_NAME     C911 1
 '@S9S_MB_2U_LIB.S9S_MB_2U(SCH_1):PAGE164_I59@PURE_QUANTA.Q_CAP_DIFFBUS(CHIPS)':
 '1': CDS_PINID='\1\';
NODE_NAME     J108 J5
 '@S9S_MB_2U_LIB.S9S_MB_2U(SCH_1):PAGE320_I76@PURE_QUANTA.CONN112_10137002101LF(CHIPS)':
 'J5': CDS_PINID='J5';
NET_NAME
'P5E_CPU0_PE0_TX_C_DP<12>'
 '@S9S_MB_2U_LIB.S9S_MB_2U(SCH_1):P5E_CPU0_PE0_TX_C_DP'<12>:
 C_SIGNAL='@s9s_mb_2u_lib.s9s_mb_2u(sch_1):p5e_cpu0_pe0_tx_c_dp(12)';
NODE_NAME     C909 1
 '@S9S_MB_2U_LIB.S9S_MB_2U(SCH_1):PAGE164_I61@PURE_QUANTA.Q_CAP_DIFFBUS(CHIPS)':
 '1': CDS_PINID='\1\';
NODE_NAME     J108 I4
 '@S9S_MB_2U_LIB.S9S_MB_2U(SCH_1):PAGE320_I57@PURE_QUANTA.CONN112_10137002101LF(CHIPS)':
 'I4': CDS_PINID='I4';
NET_NAME
'P5E_CPU0_PE0_TX_C_DP<13>'
 '@S9S_MB_2U_LIB.S9S_MB_2U(SCH_1):P5E_CPU0_PE0_TX_C_DP'<13>:
 C_SIGNAL='@s9s_mb_2u_lib.s9s_mb_2u(sch_1):p5e_cpu0_pe0_tx_c_dp(13)';
NODE_NAME     C907 1
 '@S9S_MB_2U_LIB.S9S_MB_2U(SCH_1):PAGE164_I64@PURE_QUANTA.Q_CAP_DIFFBUS(CHIPS)':
 '1': CDS_PINID='\1\';
NODE_NAME     J108 J3
 '@S9S_MB_2U_LIB.S9S_MB_2U(SCH_1):PAGE320_I57@PURE_QUANTA.CONN112_10137002101LF(CHIPS)':
 'J3': CDS_PINID='J3';
NET_NAME
'P5E_CPU0_PE0_TX_C_DP<14>'
 '@S9S_MB_2U_LIB.S9S_MB_2U(SCH_1):P5E_CPU0_PE0_TX_C_DP'<14>:
 C_SIGNAL='@s9s_mb_2u_lib.s9s_mb_2u(sch_1):p5e_cpu0_pe0_tx_c_dp(14)';
NODE_NAME     C905 1
 '@S9S_MB_2U_LIB.S9S_MB_2U(SCH_1):PAGE164_I65@PURE_QUANTA.Q_CAP_DIFFBUS(CHIPS)':
 '1': CDS_PINID='\1\';
NODE_NAME     J108 I2
 '@S9S_MB_2U_LIB.S9S_MB_2U(SCH_1):PAGE320_I57@PURE_QUANTA.CONN112_10137002101LF(CHIPS)':
 'I2': CDS_PINID='I2';
NET_NAME
'P5E_CPU0_PE0_TX_C_DP<15>'
 '@S9S_MB_2U_LIB.S9S_MB_2U(SCH_1):P5E_CPU0_PE0_TX_C_DP'<15>:
 C_SIGNAL='@s9s_mb_2u_lib.s9s_mb_2u(sch_1):p5e_cpu0_pe0_tx_c_dp(15)';
NODE_NAME     C903 1
 '@S9S_MB_2U_LIB.S9S_MB_2U(SCH_1):PAGE164_I67@PURE_QUANTA.Q_CAP_DIFFBUS(CHIPS)':
 '1': CDS_PINID='\1\';
NODE_NAME     J108 J1
 '@S9S_MB_2U_LIB.S9S_MB_2U(SCH_1):PAGE320_I57@PURE_QUANTA.CONN112_10137002101LF(CHIPS)':
 'J1': CDS_PINID='J1';
NET_NAME
'P5E_CPU0_PE0_TX_C_DP<1>'
 '@S9S_MB_2U_LIB.S9S_MB_2U(SCH_1):P5E_CPU0_PE0_TX_C_DP'<1>:
 C_SIGNAL='@s9s_mb_2u_lib.s9s_mb_2u(sch_1):p5e_cpu0_pe0_tx_c_dp(1)';
NODE_NAME     C931 1
 '@S9S_MB_2U_LIB.S9S_MB_2U(SCH_1):PAGE164_I23@PURE_QUANTA.Q_CAP_DIFFBUS(CHIPS)':
 '1': CDS_PINID='\1\';
NODE_NAME     J107 J7
 '@S9S_MB_2U_LIB.S9S_MB_2U(SCH_1):PAGE317_I38@PURE_QUANTA.CONN112_10137002101LF(CHIPS)':
 'J7': CDS_PINID='J7';
NET_NAME
'P5E_CPU0_PE0_TX_C_DP<2>'
 '@S9S_MB_2U_LIB.S9S_MB_2U(SCH_1):P5E_CPU0_PE0_TX_C_DP'<2>:
 C_SIGNAL='@s9s_mb_2u_lib.s9s_mb_2u(sch_1):p5e_cpu0_pe0_tx_c_dp(2)';
NODE_NAME     C929 1
 '@S9S_MB_2U_LIB.S9S_MB_2U(SCH_1):PAGE164_I26@PURE_QUANTA.Q_CAP_DIFFBUS(CHIPS)':
 '1': CDS_PINID='\1\';
NODE_NAME     J107 I6
 '@S9S_MB_2U_LIB.S9S_MB_2U(SCH_1):PAGE317_I38@PURE_QUANTA.CONN112_10137002101LF(CHIPS)':
 'I6': CDS_PINID='I6';
NET_NAME
'P5E_CPU0_PE0_TX_C_DP<3>'
 '@S9S_MB_2U_LIB.S9S_MB_2U(SCH_1):P5E_CPU0_PE0_TX_C_DP'<3>:
 C_SIGNAL='@s9s_mb_2u_lib.s9s_mb_2u(sch_1):p5e_cpu0_pe0_tx_c_dp(3)';
NODE_NAME     C927 1
 '@S9S_MB_2U_LIB.S9S_MB_2U(SCH_1):PAGE164_I27@PURE_QUANTA.Q_CAP_DIFFBUS(CHIPS)':
 '1': CDS_PINID='\1\';
NODE_NAME     J107 J5
 '@S9S_MB_2U_LIB.S9S_MB_2U(SCH_1):PAGE317_I38@PURE_QUANTA.CONN112_10137002101LF(CHIPS)':
 'J5': CDS_PINID='J5';
NET_NAME
'P5E_CPU0_PE0_TX_C_DP<4>'
 '@S9S_MB_2U_LIB.S9S_MB_2U(SCH_1):P5E_CPU0_PE0_TX_C_DP'<4>:
 C_SIGNAL='@s9s_mb_2u_lib.s9s_mb_2u(sch_1):p5e_cpu0_pe0_tx_c_dp(4)';
NODE_NAME     C925 1
 '@S9S_MB_2U_LIB.S9S_MB_2U(SCH_1):PAGE164_I29@PURE_QUANTA.Q_CAP_DIFFBUS(CHIPS)':
 '1': CDS_PINID='\1\';
NODE_NAME     J107 I4
 '@S9S_MB_2U_LIB.S9S_MB_2U(SCH_1):PAGE317_I58@PURE_QUANTA.CONN112_10137002101LF(CHIPS)':
 'I4': CDS_PINID='I4';
NET_NAME
'P5E_CPU0_PE0_TX_C_DP<5>'
 '@S9S_MB_2U_LIB.S9S_MB_2U(SCH_1):P5E_CPU0_PE0_TX_C_DP'<5>:
 C_SIGNAL='@s9s_mb_2u_lib.s9s_mb_2u(sch_1):p5e_cpu0_pe0_tx_c_dp(5)';
NODE_NAME     C923 1
 '@S9S_MB_2U_LIB.S9S_MB_2U(SCH_1):PAGE164_I31@PURE_QUANTA.Q_CAP_DIFFBUS(CHIPS)':
 '1': CDS_PINID='\1\';
NODE_NAME     J107 J3
 '@S9S_MB_2U_LIB.S9S_MB_2U(SCH_1):PAGE317_I58@PURE_QUANTA.CONN112_10137002101LF(CHIPS)':
 'J3': CDS_PINID='J3';
NET_NAME
'P5E_CPU0_PE0_TX_C_DP<6>'
 '@S9S_MB_2U_LIB.S9S_MB_2U(SCH_1):P5E_CPU0_PE0_TX_C_DP'<6>:
 C_SIGNAL='@s9s_mb_2u_lib.s9s_mb_2u(sch_1):p5e_cpu0_pe0_tx_c_dp(6)';
NODE_NAME     C921 1
 '@S9S_MB_2U_LIB.S9S_MB_2U(SCH_1):PAGE164_I33@PURE_QUANTA.Q_CAP_DIFFBUS(CHIPS)':
 '1': CDS_PINID='\1\';
NODE_NAME     J107 I2
 '@S9S_MB_2U_LIB.S9S_MB_2U(SCH_1):PAGE317_I58@PURE_QUANTA.CONN112_10137002101LF(CHIPS)':
 'I2': CDS_PINID='I2';
NET_NAME
'P5E_CPU0_PE0_TX_C_DP<7>'
 '@S9S_MB_2U_LIB.S9S_MB_2U(SCH_1):P5E_CPU0_PE0_TX_C_DP'<7>:
 C_SIGNAL='@s9s_mb_2u_lib.s9s_mb_2u(sch_1):p5e_cpu0_pe0_tx_c_dp(7)';
NODE_NAME     C919 1
 '@S9S_MB_2U_LIB.S9S_MB_2U(SCH_1):PAGE164_I36@PURE_QUANTA.Q_CAP_DIFFBUS(CHIPS)':
 '1': CDS_PINID='\1\';
NODE_NAME     J107 J1
 '@S9S_MB_2U_LIB.S9S_MB_2U(SCH_1):PAGE317_I58@PURE_QUANTA.CONN112_10137002101LF(CHIPS)':
 'J1': CDS_PINID='J1';
NET_NAME
'P5E_CPU0_PE0_TX_C_DP<8>'
 '@S9S_MB_2U_LIB.S9S_MB_2U(SCH_1):P5E_CPU0_PE0_TX_C_DP'<8>:
 C_SIGNAL='@s9s_mb_2u_lib.s9s_mb_2u(sch_1):p5e_cpu0_pe0_tx_c_dp(8)';
NODE_NAME     C917 1
 '@S9S_MB_2U_LIB.S9S_MB_2U(SCH_1):PAGE164_I54@PURE_QUANTA.Q_CAP_DIFFBUS(CHIPS)':
 '1': CDS_PINID='\1\';
NODE_NAME     J108 I8
 '@S9S_MB_2U_LIB.S9S_MB_2U(SCH_1):PAGE320_I76@PURE_QUANTA.CONN112_10137002101LF(CHIPS)':
 'I8': CDS_PINID='I8';
NET_NAME
'P5E_CPU0_PE0_TX_C_DP<9>'
 '@S9S_MB_2U_LIB.S9S_MB_2U(SCH_1):P5E_CPU0_PE0_TX_C_DP'<9>:
 C_SIGNAL='@s9s_mb_2u_lib.s9s_mb_2u(sch_1):p5e_cpu0_pe0_tx_c_dp(9)';
NODE_NAME     C915 1
 '@S9S_MB_2U_LIB.S9S_MB_2U(SCH_1):PAGE164_I55@PURE_QUANTA.Q_CAP_DIFFBUS(CHIPS)':
 '1': CDS_PINID='\1\';
NODE_NAME     J108 J7
 '@S9S_MB_2U_LIB.S9S_MB_2U(SCH_1):PAGE320_I76@PURE_QUANTA.CONN112_10137002101LF(CHIPS)':
 'J7': CDS_PINID='J7';
NET_NAME
'P5E_CPU0_PE0_TX_DN<0>'
 '@S9S_MB_2U_LIB.S9S_MB_2U(SCH_1):P5E_CPU0_PE0_TX_DN'<0>:
 C_SIGNAL='@s9s_mb_2u_lib.s9s_mb_2u(sch_1):p5e_cpu0_pe0_tx_dn(0)';
NODE_NAME     U2 N13
 '@S9S_MB_2U_LIB.S9S_MB_2U(SCH_1):PAGE29_I37@PURE_QUANTA.SOCKET4677_AZIF0045P001C01CS(CHIPS)':
 'PE0_TX_DN0': CDS_PINID='PE0_TX_DN0';
NODE_NAME     C932 2
 '@S9S_MB_2U_LIB.S9S_MB_2U(SCH_1):PAGE164_I21@PURE_QUANTA.Q_CAP_DIFFBUS(CHIPS)':
 '2': CDS_PINID='\2\';
NET_NAME
'P5E_CPU0_PE0_TX_DN<10>'
 '@S9S_MB_2U_LIB.S9S_MB_2U(SCH_1):P5E_CPU0_PE0_TX_DN'<10>:
 C_SIGNAL='@s9s_mb_2u_lib.s9s_mb_2u(sch_1):p5e_cpu0_pe0_tx_dn(10)';
NODE_NAME     U2 AN13
 '@S9S_MB_2U_LIB.S9S_MB_2U(SCH_1):PAGE29_I37@PURE_QUANTA.SOCKET4677_AZIF0045P001C01CS(CHIPS)':
 'PE0_TX_DN10': CDS_PINID='PE0_TX_DN10';
NODE_NAME     C912 2
 '@S9S_MB_2U_LIB.S9S_MB_2U(SCH_1):PAGE164_I58@PURE_QUANTA.Q_CAP_DIFFBUS(CHIPS)':
 '2': CDS_PINID='\2\';
NET_NAME
'P5E_CPU0_PE0_TX_DN<11>'
 '@S9S_MB_2U_LIB.S9S_MB_2U(SCH_1):P5E_CPU0_PE0_TX_DN'<11>:
 C_SIGNAL='@s9s_mb_2u_lib.s9s_mb_2u(sch_1):p5e_cpu0_pe0_tx_dn(11)';
NODE_NAME     U2 AP14
 '@S9S_MB_2U_LIB.S9S_MB_2U(SCH_1):PAGE29_I37@PURE_QUANTA.SOCKET4677_AZIF0045P001C01CS(CHIPS)':
 'PE0_TX_DN11': CDS_PINID='PE0_TX_DN11';
NODE_NAME     C910 2
 '@S9S_MB_2U_LIB.S9S_MB_2U(SCH_1):PAGE164_I60@PURE_QUANTA.Q_CAP_DIFFBUS(CHIPS)':
 '2': CDS_PINID='\2\';
NET_NAME
'P5E_CPU0_PE0_TX_DN<12>'
 '@S9S_MB_2U_LIB.S9S_MB_2U(SCH_1):P5E_CPU0_PE0_TX_DN'<12>:
 C_SIGNAL='@s9s_mb_2u_lib.s9s_mb_2u(sch_1):p5e_cpu0_pe0_tx_dn(12)';
NODE_NAME     U2 AU13
 '@S9S_MB_2U_LIB.S9S_MB_2U(SCH_1):PAGE29_I37@PURE_QUANTA.SOCKET4677_AZIF0045P001C01CS(CHIPS)':
 'PE0_TX_DN12': CDS_PINID='PE0_TX_DN12';
NODE_NAME     C908 2
 '@S9S_MB_2U_LIB.S9S_MB_2U(SCH_1):PAGE164_I62@PURE_QUANTA.Q_CAP_DIFFBUS(CHIPS)':
 '2': CDS_PINID='\2\';
NET_NAME
'P5E_CPU0_PE0_TX_DN<13>'
 '@S9S_MB_2U_LIB.S9S_MB_2U(SCH_1):P5E_CPU0_PE0_TX_DN'<13>:
 C_SIGNAL='@s9s_mb_2u_lib.s9s_mb_2u(sch_1):p5e_cpu0_pe0_tx_dn(13)';
NODE_NAME     U2 AV14
 '@S9S_MB_2U_LIB.S9S_MB_2U(SCH_1):PAGE29_I37@PURE_QUANTA.SOCKET4677_AZIF0045P001C01CS(CHIPS)':
 'PE0_TX_DN13': CDS_PINID='PE0_TX_DN13';
NODE_NAME     C906 2
 '@S9S_MB_2U_LIB.S9S_MB_2U(SCH_1):PAGE164_I63@PURE_QUANTA.Q_CAP_DIFFBUS(CHIPS)':
 '2': CDS_PINID='\2\';
NET_NAME
'P5E_CPU0_PE0_TX_DN<14>'
 '@S9S_MB_2U_LIB.S9S_MB_2U(SCH_1):P5E_CPU0_PE0_TX_DN'<14>:
 C_SIGNAL='@s9s_mb_2u_lib.s9s_mb_2u(sch_1):p5e_cpu0_pe0_tx_dn(14)';
NODE_NAME     U2 BA13
 '@S9S_MB_2U_LIB.S9S_MB_2U(SCH_1):PAGE29_I37@PURE_QUANTA.SOCKET4677_AZIF0045P001C01CS(CHIPS)':
 'PE0_TX_DN14': CDS_PINID='PE0_TX_DN14';
NODE_NAME     C904 2
 '@S9S_MB_2U_LIB.S9S_MB_2U(SCH_1):PAGE164_I66@PURE_QUANTA.Q_CAP_DIFFBUS(CHIPS)':
 '2': CDS_PINID='\2\';
NET_NAME
'P5E_CPU0_PE0_TX_DN<15>'
 '@S9S_MB_2U_LIB.S9S_MB_2U(SCH_1):P5E_CPU0_PE0_TX_DN'<15>:
 C_SIGNAL='@s9s_mb_2u_lib.s9s_mb_2u(sch_1):p5e_cpu0_pe0_tx_dn(15)';
NODE_NAME     U2 BB14
 '@S9S_MB_2U_LIB.S9S_MB_2U(SCH_1):PAGE29_I37@PURE_QUANTA.SOCKET4677_AZIF0045P001C01CS(CHIPS)':
 'PE0_TX_DN15': CDS_PINID='PE0_TX_DN15';
NODE_NAME     C902 2
 '@S9S_MB_2U_LIB.S9S_MB_2U(SCH_1):PAGE164_I68@PURE_QUANTA.Q_CAP_DIFFBUS(CHIPS)':
 '2': CDS_PINID='\2\';
NET_NAME
'P5E_CPU0_PE0_TX_DN<1>'
 '@S9S_MB_2U_LIB.S9S_MB_2U(SCH_1):P5E_CPU0_PE0_TX_DN'<1>:
 C_SIGNAL='@s9s_mb_2u_lib.s9s_mb_2u(sch_1):p5e_cpu0_pe0_tx_dn(1)';
NODE_NAME     U2 P14
 '@S9S_MB_2U_LIB.S9S_MB_2U(SCH_1):PAGE29_I37@PURE_QUANTA.SOCKET4677_AZIF0045P001C01CS(CHIPS)':
 'PE0_TX_DN1': CDS_PINID='PE0_TX_DN1';
NODE_NAME     C930 2
 '@S9S_MB_2U_LIB.S9S_MB_2U(SCH_1):PAGE164_I24@PURE_QUANTA.Q_CAP_DIFFBUS(CHIPS)':
 '2': CDS_PINID='\2\';
NET_NAME
'P5E_CPU0_PE0_TX_DN<2>'
 '@S9S_MB_2U_LIB.S9S_MB_2U(SCH_1):P5E_CPU0_PE0_TX_DN'<2>:
 C_SIGNAL='@s9s_mb_2u_lib.s9s_mb_2u(sch_1):p5e_cpu0_pe0_tx_dn(2)';
NODE_NAME     U2 U13
 '@S9S_MB_2U_LIB.S9S_MB_2U(SCH_1):PAGE29_I37@PURE_QUANTA.SOCKET4677_AZIF0045P001C01CS(CHIPS)':
 'PE0_TX_DN2': CDS_PINID='PE0_TX_DN2';
NODE_NAME     C928 2
 '@S9S_MB_2U_LIB.S9S_MB_2U(SCH_1):PAGE164_I25@PURE_QUANTA.Q_CAP_DIFFBUS(CHIPS)':
 '2': CDS_PINID='\2\';
NET_NAME
'P5E_CPU0_PE0_TX_DN<3>'
 '@S9S_MB_2U_LIB.S9S_MB_2U(SCH_1):P5E_CPU0_PE0_TX_DN'<3>:
 C_SIGNAL='@s9s_mb_2u_lib.s9s_mb_2u(sch_1):p5e_cpu0_pe0_tx_dn(3)';
NODE_NAME     U2 V14
 '@S9S_MB_2U_LIB.S9S_MB_2U(SCH_1):PAGE29_I37@PURE_QUANTA.SOCKET4677_AZIF0045P001C01CS(CHIPS)':
 'PE0_TX_DN3': CDS_PINID='PE0_TX_DN3';
NODE_NAME     C926 2
 '@S9S_MB_2U_LIB.S9S_MB_2U(SCH_1):PAGE164_I28@PURE_QUANTA.Q_CAP_DIFFBUS(CHIPS)':
 '2': CDS_PINID='\2\';
NET_NAME
'P5E_CPU0_PE0_TX_DN<4>'
 '@S9S_MB_2U_LIB.S9S_MB_2U(SCH_1):P5E_CPU0_PE0_TX_DN'<4>:
 C_SIGNAL='@s9s_mb_2u_lib.s9s_mb_2u(sch_1):p5e_cpu0_pe0_tx_dn(4)';
NODE_NAME     U2 AA13
 '@S9S_MB_2U_LIB.S9S_MB_2U(SCH_1):PAGE29_I37@PURE_QUANTA.SOCKET4677_AZIF0045P001C01CS(CHIPS)':
 'PE0_TX_DN4': CDS_PINID='PE0_TX_DN4';
NODE_NAME     C924 2
 '@S9S_MB_2U_LIB.S9S_MB_2U(SCH_1):PAGE164_I30@PURE_QUANTA.Q_CAP_DIFFBUS(CHIPS)':
 '2': CDS_PINID='\2\';
NET_NAME
'P5E_CPU0_PE0_TX_DN<5>'
 '@S9S_MB_2U_LIB.S9S_MB_2U(SCH_1):P5E_CPU0_PE0_TX_DN'<5>:
 C_SIGNAL='@s9s_mb_2u_lib.s9s_mb_2u(sch_1):p5e_cpu0_pe0_tx_dn(5)';
NODE_NAME     U2 AB14
 '@S9S_MB_2U_LIB.S9S_MB_2U(SCH_1):PAGE29_I37@PURE_QUANTA.SOCKET4677_AZIF0045P001C01CS(CHIPS)':
 'PE0_TX_DN5': CDS_PINID='PE0_TX_DN5';
NODE_NAME     C922 2
 '@S9S_MB_2U_LIB.S9S_MB_2U(SCH_1):PAGE164_I32@PURE_QUANTA.Q_CAP_DIFFBUS(CHIPS)':
 '2': CDS_PINID='\2\';
NET_NAME
'P5E_CPU0_PE0_TX_DN<6>'
 '@S9S_MB_2U_LIB.S9S_MB_2U(SCH_1):P5E_CPU0_PE0_TX_DN'<6>:
 C_SIGNAL='@s9s_mb_2u_lib.s9s_mb_2u(sch_1):p5e_cpu0_pe0_tx_dn(6)';
NODE_NAME     U2 AE13
 '@S9S_MB_2U_LIB.S9S_MB_2U(SCH_1):PAGE29_I37@PURE_QUANTA.SOCKET4677_AZIF0045P001C01CS(CHIPS)':
 'PE0_TX_DN6': CDS_PINID='PE0_TX_DN6';
NODE_NAME     C920 2
 '@S9S_MB_2U_LIB.S9S_MB_2U(SCH_1):PAGE164_I34@PURE_QUANTA.Q_CAP_DIFFBUS(CHIPS)':
 '2': CDS_PINID='\2\';
NET_NAME
'P5E_CPU0_PE0_TX_DN<7>'
 '@S9S_MB_2U_LIB.S9S_MB_2U(SCH_1):P5E_CPU0_PE0_TX_DN'<7>:
 C_SIGNAL='@s9s_mb_2u_lib.s9s_mb_2u(sch_1):p5e_cpu0_pe0_tx_dn(7)';
NODE_NAME     U2 AF14
 '@S9S_MB_2U_LIB.S9S_MB_2U(SCH_1):PAGE29_I37@PURE_QUANTA.SOCKET4677_AZIF0045P001C01CS(CHIPS)':
 'PE0_TX_DN7': CDS_PINID='PE0_TX_DN7';
NODE_NAME     C918 2
 '@S9S_MB_2U_LIB.S9S_MB_2U(SCH_1):PAGE164_I35@PURE_QUANTA.Q_CAP_DIFFBUS(CHIPS)':
 '2': CDS_PINID='\2\';
NET_NAME
'P5E_CPU0_PE0_TX_DN<8>'
 '@S9S_MB_2U_LIB.S9S_MB_2U(SCH_1):P5E_CPU0_PE0_TX_DN'<8>:
 C_SIGNAL='@s9s_mb_2u_lib.s9s_mb_2u(sch_1):p5e_cpu0_pe0_tx_dn(8)';
NODE_NAME     U2 AJ13
 '@S9S_MB_2U_LIB.S9S_MB_2U(SCH_1):PAGE29_I37@PURE_QUANTA.SOCKET4677_AZIF0045P001C01CS(CHIPS)':
 'PE0_TX_DN8': CDS_PINID='PE0_TX_DN8';
NODE_NAME     C916 2
 '@S9S_MB_2U_LIB.S9S_MB_2U(SCH_1):PAGE164_I53@PURE_QUANTA.Q_CAP_DIFFBUS(CHIPS)':
 '2': CDS_PINID='\2\';
NET_NAME
'P5E_CPU0_PE0_TX_DN<9>'
 '@S9S_MB_2U_LIB.S9S_MB_2U(SCH_1):P5E_CPU0_PE0_TX_DN'<9>:
 C_SIGNAL='@s9s_mb_2u_lib.s9s_mb_2u(sch_1):p5e_cpu0_pe0_tx_dn(9)';
NODE_NAME     U2 AK14
 '@S9S_MB_2U_LIB.S9S_MB_2U(SCH_1):PAGE29_I37@PURE_QUANTA.SOCKET4677_AZIF0045P001C01CS(CHIPS)':
 'PE0_TX_DN9': CDS_PINID='PE0_TX_DN9';
NODE_NAME     C914 2
 '@S9S_MB_2U_LIB.S9S_MB_2U(SCH_1):PAGE164_I56@PURE_QUANTA.Q_CAP_DIFFBUS(CHIPS)':
 '2': CDS_PINID='\2\';
NET_NAME
'P5E_CPU0_PE0_TX_DP<0>'
 '@S9S_MB_2U_LIB.S9S_MB_2U(SCH_1):P5E_CPU0_PE0_TX_DP'<0>:
 C_SIGNAL='@s9s_mb_2u_lib.s9s_mb_2u(sch_1):p5e_cpu0_pe0_tx_dp(0)';
NODE_NAME     U2 M14
 '@S9S_MB_2U_LIB.S9S_MB_2U(SCH_1):PAGE29_I37@PURE_QUANTA.SOCKET4677_AZIF0045P001C01CS(CHIPS)':
 'PE0_TX_DP0': CDS_PINID='PE0_TX_DP0';
NODE_NAME     C933 2
 '@S9S_MB_2U_LIB.S9S_MB_2U(SCH_1):PAGE164_I22@PURE_QUANTA.Q_CAP_DIFFBUS(CHIPS)':
 '2': CDS_PINID='\2\';
NET_NAME
'P5E_CPU0_PE0_TX_DP<10>'
 '@S9S_MB_2U_LIB.S9S_MB_2U(SCH_1):P5E_CPU0_PE0_TX_DP'<10>:
 C_SIGNAL='@s9s_mb_2u_lib.s9s_mb_2u(sch_1):p5e_cpu0_pe0_tx_dp(10)';
NODE_NAME     U2 AM14
 '@S9S_MB_2U_LIB.S9S_MB_2U(SCH_1):PAGE29_I37@PURE_QUANTA.SOCKET4677_AZIF0045P001C01CS(CHIPS)':
 'PE0_TX_DP10': CDS_PINID='PE0_TX_DP10';
NODE_NAME     C913 2
 '@S9S_MB_2U_LIB.S9S_MB_2U(SCH_1):PAGE164_I57@PURE_QUANTA.Q_CAP_DIFFBUS(CHIPS)':
 '2': CDS_PINID='\2\';
NET_NAME
'P5E_CPU0_PE0_TX_DP<11>'
 '@S9S_MB_2U_LIB.S9S_MB_2U(SCH_1):P5E_CPU0_PE0_TX_DP'<11>:
 C_SIGNAL='@s9s_mb_2u_lib.s9s_mb_2u(sch_1):p5e_cpu0_pe0_tx_dp(11)';
NODE_NAME     U2 AR15
 '@S9S_MB_2U_LIB.S9S_MB_2U(SCH_1):PAGE29_I37@PURE_QUANTA.SOCKET4677_AZIF0045P001C01CS(CHIPS)':
 'PE0_TX_DP11': CDS_PINID='PE0_TX_DP11';
NODE_NAME     C911 2
 '@S9S_MB_2U_LIB.S9S_MB_2U(SCH_1):PAGE164_I59@PURE_QUANTA.Q_CAP_DIFFBUS(CHIPS)':
 '2': CDS_PINID='\2\';
NET_NAME
'P5E_CPU0_PE0_TX_DP<12>'
 '@S9S_MB_2U_LIB.S9S_MB_2U(SCH_1):P5E_CPU0_PE0_TX_DP'<12>:
 C_SIGNAL='@s9s_mb_2u_lib.s9s_mb_2u(sch_1):p5e_cpu0_pe0_tx_dp(12)';
NODE_NAME     U2 AT14
 '@S9S_MB_2U_LIB.S9S_MB_2U(SCH_1):PAGE29_I37@PURE_QUANTA.SOCKET4677_AZIF0045P001C01CS(CHIPS)':
 'PE0_TX_DP12': CDS_PINID='PE0_TX_DP12';
NODE_NAME     C909 2
 '@S9S_MB_2U_LIB.S9S_MB_2U(SCH_1):PAGE164_I61@PURE_QUANTA.Q_CAP_DIFFBUS(CHIPS)':
 '2': CDS_PINID='\2\';
NET_NAME
'P5E_CPU0_PE0_TX_DP<13>'
 '@S9S_MB_2U_LIB.S9S_MB_2U(SCH_1):P5E_CPU0_PE0_TX_DP'<13>:
 C_SIGNAL='@s9s_mb_2u_lib.s9s_mb_2u(sch_1):p5e_cpu0_pe0_tx_dp(13)';
NODE_NAME     U2 AW15
 '@S9S_MB_2U_LIB.S9S_MB_2U(SCH_1):PAGE29_I37@PURE_QUANTA.SOCKET4677_AZIF0045P001C01CS(CHIPS)':
 'PE0_TX_DP13': CDS_PINID='PE0_TX_DP13';
NODE_NAME     C907 2
 '@S9S_MB_2U_LIB.S9S_MB_2U(SCH_1):PAGE164_I64@PURE_QUANTA.Q_CAP_DIFFBUS(CHIPS)':
 '2': CDS_PINID='\2\';
NET_NAME
'P5E_CPU0_PE0_TX_DP<14>'
 '@S9S_MB_2U_LIB.S9S_MB_2U(SCH_1):P5E_CPU0_PE0_TX_DP'<14>:
 C_SIGNAL='@s9s_mb_2u_lib.s9s_mb_2u(sch_1):p5e_cpu0_pe0_tx_dp(14)';
NODE_NAME     U2 AY14
 '@S9S_MB_2U_LIB.S9S_MB_2U(SCH_1):PAGE29_I37@PURE_QUANTA.SOCKET4677_AZIF0045P001C01CS(CHIPS)':
 'PE0_TX_DP14': CDS_PINID='PE0_TX_DP14';
NODE_NAME     C905 2
 '@S9S_MB_2U_LIB.S9S_MB_2U(SCH_1):PAGE164_I65@PURE_QUANTA.Q_CAP_DIFFBUS(CHIPS)':
 '2': CDS_PINID='\2\';
NET_NAME
'P5E_CPU0_PE0_TX_DP<15>'
 '@S9S_MB_2U_LIB.S9S_MB_2U(SCH_1):P5E_CPU0_PE0_TX_DP'<15>:
 C_SIGNAL='@s9s_mb_2u_lib.s9s_mb_2u(sch_1):p5e_cpu0_pe0_tx_dp(15)';
NODE_NAME     U2 BC15
 '@S9S_MB_2U_LIB.S9S_MB_2U(SCH_1):PAGE29_I37@PURE_QUANTA.SOCKET4677_AZIF0045P001C01CS(CHIPS)':
 'PE0_TX_DP15': CDS_PINID='PE0_TX_DP15';
NODE_NAME     C903 2
 '@S9S_MB_2U_LIB.S9S_MB_2U(SCH_1):PAGE164_I67@PURE_QUANTA.Q_CAP_DIFFBUS(CHIPS)':
 '2': CDS_PINID='\2\';
NET_NAME
'P5E_CPU0_PE0_TX_DP<1>'
 '@S9S_MB_2U_LIB.S9S_MB_2U(SCH_1):P5E_CPU0_PE0_TX_DP'<1>:
 C_SIGNAL='@s9s_mb_2u_lib.s9s_mb_2u(sch_1):p5e_cpu0_pe0_tx_dp(1)';
NODE_NAME     U2 R15
 '@S9S_MB_2U_LIB.S9S_MB_2U(SCH_1):PAGE29_I37@PURE_QUANTA.SOCKET4677_AZIF0045P001C01CS(CHIPS)':
 'PE0_TX_DP1': CDS_PINID='PE0_TX_DP1';
NODE_NAME     C931 2
 '@S9S_MB_2U_LIB.S9S_MB_2U(SCH_1):PAGE164_I23@PURE_QUANTA.Q_CAP_DIFFBUS(CHIPS)':
 '2': CDS_PINID='\2\';
NET_NAME
'P5E_CPU0_PE0_TX_DP<2>'
 '@S9S_MB_2U_LIB.S9S_MB_2U(SCH_1):P5E_CPU0_PE0_TX_DP'<2>:
 C_SIGNAL='@s9s_mb_2u_lib.s9s_mb_2u(sch_1):p5e_cpu0_pe0_tx_dp(2)';
NODE_NAME     U2 T14
 '@S9S_MB_2U_LIB.S9S_MB_2U(SCH_1):PAGE29_I37@PURE_QUANTA.SOCKET4677_AZIF0045P001C01CS(CHIPS)':
 'PE0_TX_DP2': CDS_PINID='PE0_TX_DP2';
NODE_NAME     C929 2
 '@S9S_MB_2U_LIB.S9S_MB_2U(SCH_1):PAGE164_I26@PURE_QUANTA.Q_CAP_DIFFBUS(CHIPS)':
 '2': CDS_PINID='\2\';
NET_NAME
'P5E_CPU0_PE0_TX_DP<3>'
 '@S9S_MB_2U_LIB.S9S_MB_2U(SCH_1):P5E_CPU0_PE0_TX_DP'<3>:
 C_SIGNAL='@s9s_mb_2u_lib.s9s_mb_2u(sch_1):p5e_cpu0_pe0_tx_dp(3)';
NODE_NAME     U2 W15
 '@S9S_MB_2U_LIB.S9S_MB_2U(SCH_1):PAGE29_I37@PURE_QUANTA.SOCKET4677_AZIF0045P001C01CS(CHIPS)':
 'PE0_TX_DP3': CDS_PINID='PE0_TX_DP3';
NODE_NAME     C927 2
 '@S9S_MB_2U_LIB.S9S_MB_2U(SCH_1):PAGE164_I27@PURE_QUANTA.Q_CAP_DIFFBUS(CHIPS)':
 '2': CDS_PINID='\2\';
NET_NAME
'P5E_CPU0_PE0_TX_DP<4>'
 '@S9S_MB_2U_LIB.S9S_MB_2U(SCH_1):P5E_CPU0_PE0_TX_DP'<4>:
 C_SIGNAL='@s9s_mb_2u_lib.s9s_mb_2u(sch_1):p5e_cpu0_pe0_tx_dp(4)';
NODE_NAME     U2 Y14
 '@S9S_MB_2U_LIB.S9S_MB_2U(SCH_1):PAGE29_I37@PURE_QUANTA.SOCKET4677_AZIF0045P001C01CS(CHIPS)':
 'PE0_TX_DP4': CDS_PINID='PE0_TX_DP4';
NODE_NAME     C925 2
 '@S9S_MB_2U_LIB.S9S_MB_2U(SCH_1):PAGE164_I29@PURE_QUANTA.Q_CAP_DIFFBUS(CHIPS)':
 '2': CDS_PINID='\2\';
NET_NAME
'P5E_CPU0_PE0_TX_DP<5>'
 '@S9S_MB_2U_LIB.S9S_MB_2U(SCH_1):P5E_CPU0_PE0_TX_DP'<5>:
 C_SIGNAL='@s9s_mb_2u_lib.s9s_mb_2u(sch_1):p5e_cpu0_pe0_tx_dp(5)';
NODE_NAME     U2 AC15
 '@S9S_MB_2U_LIB.S9S_MB_2U(SCH_1):PAGE29_I37@PURE_QUANTA.SOCKET4677_AZIF0045P001C01CS(CHIPS)':
 'PE0_TX_DP5': CDS_PINID='PE0_TX_DP5';
NODE_NAME     C923 2
 '@S9S_MB_2U_LIB.S9S_MB_2U(SCH_1):PAGE164_I31@PURE_QUANTA.Q_CAP_DIFFBUS(CHIPS)':
 '2': CDS_PINID='\2\';
NET_NAME
'P5E_CPU0_PE0_TX_DP<6>'
 '@S9S_MB_2U_LIB.S9S_MB_2U(SCH_1):P5E_CPU0_PE0_TX_DP'<6>:
 C_SIGNAL='@s9s_mb_2u_lib.s9s_mb_2u(sch_1):p5e_cpu0_pe0_tx_dp(6)';
NODE_NAME     U2 AD14
 '@S9S_MB_2U_LIB.S9S_MB_2U(SCH_1):PAGE29_I37@PURE_QUANTA.SOCKET4677_AZIF0045P001C01CS(CHIPS)':
 'PE0_TX_DP6': CDS_PINID='PE0_TX_DP6';
NODE_NAME     C921 2
 '@S9S_MB_2U_LIB.S9S_MB_2U(SCH_1):PAGE164_I33@PURE_QUANTA.Q_CAP_DIFFBUS(CHIPS)':
 '2': CDS_PINID='\2\';
NET_NAME
'P5E_CPU0_PE0_TX_DP<7>'
 '@S9S_MB_2U_LIB.S9S_MB_2U(SCH_1):P5E_CPU0_PE0_TX_DP'<7>:
 C_SIGNAL='@s9s_mb_2u_lib.s9s_mb_2u(sch_1):p5e_cpu0_pe0_tx_dp(7)';
NODE_NAME     U2 AG15
 '@S9S_MB_2U_LIB.S9S_MB_2U(SCH_1):PAGE29_I37@PURE_QUANTA.SOCKET4677_AZIF0045P001C01CS(CHIPS)':
 'PE0_TX_DP7': CDS_PINID='PE0_TX_DP7';
NODE_NAME     C919 2
 '@S9S_MB_2U_LIB.S9S_MB_2U(SCH_1):PAGE164_I36@PURE_QUANTA.Q_CAP_DIFFBUS(CHIPS)':
 '2': CDS_PINID='\2\';
NET_NAME
'P5E_CPU0_PE0_TX_DP<8>'
 '@S9S_MB_2U_LIB.S9S_MB_2U(SCH_1):P5E_CPU0_PE0_TX_DP'<8>:
 C_SIGNAL='@s9s_mb_2u_lib.s9s_mb_2u(sch_1):p5e_cpu0_pe0_tx_dp(8)';
NODE_NAME     U2 AH14
 '@S9S_MB_2U_LIB.S9S_MB_2U(SCH_1):PAGE29_I37@PURE_QUANTA.SOCKET4677_AZIF0045P001C01CS(CHIPS)':
 'PE0_TX_DP8': CDS_PINID='PE0_TX_DP8';
NODE_NAME     C917 2
 '@S9S_MB_2U_LIB.S9S_MB_2U(SCH_1):PAGE164_I54@PURE_QUANTA.Q_CAP_DIFFBUS(CHIPS)':
 '2': CDS_PINID='\2\';
NET_NAME
'P5E_CPU0_PE0_TX_DP<9>'
 '@S9S_MB_2U_LIB.S9S_MB_2U(SCH_1):P5E_CPU0_PE0_TX_DP'<9>:
 C_SIGNAL='@s9s_mb_2u_lib.s9s_mb_2u(sch_1):p5e_cpu0_pe0_tx_dp(9)';
NODE_NAME     U2 AL15
 '@S9S_MB_2U_LIB.S9S_MB_2U(SCH_1):PAGE29_I37@PURE_QUANTA.SOCKET4677_AZIF0045P001C01CS(CHIPS)':
 'PE0_TX_DP9': CDS_PINID='PE0_TX_DP9';
NODE_NAME     C915 2
 '@S9S_MB_2U_LIB.S9S_MB_2U(SCH_1):PAGE164_I55@PURE_QUANTA.Q_CAP_DIFFBUS(CHIPS)':
 '2': CDS_PINID='\2\';
NET_NAME
'P5E_CPU0_PE1_RX_DN<0>'
 '@S9S_MB_2U_LIB.S9S_MB_2U(SCH_1):P5E_CPU0_PE1_RX_DN'<0>:
 C_SIGNAL='@s9s_mb_2u_lib.s9s_mb_2u(sch_1):p5e_cpu0_pe1_rx_dn(0)';
NODE_NAME     U2 CP10
 '@S9S_MB_2U_LIB.S9S_MB_2U(SCH_1):PAGE29_I176@PURE_QUANTA.SOCKET4677_AZIF0045P001C01CS(CHIPS)':
 'PE1_RX_DN0': CDS_PINID='PE1_RX_DN0';
NODE_NAME     J37 A17
 '@S9S_MB_2U_LIB.S9S_MB_2U(SCH_1):PAGE150_I199@PURE_QUANTA.SCONN168_ME1016810202011(CHIPS)':
 'PERN0': CDS_PINID='PERN0';
NET_NAME
'P5E_CPU0_PE1_RX_DN<10>'
 '@S9S_MB_2U_LIB.S9S_MB_2U(SCH_1):P5E_CPU0_PE1_RX_DN'<10>:
 C_SIGNAL='@s9s_mb_2u_lib.s9s_mb_2u(sch_1):p5e_cpu0_pe1_rx_dn(10)';
NODE_NAME     U2 BP10
 '@S9S_MB_2U_LIB.S9S_MB_2U(SCH_1):PAGE29_I176@PURE_QUANTA.SOCKET4677_AZIF0045P001C01CS(CHIPS)':
 'PE1_RX_DN10': CDS_PINID='PE1_RX_DN10';
NODE_NAME     J37 A51
 '@S9S_MB_2U_LIB.S9S_MB_2U(SCH_1):PAGE150_I199@PURE_QUANTA.SCONN168_ME1016810202011(CHIPS)':
 'PERP10': CDS_PINID='PERP10';
NET_NAME
'P5E_CPU0_PE1_RX_DN<11>'
 '@S9S_MB_2U_LIB.S9S_MB_2U(SCH_1):P5E_CPU0_PE1_RX_DN'<11>:
 C_SIGNAL='@s9s_mb_2u_lib.s9s_mb_2u(sch_1):p5e_cpu0_pe1_rx_dn(11)';
NODE_NAME     U2 BL11
 '@S9S_MB_2U_LIB.S9S_MB_2U(SCH_1):PAGE29_I176@PURE_QUANTA.SOCKET4677_AZIF0045P001C01CS(CHIPS)':
 'PE1_RX_DN11': CDS_PINID='PE1_RX_DN11';
NODE_NAME     J37 A54
 '@S9S_MB_2U_LIB.S9S_MB_2U(SCH_1):PAGE150_I199@PURE_QUANTA.SCONN168_ME1016810202011(CHIPS)':
 'PERP11': CDS_PINID='PERP11';
NET_NAME
'P5E_CPU0_PE1_RX_DN<12>'
 '@S9S_MB_2U_LIB.S9S_MB_2U(SCH_1):P5E_CPU0_PE1_RX_DN'<12>:
 C_SIGNAL='@s9s_mb_2u_lib.s9s_mb_2u(sch_1):p5e_cpu0_pe1_rx_dn(12)';
NODE_NAME     U2 BK10
 '@S9S_MB_2U_LIB.S9S_MB_2U(SCH_1):PAGE29_I176@PURE_QUANTA.SOCKET4677_AZIF0045P001C01CS(CHIPS)':
 'PE1_RX_DN12': CDS_PINID='PE1_RX_DN12';
NODE_NAME     J37 A57
 '@S9S_MB_2U_LIB.S9S_MB_2U(SCH_1):PAGE150_I199@PURE_QUANTA.SCONN168_ME1016810202011(CHIPS)':
 'PERP12': CDS_PINID='PERP12';
NET_NAME
'P5E_CPU0_PE1_RX_DN<13>'
 '@S9S_MB_2U_LIB.S9S_MB_2U(SCH_1):P5E_CPU0_PE1_RX_DN'<13>:
 C_SIGNAL='@s9s_mb_2u_lib.s9s_mb_2u(sch_1):p5e_cpu0_pe1_rx_dn(13)';
NODE_NAME     U2 BG11
 '@S9S_MB_2U_LIB.S9S_MB_2U(SCH_1):PAGE29_I176@PURE_QUANTA.SOCKET4677_AZIF0045P001C01CS(CHIPS)':
 'PE1_RX_DN13': CDS_PINID='PE1_RX_DN13';
NODE_NAME     J37 A60
 '@S9S_MB_2U_LIB.S9S_MB_2U(SCH_1):PAGE150_I199@PURE_QUANTA.SCONN168_ME1016810202011(CHIPS)':
 'PERP13': CDS_PINID='PERP13';
NET_NAME
'P5E_CPU0_PE1_RX_DN<14>'
 '@S9S_MB_2U_LIB.S9S_MB_2U(SCH_1):P5E_CPU0_PE1_RX_DN'<14>:
 C_SIGNAL='@s9s_mb_2u_lib.s9s_mb_2u(sch_1):p5e_cpu0_pe1_rx_dn(14)';
NODE_NAME     U2 BF10
 '@S9S_MB_2U_LIB.S9S_MB_2U(SCH_1):PAGE29_I176@PURE_QUANTA.SOCKET4677_AZIF0045P001C01CS(CHIPS)':
 'PE1_RX_DN14': CDS_PINID='PE1_RX_DN14';
NODE_NAME     J37 A63
 '@S9S_MB_2U_LIB.S9S_MB_2U(SCH_1):PAGE150_I199@PURE_QUANTA.SCONN168_ME1016810202011(CHIPS)':
 'PERP14': CDS_PINID='PERP14';
NET_NAME
'P5E_CPU0_PE1_RX_DN<15>'
 '@S9S_MB_2U_LIB.S9S_MB_2U(SCH_1):P5E_CPU0_PE1_RX_DN'<15>:
 C_SIGNAL='@s9s_mb_2u_lib.s9s_mb_2u(sch_1):p5e_cpu0_pe1_rx_dn(15)';
NODE_NAME     U2 BC11
 '@S9S_MB_2U_LIB.S9S_MB_2U(SCH_1):PAGE29_I176@PURE_QUANTA.SOCKET4677_AZIF0045P001C01CS(CHIPS)':
 'PE1_RX_DN15': CDS_PINID='PE1_RX_DN15';
NODE_NAME     J37 A66
 '@S9S_MB_2U_LIB.S9S_MB_2U(SCH_1):PAGE150_I199@PURE_QUANTA.SCONN168_ME1016810202011(CHIPS)':
 'PERP15': CDS_PINID='PERP15';
NET_NAME
'P5E_CPU0_PE1_RX_DN<1>'
 '@S9S_MB_2U_LIB.S9S_MB_2U(SCH_1):P5E_CPU0_PE1_RX_DN'<1>:
 C_SIGNAL='@s9s_mb_2u_lib.s9s_mb_2u(sch_1):p5e_cpu0_pe1_rx_dn(1)';
NODE_NAME     U2 CL11
 '@S9S_MB_2U_LIB.S9S_MB_2U(SCH_1):PAGE29_I176@PURE_QUANTA.SOCKET4677_AZIF0045P001C01CS(CHIPS)':
 'PE1_RX_DN1': CDS_PINID='PE1_RX_DN1';
NODE_NAME     J37 A21
 '@S9S_MB_2U_LIB.S9S_MB_2U(SCH_1):PAGE150_I199@PURE_QUANTA.SCONN168_ME1016810202011(CHIPS)':
 'PERP1': CDS_PINID='PERP1';
NET_NAME
'P5E_CPU0_PE1_RX_DN<2>'
 '@S9S_MB_2U_LIB.S9S_MB_2U(SCH_1):P5E_CPU0_PE1_RX_DN'<2>:
 C_SIGNAL='@s9s_mb_2u_lib.s9s_mb_2u(sch_1):p5e_cpu0_pe1_rx_dn(2)';
NODE_NAME     U2 CK10
 '@S9S_MB_2U_LIB.S9S_MB_2U(SCH_1):PAGE29_I176@PURE_QUANTA.SOCKET4677_AZIF0045P001C01CS(CHIPS)':
 'PE1_RX_DN2': CDS_PINID='PE1_RX_DN2';
NODE_NAME     J37 A24
 '@S9S_MB_2U_LIB.S9S_MB_2U(SCH_1):PAGE150_I199@PURE_QUANTA.SCONN168_ME1016810202011(CHIPS)':
 'PERP2': CDS_PINID='PERP2';
NET_NAME
'P5E_CPU0_PE1_RX_DN<3>'
 '@S9S_MB_2U_LIB.S9S_MB_2U(SCH_1):P5E_CPU0_PE1_RX_DN'<3>:
 C_SIGNAL='@s9s_mb_2u_lib.s9s_mb_2u(sch_1):p5e_cpu0_pe1_rx_dn(3)';
NODE_NAME     U2 CG11
 '@S9S_MB_2U_LIB.S9S_MB_2U(SCH_1):PAGE29_I176@PURE_QUANTA.SOCKET4677_AZIF0045P001C01CS(CHIPS)':
 'PE1_RX_DN3': CDS_PINID='PE1_RX_DN3';
NODE_NAME     J37 A27
 '@S9S_MB_2U_LIB.S9S_MB_2U(SCH_1):PAGE150_I199@PURE_QUANTA.SCONN168_ME1016810202011(CHIPS)':
 'PERP3': CDS_PINID='PERP3';
NET_NAME
'P5E_CPU0_PE1_RX_DN<4>'
 '@S9S_MB_2U_LIB.S9S_MB_2U(SCH_1):P5E_CPU0_PE1_RX_DN'<4>:
 C_SIGNAL='@s9s_mb_2u_lib.s9s_mb_2u(sch_1):p5e_cpu0_pe1_rx_dn(4)';
NODE_NAME     U2 CF10
 '@S9S_MB_2U_LIB.S9S_MB_2U(SCH_1):PAGE29_I176@PURE_QUANTA.SOCKET4677_AZIF0045P001C01CS(CHIPS)':
 'PE1_RX_DN4': CDS_PINID='PE1_RX_DN4';
NODE_NAME     J37 A31
 '@S9S_MB_2U_LIB.S9S_MB_2U(SCH_1):PAGE150_I199@PURE_QUANTA.SCONN168_ME1016810202011(CHIPS)':
 'PERP4': CDS_PINID='PERP4';
NET_NAME
'P5E_CPU0_PE1_RX_DN<5>'
 '@S9S_MB_2U_LIB.S9S_MB_2U(SCH_1):P5E_CPU0_PE1_RX_DN'<5>:
 C_SIGNAL='@s9s_mb_2u_lib.s9s_mb_2u(sch_1):p5e_cpu0_pe1_rx_dn(5)';
NODE_NAME     U2 CC11
 '@S9S_MB_2U_LIB.S9S_MB_2U(SCH_1):PAGE29_I176@PURE_QUANTA.SOCKET4677_AZIF0045P001C01CS(CHIPS)':
 'PE1_RX_DN5': CDS_PINID='PE1_RX_DN5';
NODE_NAME     J37 A34
 '@S9S_MB_2U_LIB.S9S_MB_2U(SCH_1):PAGE150_I199@PURE_QUANTA.SCONN168_ME1016810202011(CHIPS)':
 'PERP5': CDS_PINID='PERP5';
NET_NAME
'P5E_CPU0_PE1_RX_DN<6>'
 '@S9S_MB_2U_LIB.S9S_MB_2U(SCH_1):P5E_CPU0_PE1_RX_DN'<6>:
 C_SIGNAL='@s9s_mb_2u_lib.s9s_mb_2u(sch_1):p5e_cpu0_pe1_rx_dn(6)';
NODE_NAME     U2 CB10
 '@S9S_MB_2U_LIB.S9S_MB_2U(SCH_1):PAGE29_I176@PURE_QUANTA.SOCKET4677_AZIF0045P001C01CS(CHIPS)':
 'PE1_RX_DN6': CDS_PINID='PE1_RX_DN6';
NODE_NAME     J37 A37
 '@S9S_MB_2U_LIB.S9S_MB_2U(SCH_1):PAGE150_I199@PURE_QUANTA.SCONN168_ME1016810202011(CHIPS)':
 'PERP6': CDS_PINID='PERP6';
NET_NAME
'P5E_CPU0_PE1_RX_DN<7>'
 '@S9S_MB_2U_LIB.S9S_MB_2U(SCH_1):P5E_CPU0_PE1_RX_DN'<7>:
 C_SIGNAL='@s9s_mb_2u_lib.s9s_mb_2u(sch_1):p5e_cpu0_pe1_rx_dn(7)';
NODE_NAME     U2 BW11
 '@S9S_MB_2U_LIB.S9S_MB_2U(SCH_1):PAGE29_I176@PURE_QUANTA.SOCKET4677_AZIF0045P001C01CS(CHIPS)':
 'PE1_RX_DN7': CDS_PINID='PE1_RX_DN7';
NODE_NAME     J37 A40
 '@S9S_MB_2U_LIB.S9S_MB_2U(SCH_1):PAGE150_I199@PURE_QUANTA.SCONN168_ME1016810202011(CHIPS)':
 'PERP7': CDS_PINID='PERP7';
NET_NAME
'P5E_CPU0_PE1_RX_DN<8>'
 '@S9S_MB_2U_LIB.S9S_MB_2U(SCH_1):P5E_CPU0_PE1_RX_DN'<8>:
 C_SIGNAL='@s9s_mb_2u_lib.s9s_mb_2u(sch_1):p5e_cpu0_pe1_rx_dn(8)';
NODE_NAME     U2 BV10
 '@S9S_MB_2U_LIB.S9S_MB_2U(SCH_1):PAGE29_I176@PURE_QUANTA.SOCKET4677_AZIF0045P001C01CS(CHIPS)':
 'PE1_RX_DN8': CDS_PINID='PE1_RX_DN8';
NODE_NAME     J37 A45
 '@S9S_MB_2U_LIB.S9S_MB_2U(SCH_1):PAGE150_I199@PURE_QUANTA.SCONN168_ME1016810202011(CHIPS)':
 'PERP8': CDS_PINID='PERP8';
NET_NAME
'P5E_CPU0_PE1_RX_DN<9>'
 '@S9S_MB_2U_LIB.S9S_MB_2U(SCH_1):P5E_CPU0_PE1_RX_DN'<9>:
 C_SIGNAL='@s9s_mb_2u_lib.s9s_mb_2u(sch_1):p5e_cpu0_pe1_rx_dn(9)';
NODE_NAME     U2 BR11
 '@S9S_MB_2U_LIB.S9S_MB_2U(SCH_1):PAGE29_I176@PURE_QUANTA.SOCKET4677_AZIF0045P001C01CS(CHIPS)':
 'PE1_RX_DN9': CDS_PINID='PE1_RX_DN9';
NODE_NAME     J37 A48
 '@S9S_MB_2U_LIB.S9S_MB_2U(SCH_1):PAGE150_I199@PURE_QUANTA.SCONN168_ME1016810202011(CHIPS)':
 'PERP9': CDS_PINID='PERP9';
NET_NAME
'P5E_CPU0_PE1_RX_DP<0>'
 '@S9S_MB_2U_LIB.S9S_MB_2U(SCH_1):P5E_CPU0_PE1_RX_DP'<0>:
 C_SIGNAL='@s9s_mb_2u_lib.s9s_mb_2u(sch_1):p5e_cpu0_pe1_rx_dp(0)';
NODE_NAME     U2 CN9
 '@S9S_MB_2U_LIB.S9S_MB_2U(SCH_1):PAGE29_I176@PURE_QUANTA.SOCKET4677_AZIF0045P001C01CS(CHIPS)':
 'PE1_RX_DP0': CDS_PINID='PE1_RX_DP0';
NODE_NAME     J37 A18
 '@S9S_MB_2U_LIB.S9S_MB_2U(SCH_1):PAGE150_I199@PURE_QUANTA.SCONN168_ME1016810202011(CHIPS)':
 'PERP0': CDS_PINID='PERP0';
NET_NAME
'P5E_CPU0_PE1_RX_DP<10>'
 '@S9S_MB_2U_LIB.S9S_MB_2U(SCH_1):P5E_CPU0_PE1_RX_DP'<10>:
 C_SIGNAL='@s9s_mb_2u_lib.s9s_mb_2u(sch_1):p5e_cpu0_pe1_rx_dp(10)';
NODE_NAME     U2 BN9
 '@S9S_MB_2U_LIB.S9S_MB_2U(SCH_1):PAGE29_I176@PURE_QUANTA.SOCKET4677_AZIF0045P001C01CS(CHIPS)':
 'PE1_RX_DP10': CDS_PINID='PE1_RX_DP10';
NODE_NAME     J37 A50
 '@S9S_MB_2U_LIB.S9S_MB_2U(SCH_1):PAGE150_I199@PURE_QUANTA.SCONN168_ME1016810202011(CHIPS)':
 'PERN10': CDS_PINID='PERN10';
NET_NAME
'P5E_CPU0_PE1_RX_DP<11>'
 '@S9S_MB_2U_LIB.S9S_MB_2U(SCH_1):P5E_CPU0_PE1_RX_DP'<11>:
 C_SIGNAL='@s9s_mb_2u_lib.s9s_mb_2u(sch_1):p5e_cpu0_pe1_rx_dp(11)';
NODE_NAME     U2 BM10
 '@S9S_MB_2U_LIB.S9S_MB_2U(SCH_1):PAGE29_I176@PURE_QUANTA.SOCKET4677_AZIF0045P001C01CS(CHIPS)':
 'PE1_RX_DP11': CDS_PINID='PE1_RX_DP11';
NODE_NAME     J37 A53
 '@S9S_MB_2U_LIB.S9S_MB_2U(SCH_1):PAGE150_I199@PURE_QUANTA.SCONN168_ME1016810202011(CHIPS)':
 'PERN11': CDS_PINID='PERN11';
NET_NAME
'P5E_CPU0_PE1_RX_DP<12>'
 '@S9S_MB_2U_LIB.S9S_MB_2U(SCH_1):P5E_CPU0_PE1_RX_DP'<12>:
 C_SIGNAL='@s9s_mb_2u_lib.s9s_mb_2u(sch_1):p5e_cpu0_pe1_rx_dp(12)';
NODE_NAME     U2 BJ9
 '@S9S_MB_2U_LIB.S9S_MB_2U(SCH_1):PAGE29_I176@PURE_QUANTA.SOCKET4677_AZIF0045P001C01CS(CHIPS)':
 'PE1_RX_DP12': CDS_PINID='PE1_RX_DP12';
NODE_NAME     J37 A56
 '@S9S_MB_2U_LIB.S9S_MB_2U(SCH_1):PAGE150_I199@PURE_QUANTA.SCONN168_ME1016810202011(CHIPS)':
 'PERN12': CDS_PINID='PERN12';
NET_NAME
'P5E_CPU0_PE1_RX_DP<13>'
 '@S9S_MB_2U_LIB.S9S_MB_2U(SCH_1):P5E_CPU0_PE1_RX_DP'<13>:
 C_SIGNAL='@s9s_mb_2u_lib.s9s_mb_2u(sch_1):p5e_cpu0_pe1_rx_dp(13)';
NODE_NAME     U2 BH10
 '@S9S_MB_2U_LIB.S9S_MB_2U(SCH_1):PAGE29_I176@PURE_QUANTA.SOCKET4677_AZIF0045P001C01CS(CHIPS)':
 'PE1_RX_DP13': CDS_PINID='PE1_RX_DP13';
NODE_NAME     J37 A59
 '@S9S_MB_2U_LIB.S9S_MB_2U(SCH_1):PAGE150_I199@PURE_QUANTA.SCONN168_ME1016810202011(CHIPS)':
 'PERN13': CDS_PINID='PERN13';
NET_NAME
'P5E_CPU0_PE1_RX_DP<14>'
 '@S9S_MB_2U_LIB.S9S_MB_2U(SCH_1):P5E_CPU0_PE1_RX_DP'<14>:
 C_SIGNAL='@s9s_mb_2u_lib.s9s_mb_2u(sch_1):p5e_cpu0_pe1_rx_dp(14)';
NODE_NAME     U2 BE9
 '@S9S_MB_2U_LIB.S9S_MB_2U(SCH_1):PAGE29_I176@PURE_QUANTA.SOCKET4677_AZIF0045P001C01CS(CHIPS)':
 'PE1_RX_DP14': CDS_PINID='PE1_RX_DP14';
NODE_NAME     J37 A62
 '@S9S_MB_2U_LIB.S9S_MB_2U(SCH_1):PAGE150_I199@PURE_QUANTA.SCONN168_ME1016810202011(CHIPS)':
 'PERN14': CDS_PINID='PERN14';
NET_NAME
'P5E_CPU0_PE1_RX_DP<15>'
 '@S9S_MB_2U_LIB.S9S_MB_2U(SCH_1):P5E_CPU0_PE1_RX_DP'<15>:
 C_SIGNAL='@s9s_mb_2u_lib.s9s_mb_2u(sch_1):p5e_cpu0_pe1_rx_dp(15)';
NODE_NAME     U2 BD10
 '@S9S_MB_2U_LIB.S9S_MB_2U(SCH_1):PAGE29_I176@PURE_QUANTA.SOCKET4677_AZIF0045P001C01CS(CHIPS)':
 'PE1_RX_DP15': CDS_PINID='PE1_RX_DP15';
NODE_NAME     J37 A65
 '@S9S_MB_2U_LIB.S9S_MB_2U(SCH_1):PAGE150_I199@PURE_QUANTA.SCONN168_ME1016810202011(CHIPS)':
 'PERN15': CDS_PINID='PERN15';
NET_NAME
'P5E_CPU0_PE1_RX_DP<1>'
 '@S9S_MB_2U_LIB.S9S_MB_2U(SCH_1):P5E_CPU0_PE1_RX_DP'<1>:
 C_SIGNAL='@s9s_mb_2u_lib.s9s_mb_2u(sch_1):p5e_cpu0_pe1_rx_dp(1)';
NODE_NAME     U2 CM10
 '@S9S_MB_2U_LIB.S9S_MB_2U(SCH_1):PAGE29_I176@PURE_QUANTA.SOCKET4677_AZIF0045P001C01CS(CHIPS)':
 'PE1_RX_DP1': CDS_PINID='PE1_RX_DP1';
NODE_NAME     J37 A20
 '@S9S_MB_2U_LIB.S9S_MB_2U(SCH_1):PAGE150_I199@PURE_QUANTA.SCONN168_ME1016810202011(CHIPS)':
 'PERN1': CDS_PINID='PERN1';
NET_NAME
'P5E_CPU0_PE1_RX_DP<2>'
 '@S9S_MB_2U_LIB.S9S_MB_2U(SCH_1):P5E_CPU0_PE1_RX_DP'<2>:
 C_SIGNAL='@s9s_mb_2u_lib.s9s_mb_2u(sch_1):p5e_cpu0_pe1_rx_dp(2)';
NODE_NAME     U2 CJ9
 '@S9S_MB_2U_LIB.S9S_MB_2U(SCH_1):PAGE29_I176@PURE_QUANTA.SOCKET4677_AZIF0045P001C01CS(CHIPS)':
 'PE1_RX_DP2': CDS_PINID='PE1_RX_DP2';
NODE_NAME     J37 A23
 '@S9S_MB_2U_LIB.S9S_MB_2U(SCH_1):PAGE150_I199@PURE_QUANTA.SCONN168_ME1016810202011(CHIPS)':
 'PERN2': CDS_PINID='PERN2';
NET_NAME
'P5E_CPU0_PE1_RX_DP<3>'
 '@S9S_MB_2U_LIB.S9S_MB_2U(SCH_1):P5E_CPU0_PE1_RX_DP'<3>:
 C_SIGNAL='@s9s_mb_2u_lib.s9s_mb_2u(sch_1):p5e_cpu0_pe1_rx_dp(3)';
NODE_NAME     U2 CH10
 '@S9S_MB_2U_LIB.S9S_MB_2U(SCH_1):PAGE29_I176@PURE_QUANTA.SOCKET4677_AZIF0045P001C01CS(CHIPS)':
 'PE1_RX_DP3': CDS_PINID='PE1_RX_DP3';
NODE_NAME     J37 A26
 '@S9S_MB_2U_LIB.S9S_MB_2U(SCH_1):PAGE150_I199@PURE_QUANTA.SCONN168_ME1016810202011(CHIPS)':
 'PERN3': CDS_PINID='PERN3';
NET_NAME
'P5E_CPU0_PE1_RX_DP<4>'
 '@S9S_MB_2U_LIB.S9S_MB_2U(SCH_1):P5E_CPU0_PE1_RX_DP'<4>:
 C_SIGNAL='@s9s_mb_2u_lib.s9s_mb_2u(sch_1):p5e_cpu0_pe1_rx_dp(4)';
NODE_NAME     U2 CE9
 '@S9S_MB_2U_LIB.S9S_MB_2U(SCH_1):PAGE29_I176@PURE_QUANTA.SOCKET4677_AZIF0045P001C01CS(CHIPS)':
 'PE1_RX_DP4': CDS_PINID='PE1_RX_DP4';
NODE_NAME     J37 A30
 '@S9S_MB_2U_LIB.S9S_MB_2U(SCH_1):PAGE150_I199@PURE_QUANTA.SCONN168_ME1016810202011(CHIPS)':
 'PERN4': CDS_PINID='PERN4';
NET_NAME
'P5E_CPU0_PE1_RX_DP<5>'
 '@S9S_MB_2U_LIB.S9S_MB_2U(SCH_1):P5E_CPU0_PE1_RX_DP'<5>:
 C_SIGNAL='@s9s_mb_2u_lib.s9s_mb_2u(sch_1):p5e_cpu0_pe1_rx_dp(5)';
NODE_NAME     U2 CD10
 '@S9S_MB_2U_LIB.S9S_MB_2U(SCH_1):PAGE29_I176@PURE_QUANTA.SOCKET4677_AZIF0045P001C01CS(CHIPS)':
 'PE1_RX_DP5': CDS_PINID='PE1_RX_DP5';
NODE_NAME     J37 A33
 '@S9S_MB_2U_LIB.S9S_MB_2U(SCH_1):PAGE150_I199@PURE_QUANTA.SCONN168_ME1016810202011(CHIPS)':
 'PERN5': CDS_PINID='PERN5';
NET_NAME
'P5E_CPU0_PE1_RX_DP<6>'
 '@S9S_MB_2U_LIB.S9S_MB_2U(SCH_1):P5E_CPU0_PE1_RX_DP'<6>:
 C_SIGNAL='@s9s_mb_2u_lib.s9s_mb_2u(sch_1):p5e_cpu0_pe1_rx_dp(6)';
NODE_NAME     U2 CA9
 '@S9S_MB_2U_LIB.S9S_MB_2U(SCH_1):PAGE29_I176@PURE_QUANTA.SOCKET4677_AZIF0045P001C01CS(CHIPS)':
 'PE1_RX_DP6': CDS_PINID='PE1_RX_DP6';
NODE_NAME     J37 A36
 '@S9S_MB_2U_LIB.S9S_MB_2U(SCH_1):PAGE150_I199@PURE_QUANTA.SCONN168_ME1016810202011(CHIPS)':
 'PERN6': CDS_PINID='PERN6';
NET_NAME
'P5E_CPU0_PE1_RX_DP<7>'
 '@S9S_MB_2U_LIB.S9S_MB_2U(SCH_1):P5E_CPU0_PE1_RX_DP'<7>:
 C_SIGNAL='@s9s_mb_2u_lib.s9s_mb_2u(sch_1):p5e_cpu0_pe1_rx_dp(7)';
NODE_NAME     U2 BY10
 '@S9S_MB_2U_LIB.S9S_MB_2U(SCH_1):PAGE29_I176@PURE_QUANTA.SOCKET4677_AZIF0045P001C01CS(CHIPS)':
 'PE1_RX_DP7': CDS_PINID='PE1_RX_DP7';
NODE_NAME     J37 A39
 '@S9S_MB_2U_LIB.S9S_MB_2U(SCH_1):PAGE150_I199@PURE_QUANTA.SCONN168_ME1016810202011(CHIPS)':
 'PERN7': CDS_PINID='PERN7';
NET_NAME
'P5E_CPU0_PE1_RX_DP<8>'
 '@S9S_MB_2U_LIB.S9S_MB_2U(SCH_1):P5E_CPU0_PE1_RX_DP'<8>:
 C_SIGNAL='@s9s_mb_2u_lib.s9s_mb_2u(sch_1):p5e_cpu0_pe1_rx_dp(8)';
NODE_NAME     U2 BU9
 '@S9S_MB_2U_LIB.S9S_MB_2U(SCH_1):PAGE29_I176@PURE_QUANTA.SOCKET4677_AZIF0045P001C01CS(CHIPS)':
 'PE1_RX_DP8': CDS_PINID='PE1_RX_DP8';
NODE_NAME     J37 A44
 '@S9S_MB_2U_LIB.S9S_MB_2U(SCH_1):PAGE150_I199@PURE_QUANTA.SCONN168_ME1016810202011(CHIPS)':
 'PERN8': CDS_PINID='PERN8';
NET_NAME
'P5E_CPU0_PE1_RX_DP<9>'
 '@S9S_MB_2U_LIB.S9S_MB_2U(SCH_1):P5E_CPU0_PE1_RX_DP'<9>:
 C_SIGNAL='@s9s_mb_2u_lib.s9s_mb_2u(sch_1):p5e_cpu0_pe1_rx_dp(9)';
NODE_NAME     U2 BT10
 '@S9S_MB_2U_LIB.S9S_MB_2U(SCH_1):PAGE29_I176@PURE_QUANTA.SOCKET4677_AZIF0045P001C01CS(CHIPS)':
 'PE1_RX_DP9': CDS_PINID='PE1_RX_DP9';
NODE_NAME     J37 A47
 '@S9S_MB_2U_LIB.S9S_MB_2U(SCH_1):PAGE150_I199@PURE_QUANTA.SCONN168_ME1016810202011(CHIPS)':
 'PERN9': CDS_PINID='PERN9';
NET_NAME
'P5E_CPU0_PE1_TX_C_DN<0>'
 '@S9S_MB_2U_LIB.S9S_MB_2U(SCH_1):P5E_CPU0_PE1_TX_C_DN'<0>:
 C_SIGNAL='@s9s_mb_2u_lib.s9s_mb_2u(sch_1):p5e_cpu0_pe1_tx_c_dn(0)';
NODE_NAME     C868 1
 '@S9S_MB_2U_LIB.S9S_MB_2U(SCH_1):PAGE165_I22@PURE_QUANTA.Q_CAP_DIFFBUS(CHIPS)':
 '1': CDS_PINID='\1\';
NODE_NAME     J37 B17
 '@S9S_MB_2U_LIB.S9S_MB_2U(SCH_1):PAGE150_I199@PURE_QUANTA.SCONN168_ME1016810202011(CHIPS)':
 'PETN0': CDS_PINID='PETN0';
NET_NAME
'P5E_CPU0_PE1_TX_C_DN<10>'
 '@S9S_MB_2U_LIB.S9S_MB_2U(SCH_1):P5E_CPU0_PE1_TX_C_DN'<10>:
 C_SIGNAL='@s9s_mb_2u_lib.s9s_mb_2u(sch_1):p5e_cpu0_pe1_tx_c_dn(10)';
NODE_NAME     C848 1
 '@S9S_MB_2U_LIB.S9S_MB_2U(SCH_1):PAGE165_I66@PURE_QUANTA.Q_CAP_DIFFBUS(CHIPS)':
 '1': CDS_PINID='\1\';
NODE_NAME     J37 B51
 '@S9S_MB_2U_LIB.S9S_MB_2U(SCH_1):PAGE150_I199@PURE_QUANTA.SCONN168_ME1016810202011(CHIPS)':
 'PETP10': CDS_PINID='PETP10';
NET_NAME
'P5E_CPU0_PE1_TX_C_DN<11>'
 '@S9S_MB_2U_LIB.S9S_MB_2U(SCH_1):P5E_CPU0_PE1_TX_C_DN'<11>:
 C_SIGNAL='@s9s_mb_2u_lib.s9s_mb_2u(sch_1):p5e_cpu0_pe1_tx_c_dn(11)';
NODE_NAME     C846 1
 '@S9S_MB_2U_LIB.S9S_MB_2U(SCH_1):PAGE165_I68@PURE_QUANTA.Q_CAP_DIFFBUS(CHIPS)':
 '1': CDS_PINID='\1\';
NODE_NAME     J37 B53
 '@S9S_MB_2U_LIB.S9S_MB_2U(SCH_1):PAGE150_I199@PURE_QUANTA.SCONN168_ME1016810202011(CHIPS)':
 'PETN11': CDS_PINID='PETN11';
NET_NAME
'P5E_CPU0_PE1_TX_C_DN<12>'
 '@S9S_MB_2U_LIB.S9S_MB_2U(SCH_1):P5E_CPU0_PE1_TX_C_DN'<12>:
 C_SIGNAL='@s9s_mb_2u_lib.s9s_mb_2u(sch_1):p5e_cpu0_pe1_tx_c_dn(12)';
NODE_NAME     C844 1
 '@S9S_MB_2U_LIB.S9S_MB_2U(SCH_1):PAGE165_I70@PURE_QUANTA.Q_CAP_DIFFBUS(CHIPS)':
 '1': CDS_PINID='\1\';
NODE_NAME     J37 B57
 '@S9S_MB_2U_LIB.S9S_MB_2U(SCH_1):PAGE150_I199@PURE_QUANTA.SCONN168_ME1016810202011(CHIPS)':
 'PETP12': CDS_PINID='PETP12';
NET_NAME
'P5E_CPU0_PE1_TX_C_DN<13>'
 '@S9S_MB_2U_LIB.S9S_MB_2U(SCH_1):P5E_CPU0_PE1_TX_C_DN'<13>:
 C_SIGNAL='@s9s_mb_2u_lib.s9s_mb_2u(sch_1):p5e_cpu0_pe1_tx_c_dn(13)';
NODE_NAME     C842 1
 '@S9S_MB_2U_LIB.S9S_MB_2U(SCH_1):PAGE165_I76@PURE_QUANTA.Q_CAP_DIFFBUS(CHIPS)':
 '1': CDS_PINID='\1\';
NODE_NAME     J37 B59
 '@S9S_MB_2U_LIB.S9S_MB_2U(SCH_1):PAGE150_I199@PURE_QUANTA.SCONN168_ME1016810202011(CHIPS)':
 'PETN13': CDS_PINID='PETN13';
NET_NAME
'P5E_CPU0_PE1_TX_C_DN<14>'
 '@S9S_MB_2U_LIB.S9S_MB_2U(SCH_1):P5E_CPU0_PE1_TX_C_DN'<14>:
 C_SIGNAL='@s9s_mb_2u_lib.s9s_mb_2u(sch_1):p5e_cpu0_pe1_tx_c_dn(14)';
NODE_NAME     C840 1
 '@S9S_MB_2U_LIB.S9S_MB_2U(SCH_1):PAGE165_I79@PURE_QUANTA.Q_CAP_DIFFBUS(CHIPS)':
 '1': CDS_PINID='\1\';
NODE_NAME     J37 B63
 '@S9S_MB_2U_LIB.S9S_MB_2U(SCH_1):PAGE150_I199@PURE_QUANTA.SCONN168_ME1016810202011(CHIPS)':
 'PETP14': CDS_PINID='PETP14';
NET_NAME
'P5E_CPU0_PE1_TX_C_DN<15>'
 '@S9S_MB_2U_LIB.S9S_MB_2U(SCH_1):P5E_CPU0_PE1_TX_C_DN'<15>:
 C_SIGNAL='@s9s_mb_2u_lib.s9s_mb_2u(sch_1):p5e_cpu0_pe1_tx_c_dn(15)';
NODE_NAME     C838 1
 '@S9S_MB_2U_LIB.S9S_MB_2U(SCH_1):PAGE165_I80@PURE_QUANTA.Q_CAP_DIFFBUS(CHIPS)':
 '1': CDS_PINID='\1\';
NODE_NAME     J37 B65
 '@S9S_MB_2U_LIB.S9S_MB_2U(SCH_1):PAGE150_I199@PURE_QUANTA.SCONN168_ME1016810202011(CHIPS)':
 'PETN15': CDS_PINID='PETN15';
NET_NAME
'P5E_CPU0_PE1_TX_C_DN<1>'
 '@S9S_MB_2U_LIB.S9S_MB_2U(SCH_1):P5E_CPU0_PE1_TX_C_DN'<1>:
 C_SIGNAL='@s9s_mb_2u_lib.s9s_mb_2u(sch_1):p5e_cpu0_pe1_tx_c_dn(1)';
NODE_NAME     C866 1
 '@S9S_MB_2U_LIB.S9S_MB_2U(SCH_1):PAGE165_I24@PURE_QUANTA.Q_CAP_DIFFBUS(CHIPS)':
 '1': CDS_PINID='\1\';
NODE_NAME     J37 B20
 '@S9S_MB_2U_LIB.S9S_MB_2U(SCH_1):PAGE150_I199@PURE_QUANTA.SCONN168_ME1016810202011(CHIPS)':
 'PETN1': CDS_PINID='PETN1';
NET_NAME
'P5E_CPU0_PE1_TX_C_DN<2>'
 '@S9S_MB_2U_LIB.S9S_MB_2U(SCH_1):P5E_CPU0_PE1_TX_C_DN'<2>:
 C_SIGNAL='@s9s_mb_2u_lib.s9s_mb_2u(sch_1):p5e_cpu0_pe1_tx_c_dn(2)';
NODE_NAME     C864 1
 '@S9S_MB_2U_LIB.S9S_MB_2U(SCH_1):PAGE165_I25@PURE_QUANTA.Q_CAP_DIFFBUS(CHIPS)':
 '1': CDS_PINID='\1\';
NODE_NAME     J37 B24
 '@S9S_MB_2U_LIB.S9S_MB_2U(SCH_1):PAGE150_I199@PURE_QUANTA.SCONN168_ME1016810202011(CHIPS)':
 'PETP2': CDS_PINID='PETP2';
NET_NAME
'P5E_CPU0_PE1_TX_C_DN<3>'
 '@S9S_MB_2U_LIB.S9S_MB_2U(SCH_1):P5E_CPU0_PE1_TX_C_DN'<3>:
 C_SIGNAL='@s9s_mb_2u_lib.s9s_mb_2u(sch_1):p5e_cpu0_pe1_tx_c_dn(3)';
NODE_NAME     C862 1
 '@S9S_MB_2U_LIB.S9S_MB_2U(SCH_1):PAGE165_I28@PURE_QUANTA.Q_CAP_DIFFBUS(CHIPS)':
 '1': CDS_PINID='\1\';
NODE_NAME     J37 B26
 '@S9S_MB_2U_LIB.S9S_MB_2U(SCH_1):PAGE150_I199@PURE_QUANTA.SCONN168_ME1016810202011(CHIPS)':
 'PETN3': CDS_PINID='PETN3';
NET_NAME
'P5E_CPU0_PE1_TX_C_DN<4>'
 '@S9S_MB_2U_LIB.S9S_MB_2U(SCH_1):P5E_CPU0_PE1_TX_C_DN'<4>:
 C_SIGNAL='@s9s_mb_2u_lib.s9s_mb_2u(sch_1):p5e_cpu0_pe1_tx_c_dn(4)';
NODE_NAME     C860 1
 '@S9S_MB_2U_LIB.S9S_MB_2U(SCH_1):PAGE165_I30@PURE_QUANTA.Q_CAP_DIFFBUS(CHIPS)':
 '1': CDS_PINID='\1\';
NODE_NAME     J37 B31
 '@S9S_MB_2U_LIB.S9S_MB_2U(SCH_1):PAGE150_I199@PURE_QUANTA.SCONN168_ME1016810202011(CHIPS)':
 'PETP4': CDS_PINID='PETP4';
NET_NAME
'P5E_CPU0_PE1_TX_C_DN<5>'
 '@S9S_MB_2U_LIB.S9S_MB_2U(SCH_1):P5E_CPU0_PE1_TX_C_DN'<5>:
 C_SIGNAL='@s9s_mb_2u_lib.s9s_mb_2u(sch_1):p5e_cpu0_pe1_tx_c_dn(5)';
NODE_NAME     C858 1
 '@S9S_MB_2U_LIB.S9S_MB_2U(SCH_1):PAGE165_I37@PURE_QUANTA.Q_CAP_DIFFBUS(CHIPS)':
 '1': CDS_PINID='\1\';
NODE_NAME     J37 B33
 '@S9S_MB_2U_LIB.S9S_MB_2U(SCH_1):PAGE150_I199@PURE_QUANTA.SCONN168_ME1016810202011(CHIPS)':
 'PETN5': CDS_PINID='PETN5';
NET_NAME
'P5E_CPU0_PE1_TX_C_DN<6>'
 '@S9S_MB_2U_LIB.S9S_MB_2U(SCH_1):P5E_CPU0_PE1_TX_C_DN'<6>:
 C_SIGNAL='@s9s_mb_2u_lib.s9s_mb_2u(sch_1):p5e_cpu0_pe1_tx_c_dn(6)';
NODE_NAME     C856 1
 '@S9S_MB_2U_LIB.S9S_MB_2U(SCH_1):PAGE165_I39@PURE_QUANTA.Q_CAP_DIFFBUS(CHIPS)':
 '1': CDS_PINID='\1\';
NODE_NAME     J37 B37
 '@S9S_MB_2U_LIB.S9S_MB_2U(SCH_1):PAGE150_I199@PURE_QUANTA.SCONN168_ME1016810202011(CHIPS)':
 'PETP6': CDS_PINID='PETP6';
NET_NAME
'P5E_CPU0_PE1_TX_C_DN<7>'
 '@S9S_MB_2U_LIB.S9S_MB_2U(SCH_1):P5E_CPU0_PE1_TX_C_DN'<7>:
 C_SIGNAL='@s9s_mb_2u_lib.s9s_mb_2u(sch_1):p5e_cpu0_pe1_tx_c_dn(7)';
NODE_NAME     C854 1
 '@S9S_MB_2U_LIB.S9S_MB_2U(SCH_1):PAGE165_I41@PURE_QUANTA.Q_CAP_DIFFBUS(CHIPS)':
 '1': CDS_PINID='\1\';
NODE_NAME     J37 B39
 '@S9S_MB_2U_LIB.S9S_MB_2U(SCH_1):PAGE150_I199@PURE_QUANTA.SCONN168_ME1016810202011(CHIPS)':
 'PETN7': CDS_PINID='PETN7';
NET_NAME
'P5E_CPU0_PE1_TX_C_DN<8>'
 '@S9S_MB_2U_LIB.S9S_MB_2U(SCH_1):P5E_CPU0_PE1_TX_C_DN'<8>:
 C_SIGNAL='@s9s_mb_2u_lib.s9s_mb_2u(sch_1):p5e_cpu0_pe1_tx_c_dn(8)';
NODE_NAME     C852 1
 '@S9S_MB_2U_LIB.S9S_MB_2U(SCH_1):PAGE165_I61@PURE_QUANTA.Q_CAP_DIFFBUS(CHIPS)':
 '1': CDS_PINID='\1\';
NODE_NAME     J37 B45
 '@S9S_MB_2U_LIB.S9S_MB_2U(SCH_1):PAGE150_I199@PURE_QUANTA.SCONN168_ME1016810202011(CHIPS)':
 'PETP8': CDS_PINID='PETP8';
NET_NAME
'P5E_CPU0_PE1_TX_C_DN<9>'
 '@S9S_MB_2U_LIB.S9S_MB_2U(SCH_1):P5E_CPU0_PE1_TX_C_DN'<9>:
 C_SIGNAL='@s9s_mb_2u_lib.s9s_mb_2u(sch_1):p5e_cpu0_pe1_tx_c_dn(9)';
NODE_NAME     C850 1
 '@S9S_MB_2U_LIB.S9S_MB_2U(SCH_1):PAGE165_I64@PURE_QUANTA.Q_CAP_DIFFBUS(CHIPS)':
 '1': CDS_PINID='\1\';
NODE_NAME     J37 B47
 '@S9S_MB_2U_LIB.S9S_MB_2U(SCH_1):PAGE150_I199@PURE_QUANTA.SCONN168_ME1016810202011(CHIPS)':
 'PETN9': CDS_PINID='PETN9';
NET_NAME
'P5E_CPU0_PE1_TX_C_DP<0>'
 '@S9S_MB_2U_LIB.S9S_MB_2U(SCH_1):P5E_CPU0_PE1_TX_C_DP'<0>:
 C_SIGNAL='@s9s_mb_2u_lib.s9s_mb_2u(sch_1):p5e_cpu0_pe1_tx_c_dp(0)';
NODE_NAME     C869 1
 '@S9S_MB_2U_LIB.S9S_MB_2U(SCH_1):PAGE165_I21@PURE_QUANTA.Q_CAP_DIFFBUS(CHIPS)':
 '1': CDS_PINID='\1\';
NODE_NAME     J37 B18
 '@S9S_MB_2U_LIB.S9S_MB_2U(SCH_1):PAGE150_I199@PURE_QUANTA.SCONN168_ME1016810202011(CHIPS)':
 'PETP0': CDS_PINID='PETP0';
NET_NAME
'P5E_CPU0_PE1_TX_C_DP<10>'
 '@S9S_MB_2U_LIB.S9S_MB_2U(SCH_1):P5E_CPU0_PE1_TX_C_DP'<10>:
 C_SIGNAL='@s9s_mb_2u_lib.s9s_mb_2u(sch_1):p5e_cpu0_pe1_tx_c_dp(10)';
NODE_NAME     C849 1
 '@S9S_MB_2U_LIB.S9S_MB_2U(SCH_1):PAGE165_I65@PURE_QUANTA.Q_CAP_DIFFBUS(CHIPS)':
 '1': CDS_PINID='\1\';
NODE_NAME     J37 B50
 '@S9S_MB_2U_LIB.S9S_MB_2U(SCH_1):PAGE150_I199@PURE_QUANTA.SCONN168_ME1016810202011(CHIPS)':
 'PETN10': CDS_PINID='PETN10';
NET_NAME
'P5E_CPU0_PE1_TX_C_DP<11>'
 '@S9S_MB_2U_LIB.S9S_MB_2U(SCH_1):P5E_CPU0_PE1_TX_C_DP'<11>:
 C_SIGNAL='@s9s_mb_2u_lib.s9s_mb_2u(sch_1):p5e_cpu0_pe1_tx_c_dp(11)';
NODE_NAME     C847 1
 '@S9S_MB_2U_LIB.S9S_MB_2U(SCH_1):PAGE165_I67@PURE_QUANTA.Q_CAP_DIFFBUS(CHIPS)':
 '1': CDS_PINID='\1\';
NODE_NAME     J37 B54
 '@S9S_MB_2U_LIB.S9S_MB_2U(SCH_1):PAGE150_I199@PURE_QUANTA.SCONN168_ME1016810202011(CHIPS)':
 'PETP11': CDS_PINID='PETP11';
NET_NAME
'P5E_CPU0_PE1_TX_C_DP<12>'
 '@S9S_MB_2U_LIB.S9S_MB_2U(SCH_1):P5E_CPU0_PE1_TX_C_DP'<12>:
 C_SIGNAL='@s9s_mb_2u_lib.s9s_mb_2u(sch_1):p5e_cpu0_pe1_tx_c_dp(12)';
NODE_NAME     C845 1
 '@S9S_MB_2U_LIB.S9S_MB_2U(SCH_1):PAGE165_I69@PURE_QUANTA.Q_CAP_DIFFBUS(CHIPS)':
 '1': CDS_PINID='\1\';
NODE_NAME     J37 B56
 '@S9S_MB_2U_LIB.S9S_MB_2U(SCH_1):PAGE150_I199@PURE_QUANTA.SCONN168_ME1016810202011(CHIPS)':
 'PETN12': CDS_PINID='PETN12';
NET_NAME
'P5E_CPU0_PE1_TX_C_DP<13>'
 '@S9S_MB_2U_LIB.S9S_MB_2U(SCH_1):P5E_CPU0_PE1_TX_C_DP'<13>:
 C_SIGNAL='@s9s_mb_2u_lib.s9s_mb_2u(sch_1):p5e_cpu0_pe1_tx_c_dp(13)';
NODE_NAME     C843 1
 '@S9S_MB_2U_LIB.S9S_MB_2U(SCH_1):PAGE165_I77@PURE_QUANTA.Q_CAP_DIFFBUS(CHIPS)':
 '1': CDS_PINID='\1\';
NODE_NAME     J37 B60
 '@S9S_MB_2U_LIB.S9S_MB_2U(SCH_1):PAGE150_I199@PURE_QUANTA.SCONN168_ME1016810202011(CHIPS)':
 'PETP13': CDS_PINID='PETP13';
NET_NAME
'P5E_CPU0_PE1_TX_C_DP<14>'
 '@S9S_MB_2U_LIB.S9S_MB_2U(SCH_1):P5E_CPU0_PE1_TX_C_DP'<14>:
 C_SIGNAL='@s9s_mb_2u_lib.s9s_mb_2u(sch_1):p5e_cpu0_pe1_tx_c_dp(14)';
NODE_NAME     C841 1
 '@S9S_MB_2U_LIB.S9S_MB_2U(SCH_1):PAGE165_I78@PURE_QUANTA.Q_CAP_DIFFBUS(CHIPS)':
 '1': CDS_PINID='\1\';
NODE_NAME     J37 B62
 '@S9S_MB_2U_LIB.S9S_MB_2U(SCH_1):PAGE150_I199@PURE_QUANTA.SCONN168_ME1016810202011(CHIPS)':
 'PETN14': CDS_PINID='PETN14';
NET_NAME
'P5E_CPU0_PE1_TX_C_DP<15>'
 '@S9S_MB_2U_LIB.S9S_MB_2U(SCH_1):P5E_CPU0_PE1_TX_C_DP'<15>:
 C_SIGNAL='@s9s_mb_2u_lib.s9s_mb_2u(sch_1):p5e_cpu0_pe1_tx_c_dp(15)';
NODE_NAME     C839 1
 '@S9S_MB_2U_LIB.S9S_MB_2U(SCH_1):PAGE165_I81@PURE_QUANTA.Q_CAP_DIFFBUS(CHIPS)':
 '1': CDS_PINID='\1\';
NODE_NAME     J37 B66
 '@S9S_MB_2U_LIB.S9S_MB_2U(SCH_1):PAGE150_I199@PURE_QUANTA.SCONN168_ME1016810202011(CHIPS)':
 'PETP15': CDS_PINID='PETP15';
NET_NAME
'P5E_CPU0_PE1_TX_C_DP<1>'
 '@S9S_MB_2U_LIB.S9S_MB_2U(SCH_1):P5E_CPU0_PE1_TX_C_DP'<1>:
 C_SIGNAL='@s9s_mb_2u_lib.s9s_mb_2u(sch_1):p5e_cpu0_pe1_tx_c_dp(1)';
NODE_NAME     C867 1
 '@S9S_MB_2U_LIB.S9S_MB_2U(SCH_1):PAGE165_I23@PURE_QUANTA.Q_CAP_DIFFBUS(CHIPS)':
 '1': CDS_PINID='\1\';
NODE_NAME     J37 B21
 '@S9S_MB_2U_LIB.S9S_MB_2U(SCH_1):PAGE150_I199@PURE_QUANTA.SCONN168_ME1016810202011(CHIPS)':
 'PETP1': CDS_PINID='PETP1';
NET_NAME
'P5E_CPU0_PE1_TX_C_DP<2>'
 '@S9S_MB_2U_LIB.S9S_MB_2U(SCH_1):P5E_CPU0_PE1_TX_C_DP'<2>:
 C_SIGNAL='@s9s_mb_2u_lib.s9s_mb_2u(sch_1):p5e_cpu0_pe1_tx_c_dp(2)';
NODE_NAME     C865 1
 '@S9S_MB_2U_LIB.S9S_MB_2U(SCH_1):PAGE165_I26@PURE_QUANTA.Q_CAP_DIFFBUS(CHIPS)':
 '1': CDS_PINID='\1\';
NODE_NAME     J37 B23
 '@S9S_MB_2U_LIB.S9S_MB_2U(SCH_1):PAGE150_I199@PURE_QUANTA.SCONN168_ME1016810202011(CHIPS)':
 'PETN2': CDS_PINID='PETN2';
NET_NAME
'P5E_CPU0_PE1_TX_C_DP<3>'
 '@S9S_MB_2U_LIB.S9S_MB_2U(SCH_1):P5E_CPU0_PE1_TX_C_DP'<3>:
 C_SIGNAL='@s9s_mb_2u_lib.s9s_mb_2u(sch_1):p5e_cpu0_pe1_tx_c_dp(3)';
NODE_NAME     C863 1
 '@S9S_MB_2U_LIB.S9S_MB_2U(SCH_1):PAGE165_I27@PURE_QUANTA.Q_CAP_DIFFBUS(CHIPS)':
 '1': CDS_PINID='\1\';
NODE_NAME     J37 B27
 '@S9S_MB_2U_LIB.S9S_MB_2U(SCH_1):PAGE150_I199@PURE_QUANTA.SCONN168_ME1016810202011(CHIPS)':
 'PETP3': CDS_PINID='PETP3';
NET_NAME
'P5E_CPU0_PE1_TX_C_DP<4>'
 '@S9S_MB_2U_LIB.S9S_MB_2U(SCH_1):P5E_CPU0_PE1_TX_C_DP'<4>:
 C_SIGNAL='@s9s_mb_2u_lib.s9s_mb_2u(sch_1):p5e_cpu0_pe1_tx_c_dp(4)';
NODE_NAME     C861 1
 '@S9S_MB_2U_LIB.S9S_MB_2U(SCH_1):PAGE165_I29@PURE_QUANTA.Q_CAP_DIFFBUS(CHIPS)':
 '1': CDS_PINID='\1\';
NODE_NAME     J37 B30
 '@S9S_MB_2U_LIB.S9S_MB_2U(SCH_1):PAGE150_I199@PURE_QUANTA.SCONN168_ME1016810202011(CHIPS)':
 'PETN4': CDS_PINID='PETN4';
NET_NAME
'P5E_CPU0_PE1_TX_C_DP<5>'
 '@S9S_MB_2U_LIB.S9S_MB_2U(SCH_1):P5E_CPU0_PE1_TX_C_DP'<5>:
 C_SIGNAL='@s9s_mb_2u_lib.s9s_mb_2u(sch_1):p5e_cpu0_pe1_tx_c_dp(5)';
NODE_NAME     C859 1
 '@S9S_MB_2U_LIB.S9S_MB_2U(SCH_1):PAGE165_I36@PURE_QUANTA.Q_CAP_DIFFBUS(CHIPS)':
 '1': CDS_PINID='\1\';
NODE_NAME     J37 B34
 '@S9S_MB_2U_LIB.S9S_MB_2U(SCH_1):PAGE150_I199@PURE_QUANTA.SCONN168_ME1016810202011(CHIPS)':
 'PETP5': CDS_PINID='PETP5';
NET_NAME
'P5E_CPU0_PE1_TX_C_DP<6>'
 '@S9S_MB_2U_LIB.S9S_MB_2U(SCH_1):P5E_CPU0_PE1_TX_C_DP'<6>:
 C_SIGNAL='@s9s_mb_2u_lib.s9s_mb_2u(sch_1):p5e_cpu0_pe1_tx_c_dp(6)';
NODE_NAME     C857 1
 '@S9S_MB_2U_LIB.S9S_MB_2U(SCH_1):PAGE165_I38@PURE_QUANTA.Q_CAP_DIFFBUS(CHIPS)':
 '1': CDS_PINID='\1\';
NODE_NAME     J37 B36
 '@S9S_MB_2U_LIB.S9S_MB_2U(SCH_1):PAGE150_I199@PURE_QUANTA.SCONN168_ME1016810202011(CHIPS)':
 'PETN6': CDS_PINID='PETN6';
NET_NAME
'P5E_CPU0_PE1_TX_C_DP<7>'
 '@S9S_MB_2U_LIB.S9S_MB_2U(SCH_1):P5E_CPU0_PE1_TX_C_DP'<7>:
 C_SIGNAL='@s9s_mb_2u_lib.s9s_mb_2u(sch_1):p5e_cpu0_pe1_tx_c_dp(7)';
NODE_NAME     C855 1
 '@S9S_MB_2U_LIB.S9S_MB_2U(SCH_1):PAGE165_I40@PURE_QUANTA.Q_CAP_DIFFBUS(CHIPS)':
 '1': CDS_PINID='\1\';
NODE_NAME     J37 B40
 '@S9S_MB_2U_LIB.S9S_MB_2U(SCH_1):PAGE150_I199@PURE_QUANTA.SCONN168_ME1016810202011(CHIPS)':
 'PETP7': CDS_PINID='PETP7';
NET_NAME
'P5E_CPU0_PE1_TX_C_DP<8>'
 '@S9S_MB_2U_LIB.S9S_MB_2U(SCH_1):P5E_CPU0_PE1_TX_C_DP'<8>:
 C_SIGNAL='@s9s_mb_2u_lib.s9s_mb_2u(sch_1):p5e_cpu0_pe1_tx_c_dp(8)';
NODE_NAME     C853 1
 '@S9S_MB_2U_LIB.S9S_MB_2U(SCH_1):PAGE165_I62@PURE_QUANTA.Q_CAP_DIFFBUS(CHIPS)':
 '1': CDS_PINID='\1\';
NODE_NAME     J37 B44
 '@S9S_MB_2U_LIB.S9S_MB_2U(SCH_1):PAGE150_I199@PURE_QUANTA.SCONN168_ME1016810202011(CHIPS)':
 'PETN8': CDS_PINID='PETN8';
NET_NAME
'P5E_CPU0_PE1_TX_C_DP<9>'
 '@S9S_MB_2U_LIB.S9S_MB_2U(SCH_1):P5E_CPU0_PE1_TX_C_DP'<9>:
 C_SIGNAL='@s9s_mb_2u_lib.s9s_mb_2u(sch_1):p5e_cpu0_pe1_tx_c_dp(9)';
NODE_NAME     C851 1
 '@S9S_MB_2U_LIB.S9S_MB_2U(SCH_1):PAGE165_I63@PURE_QUANTA.Q_CAP_DIFFBUS(CHIPS)':
 '1': CDS_PINID='\1\';
NODE_NAME     J37 B48
 '@S9S_MB_2U_LIB.S9S_MB_2U(SCH_1):PAGE150_I199@PURE_QUANTA.SCONN168_ME1016810202011(CHIPS)':
 'PETP9': CDS_PINID='PETP9';
NET_NAME
'P5E_CPU0_PE1_TX_DN<0>'
 '@S9S_MB_2U_LIB.S9S_MB_2U(SCH_1):P5E_CPU0_PE1_TX_DN'<0>:
 C_SIGNAL='@s9s_mb_2u_lib.s9s_mb_2u(sch_1):p5e_cpu0_pe1_tx_dn(0)';
NODE_NAME     U2 CP14
 '@S9S_MB_2U_LIB.S9S_MB_2U(SCH_1):PAGE29_I176@PURE_QUANTA.SOCKET4677_AZIF0045P001C01CS(CHIPS)':
 'PE1_TX_DN0': CDS_PINID='PE1_TX_DN0';
NODE_NAME     C868 2
 '@S9S_MB_2U_LIB.S9S_MB_2U(SCH_1):PAGE165_I22@PURE_QUANTA.Q_CAP_DIFFBUS(CHIPS)':
 '2': CDS_PINID='\2\';
NET_NAME
'P5E_CPU0_PE1_TX_DN<10>'
 '@S9S_MB_2U_LIB.S9S_MB_2U(SCH_1):P5E_CPU0_PE1_TX_DN'<10>:
 C_SIGNAL='@s9s_mb_2u_lib.s9s_mb_2u(sch_1):p5e_cpu0_pe1_tx_dn(10)';
NODE_NAME     U2 BP14
 '@S9S_MB_2U_LIB.S9S_MB_2U(SCH_1):PAGE29_I176@PURE_QUANTA.SOCKET4677_AZIF0045P001C01CS(CHIPS)':
 'PE1_TX_DN10': CDS_PINID='PE1_TX_DN10';
NODE_NAME     C848 2
 '@S9S_MB_2U_LIB.S9S_MB_2U(SCH_1):PAGE165_I66@PURE_QUANTA.Q_CAP_DIFFBUS(CHIPS)':
 '2': CDS_PINID='\2\';
NET_NAME
'P5E_CPU0_PE1_TX_DN<11>'
 '@S9S_MB_2U_LIB.S9S_MB_2U(SCH_1):P5E_CPU0_PE1_TX_DN'<11>:
 C_SIGNAL='@s9s_mb_2u_lib.s9s_mb_2u(sch_1):p5e_cpu0_pe1_tx_dn(11)';
NODE_NAME     U2 BN13
 '@S9S_MB_2U_LIB.S9S_MB_2U(SCH_1):PAGE29_I176@PURE_QUANTA.SOCKET4677_AZIF0045P001C01CS(CHIPS)':
 'PE1_TX_DN11': CDS_PINID='PE1_TX_DN11';
NODE_NAME     C846 2
 '@S9S_MB_2U_LIB.S9S_MB_2U(SCH_1):PAGE165_I68@PURE_QUANTA.Q_CAP_DIFFBUS(CHIPS)':
 '2': CDS_PINID='\2\';
NET_NAME
'P5E_CPU0_PE1_TX_DN<12>'
 '@S9S_MB_2U_LIB.S9S_MB_2U(SCH_1):P5E_CPU0_PE1_TX_DN'<12>:
 C_SIGNAL='@s9s_mb_2u_lib.s9s_mb_2u(sch_1):p5e_cpu0_pe1_tx_dn(12)';
NODE_NAME     U2 BK14
 '@S9S_MB_2U_LIB.S9S_MB_2U(SCH_1):PAGE29_I176@PURE_QUANTA.SOCKET4677_AZIF0045P001C01CS(CHIPS)':
 'PE1_TX_DN12': CDS_PINID='PE1_TX_DN12';
NODE_NAME     C844 2
 '@S9S_MB_2U_LIB.S9S_MB_2U(SCH_1):PAGE165_I70@PURE_QUANTA.Q_CAP_DIFFBUS(CHIPS)':
 '2': CDS_PINID='\2\';
NET_NAME
'P5E_CPU0_PE1_TX_DN<13>'
 '@S9S_MB_2U_LIB.S9S_MB_2U(SCH_1):P5E_CPU0_PE1_TX_DN'<13>:
 C_SIGNAL='@s9s_mb_2u_lib.s9s_mb_2u(sch_1):p5e_cpu0_pe1_tx_dn(13)';
NODE_NAME     U2 BJ13
 '@S9S_MB_2U_LIB.S9S_MB_2U(SCH_1):PAGE29_I176@PURE_QUANTA.SOCKET4677_AZIF0045P001C01CS(CHIPS)':
 'PE1_TX_DN13': CDS_PINID='PE1_TX_DN13';
NODE_NAME     C842 2
 '@S9S_MB_2U_LIB.S9S_MB_2U(SCH_1):PAGE165_I76@PURE_QUANTA.Q_CAP_DIFFBUS(CHIPS)':
 '2': CDS_PINID='\2\';
NET_NAME
'P5E_CPU0_PE1_TX_DN<14>'
 '@S9S_MB_2U_LIB.S9S_MB_2U(SCH_1):P5E_CPU0_PE1_TX_DN'<14>:
 C_SIGNAL='@s9s_mb_2u_lib.s9s_mb_2u(sch_1):p5e_cpu0_pe1_tx_dn(14)';
NODE_NAME     U2 BF14
 '@S9S_MB_2U_LIB.S9S_MB_2U(SCH_1):PAGE29_I176@PURE_QUANTA.SOCKET4677_AZIF0045P001C01CS(CHIPS)':
 'PE1_TX_DN14': CDS_PINID='PE1_TX_DN14';
NODE_NAME     C840 2
 '@S9S_MB_2U_LIB.S9S_MB_2U(SCH_1):PAGE165_I79@PURE_QUANTA.Q_CAP_DIFFBUS(CHIPS)':
 '2': CDS_PINID='\2\';
NET_NAME
'P5E_CPU0_PE1_TX_DN<15>'
 '@S9S_MB_2U_LIB.S9S_MB_2U(SCH_1):P5E_CPU0_PE1_TX_DN'<15>:
 C_SIGNAL='@s9s_mb_2u_lib.s9s_mb_2u(sch_1):p5e_cpu0_pe1_tx_dn(15)';
NODE_NAME     U2 BE13
 '@S9S_MB_2U_LIB.S9S_MB_2U(SCH_1):PAGE29_I176@PURE_QUANTA.SOCKET4677_AZIF0045P001C01CS(CHIPS)':
 'PE1_TX_DN15': CDS_PINID='PE1_TX_DN15';
NODE_NAME     C838 2
 '@S9S_MB_2U_LIB.S9S_MB_2U(SCH_1):PAGE165_I80@PURE_QUANTA.Q_CAP_DIFFBUS(CHIPS)':
 '2': CDS_PINID='\2\';
NET_NAME
'P5E_CPU0_PE1_TX_DN<1>'
 '@S9S_MB_2U_LIB.S9S_MB_2U(SCH_1):P5E_CPU0_PE1_TX_DN'<1>:
 C_SIGNAL='@s9s_mb_2u_lib.s9s_mb_2u(sch_1):p5e_cpu0_pe1_tx_dn(1)';
NODE_NAME     U2 CN13
 '@S9S_MB_2U_LIB.S9S_MB_2U(SCH_1):PAGE29_I176@PURE_QUANTA.SOCKET4677_AZIF0045P001C01CS(CHIPS)':
 'PE1_TX_DN1': CDS_PINID='PE1_TX_DN1';
NODE_NAME     C866 2
 '@S9S_MB_2U_LIB.S9S_MB_2U(SCH_1):PAGE165_I24@PURE_QUANTA.Q_CAP_DIFFBUS(CHIPS)':
 '2': CDS_PINID='\2\';
NET_NAME
'P5E_CPU0_PE1_TX_DN<2>'
 '@S9S_MB_2U_LIB.S9S_MB_2U(SCH_1):P5E_CPU0_PE1_TX_DN'<2>:
 C_SIGNAL='@s9s_mb_2u_lib.s9s_mb_2u(sch_1):p5e_cpu0_pe1_tx_dn(2)';
NODE_NAME     U2 CK14
 '@S9S_MB_2U_LIB.S9S_MB_2U(SCH_1):PAGE29_I176@PURE_QUANTA.SOCKET4677_AZIF0045P001C01CS(CHIPS)':
 'PE1_TX_DN2': CDS_PINID='PE1_TX_DN2';
NODE_NAME     C864 2
 '@S9S_MB_2U_LIB.S9S_MB_2U(SCH_1):PAGE165_I25@PURE_QUANTA.Q_CAP_DIFFBUS(CHIPS)':
 '2': CDS_PINID='\2\';
NET_NAME
'P5E_CPU0_PE1_TX_DN<3>'
 '@S9S_MB_2U_LIB.S9S_MB_2U(SCH_1):P5E_CPU0_PE1_TX_DN'<3>:
 C_SIGNAL='@s9s_mb_2u_lib.s9s_mb_2u(sch_1):p5e_cpu0_pe1_tx_dn(3)';
NODE_NAME     U2 CJ13
 '@S9S_MB_2U_LIB.S9S_MB_2U(SCH_1):PAGE29_I176@PURE_QUANTA.SOCKET4677_AZIF0045P001C01CS(CHIPS)':
 'PE1_TX_DN3': CDS_PINID='PE1_TX_DN3';
NODE_NAME     C862 2
 '@S9S_MB_2U_LIB.S9S_MB_2U(SCH_1):PAGE165_I28@PURE_QUANTA.Q_CAP_DIFFBUS(CHIPS)':
 '2': CDS_PINID='\2\';
NET_NAME
'P5E_CPU0_PE1_TX_DN<4>'
 '@S9S_MB_2U_LIB.S9S_MB_2U(SCH_1):P5E_CPU0_PE1_TX_DN'<4>:
 C_SIGNAL='@s9s_mb_2u_lib.s9s_mb_2u(sch_1):p5e_cpu0_pe1_tx_dn(4)';
NODE_NAME     U2 CF14
 '@S9S_MB_2U_LIB.S9S_MB_2U(SCH_1):PAGE29_I176@PURE_QUANTA.SOCKET4677_AZIF0045P001C01CS(CHIPS)':
 'PE1_TX_DN4': CDS_PINID='PE1_TX_DN4';
NODE_NAME     C860 2
 '@S9S_MB_2U_LIB.S9S_MB_2U(SCH_1):PAGE165_I30@PURE_QUANTA.Q_CAP_DIFFBUS(CHIPS)':
 '2': CDS_PINID='\2\';
NET_NAME
'P5E_CPU0_PE1_TX_DN<5>'
 '@S9S_MB_2U_LIB.S9S_MB_2U(SCH_1):P5E_CPU0_PE1_TX_DN'<5>:
 C_SIGNAL='@s9s_mb_2u_lib.s9s_mb_2u(sch_1):p5e_cpu0_pe1_tx_dn(5)';
NODE_NAME     U2 CE13
 '@S9S_MB_2U_LIB.S9S_MB_2U(SCH_1):PAGE29_I176@PURE_QUANTA.SOCKET4677_AZIF0045P001C01CS(CHIPS)':
 'PE1_TX_DN5': CDS_PINID='PE1_TX_DN5';
NODE_NAME     C858 2
 '@S9S_MB_2U_LIB.S9S_MB_2U(SCH_1):PAGE165_I37@PURE_QUANTA.Q_CAP_DIFFBUS(CHIPS)':
 '2': CDS_PINID='\2\';
NET_NAME
'P5E_CPU0_PE1_TX_DN<6>'
 '@S9S_MB_2U_LIB.S9S_MB_2U(SCH_1):P5E_CPU0_PE1_TX_DN'<6>:
 C_SIGNAL='@s9s_mb_2u_lib.s9s_mb_2u(sch_1):p5e_cpu0_pe1_tx_dn(6)';
NODE_NAME     U2 CB14
 '@S9S_MB_2U_LIB.S9S_MB_2U(SCH_1):PAGE29_I176@PURE_QUANTA.SOCKET4677_AZIF0045P001C01CS(CHIPS)':
 'PE1_TX_DN6': CDS_PINID='PE1_TX_DN6';
NODE_NAME     C856 2
 '@S9S_MB_2U_LIB.S9S_MB_2U(SCH_1):PAGE165_I39@PURE_QUANTA.Q_CAP_DIFFBUS(CHIPS)':
 '2': CDS_PINID='\2\';
NET_NAME
'P5E_CPU0_PE1_TX_DN<7>'
 '@S9S_MB_2U_LIB.S9S_MB_2U(SCH_1):P5E_CPU0_PE1_TX_DN'<7>:
 C_SIGNAL='@s9s_mb_2u_lib.s9s_mb_2u(sch_1):p5e_cpu0_pe1_tx_dn(7)';
NODE_NAME     U2 CA13
 '@S9S_MB_2U_LIB.S9S_MB_2U(SCH_1):PAGE29_I176@PURE_QUANTA.SOCKET4677_AZIF0045P001C01CS(CHIPS)':
 'PE1_TX_DN7': CDS_PINID='PE1_TX_DN7';
NODE_NAME     C854 2
 '@S9S_MB_2U_LIB.S9S_MB_2U(SCH_1):PAGE165_I41@PURE_QUANTA.Q_CAP_DIFFBUS(CHIPS)':
 '2': CDS_PINID='\2\';
NET_NAME
'P5E_CPU0_PE1_TX_DN<8>'
 '@S9S_MB_2U_LIB.S9S_MB_2U(SCH_1):P5E_CPU0_PE1_TX_DN'<8>:
 C_SIGNAL='@s9s_mb_2u_lib.s9s_mb_2u(sch_1):p5e_cpu0_pe1_tx_dn(8)';
NODE_NAME     U2 BV14
 '@S9S_MB_2U_LIB.S9S_MB_2U(SCH_1):PAGE29_I176@PURE_QUANTA.SOCKET4677_AZIF0045P001C01CS(CHIPS)':
 'PE1_TX_DN8': CDS_PINID='PE1_TX_DN8';
NODE_NAME     C852 2
 '@S9S_MB_2U_LIB.S9S_MB_2U(SCH_1):PAGE165_I61@PURE_QUANTA.Q_CAP_DIFFBUS(CHIPS)':
 '2': CDS_PINID='\2\';
NET_NAME
'P5E_CPU0_PE1_TX_DN<9>'
 '@S9S_MB_2U_LIB.S9S_MB_2U(SCH_1):P5E_CPU0_PE1_TX_DN'<9>:
 C_SIGNAL='@s9s_mb_2u_lib.s9s_mb_2u(sch_1):p5e_cpu0_pe1_tx_dn(9)';
NODE_NAME     U2 BU13
 '@S9S_MB_2U_LIB.S9S_MB_2U(SCH_1):PAGE29_I176@PURE_QUANTA.SOCKET4677_AZIF0045P001C01CS(CHIPS)':
 'PE1_TX_DN9': CDS_PINID='PE1_TX_DN9';
NODE_NAME     C850 2
 '@S9S_MB_2U_LIB.S9S_MB_2U(SCH_1):PAGE165_I64@PURE_QUANTA.Q_CAP_DIFFBUS(CHIPS)':
 '2': CDS_PINID='\2\';
NET_NAME
'P5E_CPU0_PE1_TX_DP<0>'
 '@S9S_MB_2U_LIB.S9S_MB_2U(SCH_1):P5E_CPU0_PE1_TX_DP'<0>:
 C_SIGNAL='@s9s_mb_2u_lib.s9s_mb_2u(sch_1):p5e_cpu0_pe1_tx_dp(0)';
NODE_NAME     U2 CR15
 '@S9S_MB_2U_LIB.S9S_MB_2U(SCH_1):PAGE29_I176@PURE_QUANTA.SOCKET4677_AZIF0045P001C01CS(CHIPS)':
 'PE1_TX_DP0': CDS_PINID='PE1_TX_DP0';
NODE_NAME     C869 2
 '@S9S_MB_2U_LIB.S9S_MB_2U(SCH_1):PAGE165_I21@PURE_QUANTA.Q_CAP_DIFFBUS(CHIPS)':
 '2': CDS_PINID='\2\';
NET_NAME
'P5E_CPU0_PE1_TX_DP<10>'
 '@S9S_MB_2U_LIB.S9S_MB_2U(SCH_1):P5E_CPU0_PE1_TX_DP'<10>:
 C_SIGNAL='@s9s_mb_2u_lib.s9s_mb_2u(sch_1):p5e_cpu0_pe1_tx_dp(10)';
NODE_NAME     U2 BR15
 '@S9S_MB_2U_LIB.S9S_MB_2U(SCH_1):PAGE29_I176@PURE_QUANTA.SOCKET4677_AZIF0045P001C01CS(CHIPS)':
 'PE1_TX_DP10': CDS_PINID='PE1_TX_DP10';
NODE_NAME     C849 2
 '@S9S_MB_2U_LIB.S9S_MB_2U(SCH_1):PAGE165_I65@PURE_QUANTA.Q_CAP_DIFFBUS(CHIPS)':
 '2': CDS_PINID='\2\';
NET_NAME
'P5E_CPU0_PE1_TX_DP<11>'
 '@S9S_MB_2U_LIB.S9S_MB_2U(SCH_1):P5E_CPU0_PE1_TX_DP'<11>:
 C_SIGNAL='@s9s_mb_2u_lib.s9s_mb_2u(sch_1):p5e_cpu0_pe1_tx_dp(11)';
NODE_NAME     U2 BM14
 '@S9S_MB_2U_LIB.S9S_MB_2U(SCH_1):PAGE29_I176@PURE_QUANTA.SOCKET4677_AZIF0045P001C01CS(CHIPS)':
 'PE1_TX_DP11': CDS_PINID='PE1_TX_DP11';
NODE_NAME     C847 2
 '@S9S_MB_2U_LIB.S9S_MB_2U(SCH_1):PAGE165_I67@PURE_QUANTA.Q_CAP_DIFFBUS(CHIPS)':
 '2': CDS_PINID='\2\';
NET_NAME
'P5E_CPU0_PE1_TX_DP<12>'
 '@S9S_MB_2U_LIB.S9S_MB_2U(SCH_1):P5E_CPU0_PE1_TX_DP'<12>:
 C_SIGNAL='@s9s_mb_2u_lib.s9s_mb_2u(sch_1):p5e_cpu0_pe1_tx_dp(12)';
NODE_NAME     U2 BL15
 '@S9S_MB_2U_LIB.S9S_MB_2U(SCH_1):PAGE29_I176@PURE_QUANTA.SOCKET4677_AZIF0045P001C01CS(CHIPS)':
 'PE1_TX_DP12': CDS_PINID='PE1_TX_DP12';
NODE_NAME     C845 2
 '@S9S_MB_2U_LIB.S9S_MB_2U(SCH_1):PAGE165_I69@PURE_QUANTA.Q_CAP_DIFFBUS(CHIPS)':
 '2': CDS_PINID='\2\';
NET_NAME
'P5E_CPU0_PE1_TX_DP<13>'
 '@S9S_MB_2U_LIB.S9S_MB_2U(SCH_1):P5E_CPU0_PE1_TX_DP'<13>:
 C_SIGNAL='@s9s_mb_2u_lib.s9s_mb_2u(sch_1):p5e_cpu0_pe1_tx_dp(13)';
NODE_NAME     U2 BH14
 '@S9S_MB_2U_LIB.S9S_MB_2U(SCH_1):PAGE29_I176@PURE_QUANTA.SOCKET4677_AZIF0045P001C01CS(CHIPS)':
 'PE1_TX_DP13': CDS_PINID='PE1_TX_DP13';
NODE_NAME     C843 2
 '@S9S_MB_2U_LIB.S9S_MB_2U(SCH_1):PAGE165_I77@PURE_QUANTA.Q_CAP_DIFFBUS(CHIPS)':
 '2': CDS_PINID='\2\';
NET_NAME
'P5E_CPU0_PE1_TX_DP<14>'
 '@S9S_MB_2U_LIB.S9S_MB_2U(SCH_1):P5E_CPU0_PE1_TX_DP'<14>:
 C_SIGNAL='@s9s_mb_2u_lib.s9s_mb_2u(sch_1):p5e_cpu0_pe1_tx_dp(14)';
NODE_NAME     U2 BG15
 '@S9S_MB_2U_LIB.S9S_MB_2U(SCH_1):PAGE29_I176@PURE_QUANTA.SOCKET4677_AZIF0045P001C01CS(CHIPS)':
 'PE1_TX_DP14': CDS_PINID='PE1_TX_DP14';
NODE_NAME     C841 2
 '@S9S_MB_2U_LIB.S9S_MB_2U(SCH_1):PAGE165_I78@PURE_QUANTA.Q_CAP_DIFFBUS(CHIPS)':
 '2': CDS_PINID='\2\';
NET_NAME
'P5E_CPU0_PE1_TX_DP<15>'
 '@S9S_MB_2U_LIB.S9S_MB_2U(SCH_1):P5E_CPU0_PE1_TX_DP'<15>:
 C_SIGNAL='@s9s_mb_2u_lib.s9s_mb_2u(sch_1):p5e_cpu0_pe1_tx_dp(15)';
NODE_NAME     U2 BD14
 '@S9S_MB_2U_LIB.S9S_MB_2U(SCH_1):PAGE29_I176@PURE_QUANTA.SOCKET4677_AZIF0045P001C01CS(CHIPS)':
 'PE1_TX_DP15': CDS_PINID='PE1_TX_DP15';
NODE_NAME     C839 2
 '@S9S_MB_2U_LIB.S9S_MB_2U(SCH_1):PAGE165_I81@PURE_QUANTA.Q_CAP_DIFFBUS(CHIPS)':
 '2': CDS_PINID='\2\';
NET_NAME
'P5E_CPU0_PE1_TX_DP<1>'
 '@S9S_MB_2U_LIB.S9S_MB_2U(SCH_1):P5E_CPU0_PE1_TX_DP'<1>:
 C_SIGNAL='@s9s_mb_2u_lib.s9s_mb_2u(sch_1):p5e_cpu0_pe1_tx_dp(1)';
NODE_NAME     U2 CM14
 '@S9S_MB_2U_LIB.S9S_MB_2U(SCH_1):PAGE29_I176@PURE_QUANTA.SOCKET4677_AZIF0045P001C01CS(CHIPS)':
 'PE1_TX_DP1': CDS_PINID='PE1_TX_DP1';
NODE_NAME     C867 2
 '@S9S_MB_2U_LIB.S9S_MB_2U(SCH_1):PAGE165_I23@PURE_QUANTA.Q_CAP_DIFFBUS(CHIPS)':
 '2': CDS_PINID='\2\';
NET_NAME
'P5E_CPU0_PE1_TX_DP<2>'
 '@S9S_MB_2U_LIB.S9S_MB_2U(SCH_1):P5E_CPU0_PE1_TX_DP'<2>:
 C_SIGNAL='@s9s_mb_2u_lib.s9s_mb_2u(sch_1):p5e_cpu0_pe1_tx_dp(2)';
NODE_NAME     U2 CL15
 '@S9S_MB_2U_LIB.S9S_MB_2U(SCH_1):PAGE29_I176@PURE_QUANTA.SOCKET4677_AZIF0045P001C01CS(CHIPS)':
 'PE1_TX_DP2': CDS_PINID='PE1_TX_DP2';
NODE_NAME     C865 2
 '@S9S_MB_2U_LIB.S9S_MB_2U(SCH_1):PAGE165_I26@PURE_QUANTA.Q_CAP_DIFFBUS(CHIPS)':
 '2': CDS_PINID='\2\';
NET_NAME
'P5E_CPU0_PE1_TX_DP<3>'
 '@S9S_MB_2U_LIB.S9S_MB_2U(SCH_1):P5E_CPU0_PE1_TX_DP'<3>:
 C_SIGNAL='@s9s_mb_2u_lib.s9s_mb_2u(sch_1):p5e_cpu0_pe1_tx_dp(3)';
NODE_NAME     U2 CH14
 '@S9S_MB_2U_LIB.S9S_MB_2U(SCH_1):PAGE29_I176@PURE_QUANTA.SOCKET4677_AZIF0045P001C01CS(CHIPS)':
 'PE1_TX_DP3': CDS_PINID='PE1_TX_DP3';
NODE_NAME     C863 2
 '@S9S_MB_2U_LIB.S9S_MB_2U(SCH_1):PAGE165_I27@PURE_QUANTA.Q_CAP_DIFFBUS(CHIPS)':
 '2': CDS_PINID='\2\';
NET_NAME
'P5E_CPU0_PE1_TX_DP<4>'
 '@S9S_MB_2U_LIB.S9S_MB_2U(SCH_1):P5E_CPU0_PE1_TX_DP'<4>:
 C_SIGNAL='@s9s_mb_2u_lib.s9s_mb_2u(sch_1):p5e_cpu0_pe1_tx_dp(4)';
NODE_NAME     U2 CG15
 '@S9S_MB_2U_LIB.S9S_MB_2U(SCH_1):PAGE29_I176@PURE_QUANTA.SOCKET4677_AZIF0045P001C01CS(CHIPS)':
 'PE1_TX_DP4': CDS_PINID='PE1_TX_DP4';
NODE_NAME     C861 2
 '@S9S_MB_2U_LIB.S9S_MB_2U(SCH_1):PAGE165_I29@PURE_QUANTA.Q_CAP_DIFFBUS(CHIPS)':
 '2': CDS_PINID='\2\';
NET_NAME
'P5E_CPU0_PE1_TX_DP<5>'
 '@S9S_MB_2U_LIB.S9S_MB_2U(SCH_1):P5E_CPU0_PE1_TX_DP'<5>:
 C_SIGNAL='@s9s_mb_2u_lib.s9s_mb_2u(sch_1):p5e_cpu0_pe1_tx_dp(5)';
NODE_NAME     U2 CD14
 '@S9S_MB_2U_LIB.S9S_MB_2U(SCH_1):PAGE29_I176@PURE_QUANTA.SOCKET4677_AZIF0045P001C01CS(CHIPS)':
 'PE1_TX_DP5': CDS_PINID='PE1_TX_DP5';
NODE_NAME     C859 2
 '@S9S_MB_2U_LIB.S9S_MB_2U(SCH_1):PAGE165_I36@PURE_QUANTA.Q_CAP_DIFFBUS(CHIPS)':
 '2': CDS_PINID='\2\';
NET_NAME
'P5E_CPU0_PE1_TX_DP<6>'
 '@S9S_MB_2U_LIB.S9S_MB_2U(SCH_1):P5E_CPU0_PE1_TX_DP'<6>:
 C_SIGNAL='@s9s_mb_2u_lib.s9s_mb_2u(sch_1):p5e_cpu0_pe1_tx_dp(6)';
NODE_NAME     U2 CC15
 '@S9S_MB_2U_LIB.S9S_MB_2U(SCH_1):PAGE29_I176@PURE_QUANTA.SOCKET4677_AZIF0045P001C01CS(CHIPS)':
 'PE1_TX_DP6': CDS_PINID='PE1_TX_DP6';
NODE_NAME     C857 2
 '@S9S_MB_2U_LIB.S9S_MB_2U(SCH_1):PAGE165_I38@PURE_QUANTA.Q_CAP_DIFFBUS(CHIPS)':
 '2': CDS_PINID='\2\';
NET_NAME
'P5E_CPU0_PE1_TX_DP<7>'
 '@S9S_MB_2U_LIB.S9S_MB_2U(SCH_1):P5E_CPU0_PE1_TX_DP'<7>:
 C_SIGNAL='@s9s_mb_2u_lib.s9s_mb_2u(sch_1):p5e_cpu0_pe1_tx_dp(7)';
NODE_NAME     U2 BY14
 '@S9S_MB_2U_LIB.S9S_MB_2U(SCH_1):PAGE29_I176@PURE_QUANTA.SOCKET4677_AZIF0045P001C01CS(CHIPS)':
 'PE1_TX_DP7': CDS_PINID='PE1_TX_DP7';
NODE_NAME     C855 2
 '@S9S_MB_2U_LIB.S9S_MB_2U(SCH_1):PAGE165_I40@PURE_QUANTA.Q_CAP_DIFFBUS(CHIPS)':
 '2': CDS_PINID='\2\';
NET_NAME
'P5E_CPU0_PE1_TX_DP<8>'
 '@S9S_MB_2U_LIB.S9S_MB_2U(SCH_1):P5E_CPU0_PE1_TX_DP'<8>:
 C_SIGNAL='@s9s_mb_2u_lib.s9s_mb_2u(sch_1):p5e_cpu0_pe1_tx_dp(8)';
NODE_NAME     U2 BW15
 '@S9S_MB_2U_LIB.S9S_MB_2U(SCH_1):PAGE29_I176@PURE_QUANTA.SOCKET4677_AZIF0045P001C01CS(CHIPS)':
 'PE1_TX_DP8': CDS_PINID='PE1_TX_DP8';
NODE_NAME     C853 2
 '@S9S_MB_2U_LIB.S9S_MB_2U(SCH_1):PAGE165_I62@PURE_QUANTA.Q_CAP_DIFFBUS(CHIPS)':
 '2': CDS_PINID='\2\';
NET_NAME
'P5E_CPU0_PE1_TX_DP<9>'
 '@S9S_MB_2U_LIB.S9S_MB_2U(SCH_1):P5E_CPU0_PE1_TX_DP'<9>:
 C_SIGNAL='@s9s_mb_2u_lib.s9s_mb_2u(sch_1):p5e_cpu0_pe1_tx_dp(9)';
NODE_NAME     U2 BT14
 '@S9S_MB_2U_LIB.S9S_MB_2U(SCH_1):PAGE29_I176@PURE_QUANTA.SOCKET4677_AZIF0045P001C01CS(CHIPS)':
 'PE1_TX_DP9': CDS_PINID='PE1_TX_DP9';
NODE_NAME     C851 2
 '@S9S_MB_2U_LIB.S9S_MB_2U(SCH_1):PAGE165_I63@PURE_QUANTA.Q_CAP_DIFFBUS(CHIPS)':
 '2': CDS_PINID='\2\';
NET_NAME
'P5E_CPU0_PE2_RX_DN<0>'
 '@S9S_MB_2U_LIB.S9S_MB_2U(SCH_1):P5E_CPU0_PE2_RX_DN'<0>:
 C_SIGNAL='@s9s_mb_2u_lib.s9s_mb_2u(sch_1):p5e_cpu0_pe2_rx_dn(0)';
NODE_NAME     U2 CU9
 '@S9S_MB_2U_LIB.S9S_MB_2U(SCH_1):PAGE30_I139@PURE_QUANTA.SOCKET4677_AZIF0045P001C01CS(CHIPS)':
 'PE2_RX_DN0': CDS_PINID='PE2_RX_DN0';
NODE_NAME     J105 F8
 '@S9S_MB_2U_LIB.S9S_MB_2U(SCH_1):PAGE142_I68@PURE_QUANTA.CONN112_10137002101LF(CHIPS)':
 'F8': CDS_PINID='F8';
NET_NAME
'P5E_CPU0_PE2_RX_DN<10>'
 '@S9S_MB_2U_LIB.S9S_MB_2U(SCH_1):P5E_CPU0_PE2_RX_DN'<10>:
 C_SIGNAL='@s9s_mb_2u_lib.s9s_mb_2u(sch_1):p5e_cpu0_pe2_rx_dn(10)';
NODE_NAME     U2 DU9
 '@S9S_MB_2U_LIB.S9S_MB_2U(SCH_1):PAGE30_I139@PURE_QUANTA.SOCKET4677_AZIF0045P001C01CS(CHIPS)':
 'PE2_RX_DN10': CDS_PINID='PE2_RX_DN10';
NODE_NAME     J106 F6
 '@S9S_MB_2U_LIB.S9S_MB_2U(SCH_1):PAGE144_I68@PURE_QUANTA.CONN112_10137002101LF(CHIPS)':
 'F6': CDS_PINID='F6';
NET_NAME
'P5E_CPU0_PE2_RX_DN<11>'
 '@S9S_MB_2U_LIB.S9S_MB_2U(SCH_1):P5E_CPU0_PE2_RX_DN'<11>:
 C_SIGNAL='@s9s_mb_2u_lib.s9s_mb_2u(sch_1):p5e_cpu0_pe2_rx_dn(11)';
NODE_NAME     U2 DY10
 '@S9S_MB_2U_LIB.S9S_MB_2U(SCH_1):PAGE30_I139@PURE_QUANTA.SOCKET4677_AZIF0045P001C01CS(CHIPS)':
 'PE2_RX_DN11': CDS_PINID='PE2_RX_DN11';
NODE_NAME     J106 G5
 '@S9S_MB_2U_LIB.S9S_MB_2U(SCH_1):PAGE144_I68@PURE_QUANTA.CONN112_10137002101LF(CHIPS)':
 'G5': CDS_PINID='G5';
NET_NAME
'P5E_CPU0_PE2_RX_DN<12>'
 '@S9S_MB_2U_LIB.S9S_MB_2U(SCH_1):P5E_CPU0_PE2_RX_DN'<12>:
 C_SIGNAL='@s9s_mb_2u_lib.s9s_mb_2u(sch_1):p5e_cpu0_pe2_rx_dn(12)';
NODE_NAME     U2 EA9
 '@S9S_MB_2U_LIB.S9S_MB_2U(SCH_1):PAGE30_I139@PURE_QUANTA.SOCKET4677_AZIF0045P001C01CS(CHIPS)':
 'PE2_RX_DN12': CDS_PINID='PE2_RX_DN12';
NODE_NAME     J106 F4
 '@S9S_MB_2U_LIB.S9S_MB_2U(SCH_1):PAGE144_I65@PURE_QUANTA.CONN112_10137002101LF(CHIPS)':
 'F4': CDS_PINID='F4';
NET_NAME
'P5E_CPU0_PE2_RX_DN<13>'
 '@S9S_MB_2U_LIB.S9S_MB_2U(SCH_1):P5E_CPU0_PE2_RX_DN'<13>:
 C_SIGNAL='@s9s_mb_2u_lib.s9s_mb_2u(sch_1):p5e_cpu0_pe2_rx_dn(13)';
NODE_NAME     U2 ED10
 '@S9S_MB_2U_LIB.S9S_MB_2U(SCH_1):PAGE30_I139@PURE_QUANTA.SOCKET4677_AZIF0045P001C01CS(CHIPS)':
 'PE2_RX_DN13': CDS_PINID='PE2_RX_DN13';
NODE_NAME     J106 G3
 '@S9S_MB_2U_LIB.S9S_MB_2U(SCH_1):PAGE144_I65@PURE_QUANTA.CONN112_10137002101LF(CHIPS)':
 'G3': CDS_PINID='G3';
NET_NAME
'P5E_CPU0_PE2_RX_DN<14>'
 '@S9S_MB_2U_LIB.S9S_MB_2U(SCH_1):P5E_CPU0_PE2_RX_DN'<14>:
 C_SIGNAL='@s9s_mb_2u_lib.s9s_mb_2u(sch_1):p5e_cpu0_pe2_rx_dn(14)';
NODE_NAME     U2 EE9
 '@S9S_MB_2U_LIB.S9S_MB_2U(SCH_1):PAGE30_I139@PURE_QUANTA.SOCKET4677_AZIF0045P001C01CS(CHIPS)':
 'PE2_RX_DN14': CDS_PINID='PE2_RX_DN14';
NODE_NAME     J106 F2
 '@S9S_MB_2U_LIB.S9S_MB_2U(SCH_1):PAGE144_I65@PURE_QUANTA.CONN112_10137002101LF(CHIPS)':
 'F2': CDS_PINID='F2';
NET_NAME
'P5E_CPU0_PE2_RX_DN<15>'
 '@S9S_MB_2U_LIB.S9S_MB_2U(SCH_1):P5E_CPU0_PE2_RX_DN'<15>:
 C_SIGNAL='@s9s_mb_2u_lib.s9s_mb_2u(sch_1):p5e_cpu0_pe2_rx_dn(15)';
NODE_NAME     U2 EH10
 '@S9S_MB_2U_LIB.S9S_MB_2U(SCH_1):PAGE30_I139@PURE_QUANTA.SOCKET4677_AZIF0045P001C01CS(CHIPS)':
 'PE2_RX_DN15': CDS_PINID='PE2_RX_DN15';
NODE_NAME     J106 G1
 '@S9S_MB_2U_LIB.S9S_MB_2U(SCH_1):PAGE144_I65@PURE_QUANTA.CONN112_10137002101LF(CHIPS)':
 'G1': CDS_PINID='G1';
NET_NAME
'P5E_CPU0_PE2_RX_DN<1>'
 '@S9S_MB_2U_LIB.S9S_MB_2U(SCH_1):P5E_CPU0_PE2_RX_DN'<1>:
 C_SIGNAL='@s9s_mb_2u_lib.s9s_mb_2u(sch_1):p5e_cpu0_pe2_rx_dn(1)';
NODE_NAME     U2 CY10
 '@S9S_MB_2U_LIB.S9S_MB_2U(SCH_1):PAGE30_I139@PURE_QUANTA.SOCKET4677_AZIF0045P001C01CS(CHIPS)':
 'PE2_RX_DN1': CDS_PINID='PE2_RX_DN1';
NODE_NAME     J105 G7
 '@S9S_MB_2U_LIB.S9S_MB_2U(SCH_1):PAGE142_I68@PURE_QUANTA.CONN112_10137002101LF(CHIPS)':
 'G7': CDS_PINID='G7';
NET_NAME
'P5E_CPU0_PE2_RX_DN<2>'
 '@S9S_MB_2U_LIB.S9S_MB_2U(SCH_1):P5E_CPU0_PE2_RX_DN'<2>:
 C_SIGNAL='@s9s_mb_2u_lib.s9s_mb_2u(sch_1):p5e_cpu0_pe2_rx_dn(2)';
NODE_NAME     U2 DA9
 '@S9S_MB_2U_LIB.S9S_MB_2U(SCH_1):PAGE30_I139@PURE_QUANTA.SOCKET4677_AZIF0045P001C01CS(CHIPS)':
 'PE2_RX_DN2': CDS_PINID='PE2_RX_DN2';
NODE_NAME     J105 F6
 '@S9S_MB_2U_LIB.S9S_MB_2U(SCH_1):PAGE142_I68@PURE_QUANTA.CONN112_10137002101LF(CHIPS)':
 'F6': CDS_PINID='F6';
NET_NAME
'P5E_CPU0_PE2_RX_DN<3>'
 '@S9S_MB_2U_LIB.S9S_MB_2U(SCH_1):P5E_CPU0_PE2_RX_DN'<3>:
 C_SIGNAL='@s9s_mb_2u_lib.s9s_mb_2u(sch_1):p5e_cpu0_pe2_rx_dn(3)';
NODE_NAME     U2 DD10
 '@S9S_MB_2U_LIB.S9S_MB_2U(SCH_1):PAGE30_I139@PURE_QUANTA.SOCKET4677_AZIF0045P001C01CS(CHIPS)':
 'PE2_RX_DN3': CDS_PINID='PE2_RX_DN3';
NODE_NAME     J105 G5
 '@S9S_MB_2U_LIB.S9S_MB_2U(SCH_1):PAGE142_I68@PURE_QUANTA.CONN112_10137002101LF(CHIPS)':
 'G5': CDS_PINID='G5';
NET_NAME
'P5E_CPU0_PE2_RX_DN<4>'
 '@S9S_MB_2U_LIB.S9S_MB_2U(SCH_1):P5E_CPU0_PE2_RX_DN'<4>:
 C_SIGNAL='@s9s_mb_2u_lib.s9s_mb_2u(sch_1):p5e_cpu0_pe2_rx_dn(4)';
NODE_NAME     U2 DE9
 '@S9S_MB_2U_LIB.S9S_MB_2U(SCH_1):PAGE30_I139@PURE_QUANTA.SOCKET4677_AZIF0045P001C01CS(CHIPS)':
 'PE2_RX_DN4': CDS_PINID='PE2_RX_DN4';
NODE_NAME     J105 F4
 '@S9S_MB_2U_LIB.S9S_MB_2U(SCH_1):PAGE142_I65@PURE_QUANTA.CONN112_10137002101LF(CHIPS)':
 'F4': CDS_PINID='F4';
NET_NAME
'P5E_CPU0_PE2_RX_DN<5>'
 '@S9S_MB_2U_LIB.S9S_MB_2U(SCH_1):P5E_CPU0_PE2_RX_DN'<5>:
 C_SIGNAL='@s9s_mb_2u_lib.s9s_mb_2u(sch_1):p5e_cpu0_pe2_rx_dn(5)';
NODE_NAME     U2 DH10
 '@S9S_MB_2U_LIB.S9S_MB_2U(SCH_1):PAGE30_I139@PURE_QUANTA.SOCKET4677_AZIF0045P001C01CS(CHIPS)':
 'PE2_RX_DN5': CDS_PINID='PE2_RX_DN5';
NODE_NAME     J105 G3
 '@S9S_MB_2U_LIB.S9S_MB_2U(SCH_1):PAGE142_I65@PURE_QUANTA.CONN112_10137002101LF(CHIPS)':
 'G3': CDS_PINID='G3';
NET_NAME
'P5E_CPU0_PE2_RX_DN<6>'
 '@S9S_MB_2U_LIB.S9S_MB_2U(SCH_1):P5E_CPU0_PE2_RX_DN'<6>:
 C_SIGNAL='@s9s_mb_2u_lib.s9s_mb_2u(sch_1):p5e_cpu0_pe2_rx_dn(6)';
NODE_NAME     U2 DJ9
 '@S9S_MB_2U_LIB.S9S_MB_2U(SCH_1):PAGE30_I139@PURE_QUANTA.SOCKET4677_AZIF0045P001C01CS(CHIPS)':
 'PE2_RX_DN6': CDS_PINID='PE2_RX_DN6';
NODE_NAME     J105 F2
 '@S9S_MB_2U_LIB.S9S_MB_2U(SCH_1):PAGE142_I65@PURE_QUANTA.CONN112_10137002101LF(CHIPS)':
 'F2': CDS_PINID='F2';
NET_NAME
'P5E_CPU0_PE2_RX_DN<7>'
 '@S9S_MB_2U_LIB.S9S_MB_2U(SCH_1):P5E_CPU0_PE2_RX_DN'<7>:
 C_SIGNAL='@s9s_mb_2u_lib.s9s_mb_2u(sch_1):p5e_cpu0_pe2_rx_dn(7)';
NODE_NAME     U2 DM10
 '@S9S_MB_2U_LIB.S9S_MB_2U(SCH_1):PAGE30_I139@PURE_QUANTA.SOCKET4677_AZIF0045P001C01CS(CHIPS)':
 'PE2_RX_DN7': CDS_PINID='PE2_RX_DN7';
NODE_NAME     J105 G1
 '@S9S_MB_2U_LIB.S9S_MB_2U(SCH_1):PAGE142_I65@PURE_QUANTA.CONN112_10137002101LF(CHIPS)':
 'G1': CDS_PINID='G1';
NET_NAME
'P5E_CPU0_PE2_RX_DN<8>'
 '@S9S_MB_2U_LIB.S9S_MB_2U(SCH_1):P5E_CPU0_PE2_RX_DN'<8>:
 C_SIGNAL='@s9s_mb_2u_lib.s9s_mb_2u(sch_1):p5e_cpu0_pe2_rx_dn(8)';
NODE_NAME     U2 DN9
 '@S9S_MB_2U_LIB.S9S_MB_2U(SCH_1):PAGE30_I139@PURE_QUANTA.SOCKET4677_AZIF0045P001C01CS(CHIPS)':
 'PE2_RX_DN8': CDS_PINID='PE2_RX_DN8';
NODE_NAME     J106 F8
 '@S9S_MB_2U_LIB.S9S_MB_2U(SCH_1):PAGE144_I68@PURE_QUANTA.CONN112_10137002101LF(CHIPS)':
 'F8': CDS_PINID='F8';
NET_NAME
'P5E_CPU0_PE2_RX_DN<9>'
 '@S9S_MB_2U_LIB.S9S_MB_2U(SCH_1):P5E_CPU0_PE2_RX_DN'<9>:
 C_SIGNAL='@s9s_mb_2u_lib.s9s_mb_2u(sch_1):p5e_cpu0_pe2_rx_dn(9)';
NODE_NAME     U2 DT10
 '@S9S_MB_2U_LIB.S9S_MB_2U(SCH_1):PAGE30_I139@PURE_QUANTA.SOCKET4677_AZIF0045P001C01CS(CHIPS)':
 'PE2_RX_DN9': CDS_PINID='PE2_RX_DN9';
NODE_NAME     J106 G7
 '@S9S_MB_2U_LIB.S9S_MB_2U(SCH_1):PAGE144_I68@PURE_QUANTA.CONN112_10137002101LF(CHIPS)':
 'G7': CDS_PINID='G7';
NET_NAME
'P5E_CPU0_PE2_RX_DP<0>'
 '@S9S_MB_2U_LIB.S9S_MB_2U(SCH_1):P5E_CPU0_PE2_RX_DP'<0>:
 C_SIGNAL='@s9s_mb_2u_lib.s9s_mb_2u(sch_1):p5e_cpu0_pe2_rx_dp(0)';
NODE_NAME     U2 CV10
 '@S9S_MB_2U_LIB.S9S_MB_2U(SCH_1):PAGE30_I139@PURE_QUANTA.SOCKET4677_AZIF0045P001C01CS(CHIPS)':
 'PE2_RX_DP0': CDS_PINID='PE2_RX_DP0';
NODE_NAME     J105 E8
 '@S9S_MB_2U_LIB.S9S_MB_2U(SCH_1):PAGE142_I68@PURE_QUANTA.CONN112_10137002101LF(CHIPS)':
 'E8': CDS_PINID='E8';
NET_NAME
'P5E_CPU0_PE2_RX_DP<10>'
 '@S9S_MB_2U_LIB.S9S_MB_2U(SCH_1):P5E_CPU0_PE2_RX_DP'<10>:
 C_SIGNAL='@s9s_mb_2u_lib.s9s_mb_2u(sch_1):p5e_cpu0_pe2_rx_dp(10)';
NODE_NAME     U2 DV10
 '@S9S_MB_2U_LIB.S9S_MB_2U(SCH_1):PAGE30_I139@PURE_QUANTA.SOCKET4677_AZIF0045P001C01CS(CHIPS)':
 'PE2_RX_DP10': CDS_PINID='PE2_RX_DP10';
NODE_NAME     J106 E6
 '@S9S_MB_2U_LIB.S9S_MB_2U(SCH_1):PAGE144_I68@PURE_QUANTA.CONN112_10137002101LF(CHIPS)':
 'E6': CDS_PINID='E6';
NET_NAME
'P5E_CPU0_PE2_RX_DP<11>'
 '@S9S_MB_2U_LIB.S9S_MB_2U(SCH_1):P5E_CPU0_PE2_RX_DP'<11>:
 C_SIGNAL='@s9s_mb_2u_lib.s9s_mb_2u(sch_1):p5e_cpu0_pe2_rx_dp(11)';
NODE_NAME     U2 DW11
 '@S9S_MB_2U_LIB.S9S_MB_2U(SCH_1):PAGE30_I139@PURE_QUANTA.SOCKET4677_AZIF0045P001C01CS(CHIPS)':
 'PE2_RX_DP11': CDS_PINID='PE2_RX_DP11';
NODE_NAME     J106 F5
 '@S9S_MB_2U_LIB.S9S_MB_2U(SCH_1):PAGE144_I68@PURE_QUANTA.CONN112_10137002101LF(CHIPS)':
 'F5': CDS_PINID='F5';
NET_NAME
'P5E_CPU0_PE2_RX_DP<12>'
 '@S9S_MB_2U_LIB.S9S_MB_2U(SCH_1):P5E_CPU0_PE2_RX_DP'<12>:
 C_SIGNAL='@s9s_mb_2u_lib.s9s_mb_2u(sch_1):p5e_cpu0_pe2_rx_dp(12)';
NODE_NAME     U2 EB10
 '@S9S_MB_2U_LIB.S9S_MB_2U(SCH_1):PAGE30_I139@PURE_QUANTA.SOCKET4677_AZIF0045P001C01CS(CHIPS)':
 'PE2_RX_DP12': CDS_PINID='PE2_RX_DP12';
NODE_NAME     J106 E4
 '@S9S_MB_2U_LIB.S9S_MB_2U(SCH_1):PAGE144_I65@PURE_QUANTA.CONN112_10137002101LF(CHIPS)':
 'E4': CDS_PINID='E4';
NET_NAME
'P5E_CPU0_PE2_RX_DP<13>'
 '@S9S_MB_2U_LIB.S9S_MB_2U(SCH_1):P5E_CPU0_PE2_RX_DP'<13>:
 C_SIGNAL='@s9s_mb_2u_lib.s9s_mb_2u(sch_1):p5e_cpu0_pe2_rx_dp(13)';
NODE_NAME     U2 EC11
 '@S9S_MB_2U_LIB.S9S_MB_2U(SCH_1):PAGE30_I139@PURE_QUANTA.SOCKET4677_AZIF0045P001C01CS(CHIPS)':
 'PE2_RX_DP13': CDS_PINID='PE2_RX_DP13';
NODE_NAME     J106 F3
 '@S9S_MB_2U_LIB.S9S_MB_2U(SCH_1):PAGE144_I65@PURE_QUANTA.CONN112_10137002101LF(CHIPS)':
 'F3': CDS_PINID='F3';
NET_NAME
'P5E_CPU0_PE2_RX_DP<14>'
 '@S9S_MB_2U_LIB.S9S_MB_2U(SCH_1):P5E_CPU0_PE2_RX_DP'<14>:
 C_SIGNAL='@s9s_mb_2u_lib.s9s_mb_2u(sch_1):p5e_cpu0_pe2_rx_dp(14)';
NODE_NAME     U2 EF10
 '@S9S_MB_2U_LIB.S9S_MB_2U(SCH_1):PAGE30_I139@PURE_QUANTA.SOCKET4677_AZIF0045P001C01CS(CHIPS)':
 'PE2_RX_DP14': CDS_PINID='PE2_RX_DP14';
NODE_NAME     J106 E2
 '@S9S_MB_2U_LIB.S9S_MB_2U(SCH_1):PAGE144_I65@PURE_QUANTA.CONN112_10137002101LF(CHIPS)':
 'E2': CDS_PINID='E2';
NET_NAME
'P5E_CPU0_PE2_RX_DP<15>'
 '@S9S_MB_2U_LIB.S9S_MB_2U(SCH_1):P5E_CPU0_PE2_RX_DP'<15>:
 C_SIGNAL='@s9s_mb_2u_lib.s9s_mb_2u(sch_1):p5e_cpu0_pe2_rx_dp(15)';
NODE_NAME     U2 EG11
 '@S9S_MB_2U_LIB.S9S_MB_2U(SCH_1):PAGE30_I139@PURE_QUANTA.SOCKET4677_AZIF0045P001C01CS(CHIPS)':
 'PE2_RX_DP15': CDS_PINID='PE2_RX_DP15';
NODE_NAME     J106 F1
 '@S9S_MB_2U_LIB.S9S_MB_2U(SCH_1):PAGE144_I65@PURE_QUANTA.CONN112_10137002101LF(CHIPS)':
 'F1': CDS_PINID='F1';
NET_NAME
'P5E_CPU0_PE2_RX_DP<1>'
 '@S9S_MB_2U_LIB.S9S_MB_2U(SCH_1):P5E_CPU0_PE2_RX_DP'<1>:
 C_SIGNAL='@s9s_mb_2u_lib.s9s_mb_2u(sch_1):p5e_cpu0_pe2_rx_dp(1)';
NODE_NAME     U2 CW11
 '@S9S_MB_2U_LIB.S9S_MB_2U(SCH_1):PAGE30_I139@PURE_QUANTA.SOCKET4677_AZIF0045P001C01CS(CHIPS)':
 'PE2_RX_DP1': CDS_PINID='PE2_RX_DP1';
NODE_NAME     J105 F7
 '@S9S_MB_2U_LIB.S9S_MB_2U(SCH_1):PAGE142_I68@PURE_QUANTA.CONN112_10137002101LF(CHIPS)':
 'F7': CDS_PINID='F7';
NET_NAME
'P5E_CPU0_PE2_RX_DP<2>'
 '@S9S_MB_2U_LIB.S9S_MB_2U(SCH_1):P5E_CPU0_PE2_RX_DP'<2>:
 C_SIGNAL='@s9s_mb_2u_lib.s9s_mb_2u(sch_1):p5e_cpu0_pe2_rx_dp(2)';
NODE_NAME     U2 DB10
 '@S9S_MB_2U_LIB.S9S_MB_2U(SCH_1):PAGE30_I139@PURE_QUANTA.SOCKET4677_AZIF0045P001C01CS(CHIPS)':
 'PE2_RX_DP2': CDS_PINID='PE2_RX_DP2';
NODE_NAME     J105 E6
 '@S9S_MB_2U_LIB.S9S_MB_2U(SCH_1):PAGE142_I68@PURE_QUANTA.CONN112_10137002101LF(CHIPS)':
 'E6': CDS_PINID='E6';
NET_NAME
'P5E_CPU0_PE2_RX_DP<3>'
 '@S9S_MB_2U_LIB.S9S_MB_2U(SCH_1):P5E_CPU0_PE2_RX_DP'<3>:
 C_SIGNAL='@s9s_mb_2u_lib.s9s_mb_2u(sch_1):p5e_cpu0_pe2_rx_dp(3)';
NODE_NAME     U2 DC11
 '@S9S_MB_2U_LIB.S9S_MB_2U(SCH_1):PAGE30_I139@PURE_QUANTA.SOCKET4677_AZIF0045P001C01CS(CHIPS)':
 'PE2_RX_DP3': CDS_PINID='PE2_RX_DP3';
NODE_NAME     J105 F5
 '@S9S_MB_2U_LIB.S9S_MB_2U(SCH_1):PAGE142_I68@PURE_QUANTA.CONN112_10137002101LF(CHIPS)':
 'F5': CDS_PINID='F5';
NET_NAME
'P5E_CPU0_PE2_RX_DP<4>'
 '@S9S_MB_2U_LIB.S9S_MB_2U(SCH_1):P5E_CPU0_PE2_RX_DP'<4>:
 C_SIGNAL='@s9s_mb_2u_lib.s9s_mb_2u(sch_1):p5e_cpu0_pe2_rx_dp(4)';
NODE_NAME     U2 DF10
 '@S9S_MB_2U_LIB.S9S_MB_2U(SCH_1):PAGE30_I139@PURE_QUANTA.SOCKET4677_AZIF0045P001C01CS(CHIPS)':
 'PE2_RX_DP4': CDS_PINID='PE2_RX_DP4';
NODE_NAME     J105 E4
 '@S9S_MB_2U_LIB.S9S_MB_2U(SCH_1):PAGE142_I65@PURE_QUANTA.CONN112_10137002101LF(CHIPS)':
 'E4': CDS_PINID='E4';
NET_NAME
'P5E_CPU0_PE2_RX_DP<5>'
 '@S9S_MB_2U_LIB.S9S_MB_2U(SCH_1):P5E_CPU0_PE2_RX_DP'<5>:
 C_SIGNAL='@s9s_mb_2u_lib.s9s_mb_2u(sch_1):p5e_cpu0_pe2_rx_dp(5)';
NODE_NAME     U2 DG11
 '@S9S_MB_2U_LIB.S9S_MB_2U(SCH_1):PAGE30_I139@PURE_QUANTA.SOCKET4677_AZIF0045P001C01CS(CHIPS)':
 'PE2_RX_DP5': CDS_PINID='PE2_RX_DP5';
NODE_NAME     J105 F3
 '@S9S_MB_2U_LIB.S9S_MB_2U(SCH_1):PAGE142_I65@PURE_QUANTA.CONN112_10137002101LF(CHIPS)':
 'F3': CDS_PINID='F3';
NET_NAME
'P5E_CPU0_PE2_RX_DP<6>'
 '@S9S_MB_2U_LIB.S9S_MB_2U(SCH_1):P5E_CPU0_PE2_RX_DP'<6>:
 C_SIGNAL='@s9s_mb_2u_lib.s9s_mb_2u(sch_1):p5e_cpu0_pe2_rx_dp(6)';
NODE_NAME     U2 DK10
 '@S9S_MB_2U_LIB.S9S_MB_2U(SCH_1):PAGE30_I139@PURE_QUANTA.SOCKET4677_AZIF0045P001C01CS(CHIPS)':
 'PE2_RX_DP6': CDS_PINID='PE2_RX_DP6';
NODE_NAME     J105 E2
 '@S9S_MB_2U_LIB.S9S_MB_2U(SCH_1):PAGE142_I65@PURE_QUANTA.CONN112_10137002101LF(CHIPS)':
 'E2': CDS_PINID='E2';
NET_NAME
'P5E_CPU0_PE2_RX_DP<7>'
 '@S9S_MB_2U_LIB.S9S_MB_2U(SCH_1):P5E_CPU0_PE2_RX_DP'<7>:
 C_SIGNAL='@s9s_mb_2u_lib.s9s_mb_2u(sch_1):p5e_cpu0_pe2_rx_dp(7)';
NODE_NAME     U2 DL11
 '@S9S_MB_2U_LIB.S9S_MB_2U(SCH_1):PAGE30_I139@PURE_QUANTA.SOCKET4677_AZIF0045P001C01CS(CHIPS)':
 'PE2_RX_DP7': CDS_PINID='PE2_RX_DP7';
NODE_NAME     J105 F1
 '@S9S_MB_2U_LIB.S9S_MB_2U(SCH_1):PAGE142_I65@PURE_QUANTA.CONN112_10137002101LF(CHIPS)':
 'F1': CDS_PINID='F1';
NET_NAME
'P5E_CPU0_PE2_RX_DP<8>'
 '@S9S_MB_2U_LIB.S9S_MB_2U(SCH_1):P5E_CPU0_PE2_RX_DP'<8>:
 C_SIGNAL='@s9s_mb_2u_lib.s9s_mb_2u(sch_1):p5e_cpu0_pe2_rx_dp(8)';
NODE_NAME     U2 DP10
 '@S9S_MB_2U_LIB.S9S_MB_2U(SCH_1):PAGE30_I139@PURE_QUANTA.SOCKET4677_AZIF0045P001C01CS(CHIPS)':
 'PE2_RX_DP8': CDS_PINID='PE2_RX_DP8';
NODE_NAME     J106 E8
 '@S9S_MB_2U_LIB.S9S_MB_2U(SCH_1):PAGE144_I68@PURE_QUANTA.CONN112_10137002101LF(CHIPS)':
 'E8': CDS_PINID='E8';
NET_NAME
'P5E_CPU0_PE2_RX_DP<9>'
 '@S9S_MB_2U_LIB.S9S_MB_2U(SCH_1):P5E_CPU0_PE2_RX_DP'<9>:
 C_SIGNAL='@s9s_mb_2u_lib.s9s_mb_2u(sch_1):p5e_cpu0_pe2_rx_dp(9)';
NODE_NAME     U2 DR11
 '@S9S_MB_2U_LIB.S9S_MB_2U(SCH_1):PAGE30_I139@PURE_QUANTA.SOCKET4677_AZIF0045P001C01CS(CHIPS)':
 'PE2_RX_DP9': CDS_PINID='PE2_RX_DP9';
NODE_NAME     J106 F7
 '@S9S_MB_2U_LIB.S9S_MB_2U(SCH_1):PAGE144_I68@PURE_QUANTA.CONN112_10137002101LF(CHIPS)':
 'F7': CDS_PINID='F7';
NET_NAME
'P5E_CPU0_PE2_TX_C_DN<0>'
 '@S9S_MB_2U_LIB.S9S_MB_2U(SCH_1):P5E_CPU0_PE2_TX_C_DN'<0>:
 C_SIGNAL='@s9s_mb_2u_lib.s9s_mb_2u(sch_1):p5e_cpu0_pe2_tx_c_dn(0)';
NODE_NAME     C964 1
 '@S9S_MB_2U_LIB.S9S_MB_2U(SCH_1):PAGE164_I122@PURE_QUANTA.Q_CAP_DIFFBUS(CHIPS)':
 '1': CDS_PINID='\1\';
NODE_NAME     J105 L8
 '@S9S_MB_2U_LIB.S9S_MB_2U(SCH_1):PAGE142_I68@PURE_QUANTA.CONN112_10137002101LF(CHIPS)':
 'L8': CDS_PINID='L8';
NET_NAME
'P5E_CPU0_PE2_TX_C_DN<10>'
 '@S9S_MB_2U_LIB.S9S_MB_2U(SCH_1):P5E_CPU0_PE2_TX_C_DN'<10>:
 C_SIGNAL='@s9s_mb_2u_lib.s9s_mb_2u(sch_1):p5e_cpu0_pe2_tx_c_dn(10)';
NODE_NAME     C944 1
 '@S9S_MB_2U_LIB.S9S_MB_2U(SCH_1):PAGE164_I156@PURE_QUANTA.Q_CAP_DIFFBUS(CHIPS)':
 '1': CDS_PINID='\1\';
NODE_NAME     J106 L6
 '@S9S_MB_2U_LIB.S9S_MB_2U(SCH_1):PAGE144_I68@PURE_QUANTA.CONN112_10137002101LF(CHIPS)':
 'L6': CDS_PINID='L6';
NET_NAME
'P5E_CPU0_PE2_TX_C_DN<11>'
 '@S9S_MB_2U_LIB.S9S_MB_2U(SCH_1):P5E_CPU0_PE2_TX_C_DN'<11>:
 C_SIGNAL='@s9s_mb_2u_lib.s9s_mb_2u(sch_1):p5e_cpu0_pe2_tx_c_dn(11)';
NODE_NAME     C942 1
 '@S9S_MB_2U_LIB.S9S_MB_2U(SCH_1):PAGE164_I158@PURE_QUANTA.Q_CAP_DIFFBUS(CHIPS)':
 '1': CDS_PINID='\1\';
NODE_NAME     J106 M5
 '@S9S_MB_2U_LIB.S9S_MB_2U(SCH_1):PAGE144_I68@PURE_QUANTA.CONN112_10137002101LF(CHIPS)':
 'M5': CDS_PINID='M5';
NET_NAME
'P5E_CPU0_PE2_TX_C_DN<12>'
 '@S9S_MB_2U_LIB.S9S_MB_2U(SCH_1):P5E_CPU0_PE2_TX_C_DN'<12>:
 C_SIGNAL='@s9s_mb_2u_lib.s9s_mb_2u(sch_1):p5e_cpu0_pe2_tx_c_dn(12)';
NODE_NAME     C940 1
 '@S9S_MB_2U_LIB.S9S_MB_2U(SCH_1):PAGE164_I160@PURE_QUANTA.Q_CAP_DIFFBUS(CHIPS)':
 '1': CDS_PINID='\1\';
NODE_NAME     J106 L4
 '@S9S_MB_2U_LIB.S9S_MB_2U(SCH_1):PAGE144_I65@PURE_QUANTA.CONN112_10137002101LF(CHIPS)':
 'L4': CDS_PINID='L4';
NET_NAME
'P5E_CPU0_PE2_TX_C_DN<13>'
 '@S9S_MB_2U_LIB.S9S_MB_2U(SCH_1):P5E_CPU0_PE2_TX_C_DN'<13>:
 C_SIGNAL='@s9s_mb_2u_lib.s9s_mb_2u(sch_1):p5e_cpu0_pe2_tx_c_dn(13)';
NODE_NAME     C938 1
 '@S9S_MB_2U_LIB.S9S_MB_2U(SCH_1):PAGE164_I165@PURE_QUANTA.Q_CAP_DIFFBUS(CHIPS)':
 '1': CDS_PINID='\1\';
NODE_NAME     J106 M3
 '@S9S_MB_2U_LIB.S9S_MB_2U(SCH_1):PAGE144_I65@PURE_QUANTA.CONN112_10137002101LF(CHIPS)':
 'M3': CDS_PINID='M3';
NET_NAME
'P5E_CPU0_PE2_TX_C_DN<14>'
 '@S9S_MB_2U_LIB.S9S_MB_2U(SCH_1):P5E_CPU0_PE2_TX_C_DN'<14>:
 C_SIGNAL='@s9s_mb_2u_lib.s9s_mb_2u(sch_1):p5e_cpu0_pe2_tx_c_dn(14)';
NODE_NAME     C936 1
 '@S9S_MB_2U_LIB.S9S_MB_2U(SCH_1):PAGE164_I167@PURE_QUANTA.Q_CAP_DIFFBUS(CHIPS)':
 '1': CDS_PINID='\1\';
NODE_NAME     J106 L2
 '@S9S_MB_2U_LIB.S9S_MB_2U(SCH_1):PAGE144_I65@PURE_QUANTA.CONN112_10137002101LF(CHIPS)':
 'L2': CDS_PINID='L2';
NET_NAME
'P5E_CPU0_PE2_TX_C_DN<15>'
 '@S9S_MB_2U_LIB.S9S_MB_2U(SCH_1):P5E_CPU0_PE2_TX_C_DN'<15>:
 C_SIGNAL='@s9s_mb_2u_lib.s9s_mb_2u(sch_1):p5e_cpu0_pe2_tx_c_dn(15)';
NODE_NAME     C934 1
 '@S9S_MB_2U_LIB.S9S_MB_2U(SCH_1):PAGE164_I169@PURE_QUANTA.Q_CAP_DIFFBUS(CHIPS)':
 '1': CDS_PINID='\1\';
NODE_NAME     J106 L1
 '@S9S_MB_2U_LIB.S9S_MB_2U(SCH_1):PAGE144_I65@PURE_QUANTA.CONN112_10137002101LF(CHIPS)':
 'L1': CDS_PINID='L1';
NET_NAME
'P5E_CPU0_PE2_TX_C_DN<1>'
 '@S9S_MB_2U_LIB.S9S_MB_2U(SCH_1):P5E_CPU0_PE2_TX_C_DN'<1>:
 C_SIGNAL='@s9s_mb_2u_lib.s9s_mb_2u(sch_1):p5e_cpu0_pe2_tx_c_dn(1)';
NODE_NAME     C962 1
 '@S9S_MB_2U_LIB.S9S_MB_2U(SCH_1):PAGE164_I124@PURE_QUANTA.Q_CAP_DIFFBUS(CHIPS)':
 '1': CDS_PINID='\1\';
NODE_NAME     J105 M7
 '@S9S_MB_2U_LIB.S9S_MB_2U(SCH_1):PAGE142_I68@PURE_QUANTA.CONN112_10137002101LF(CHIPS)':
 'M7': CDS_PINID='M7';
NET_NAME
'P5E_CPU0_PE2_TX_C_DN<2>'
 '@S9S_MB_2U_LIB.S9S_MB_2U(SCH_1):P5E_CPU0_PE2_TX_C_DN'<2>:
 C_SIGNAL='@s9s_mb_2u_lib.s9s_mb_2u(sch_1):p5e_cpu0_pe2_tx_c_dn(2)';
NODE_NAME     C960 1
 '@S9S_MB_2U_LIB.S9S_MB_2U(SCH_1):PAGE164_I126@PURE_QUANTA.Q_CAP_DIFFBUS(CHIPS)':
 '1': CDS_PINID='\1\';
NODE_NAME     J105 L6
 '@S9S_MB_2U_LIB.S9S_MB_2U(SCH_1):PAGE142_I68@PURE_QUANTA.CONN112_10137002101LF(CHIPS)':
 'L6': CDS_PINID='L6';
NET_NAME
'P5E_CPU0_PE2_TX_C_DN<3>'
 '@S9S_MB_2U_LIB.S9S_MB_2U(SCH_1):P5E_CPU0_PE2_TX_C_DN'<3>:
 C_SIGNAL='@s9s_mb_2u_lib.s9s_mb_2u(sch_1):p5e_cpu0_pe2_tx_c_dn(3)';
NODE_NAME     C958 1
 '@S9S_MB_2U_LIB.S9S_MB_2U(SCH_1):PAGE164_I128@PURE_QUANTA.Q_CAP_DIFFBUS(CHIPS)':
 '1': CDS_PINID='\1\';
NODE_NAME     J105 M5
 '@S9S_MB_2U_LIB.S9S_MB_2U(SCH_1):PAGE142_I68@PURE_QUANTA.CONN112_10137002101LF(CHIPS)':
 'M5': CDS_PINID='M5';
NET_NAME
'P5E_CPU0_PE2_TX_C_DN<4>'
 '@S9S_MB_2U_LIB.S9S_MB_2U(SCH_1):P5E_CPU0_PE2_TX_C_DN'<4>:
 C_SIGNAL='@s9s_mb_2u_lib.s9s_mb_2u(sch_1):p5e_cpu0_pe2_tx_c_dn(4)';
NODE_NAME     C956 1
 '@S9S_MB_2U_LIB.S9S_MB_2U(SCH_1):PAGE164_I207@PURE_QUANTA.Q_CAP_DIFFBUS(CHIPS)':
 '1': CDS_PINID='\1\';
NODE_NAME     J105 L4
 '@S9S_MB_2U_LIB.S9S_MB_2U(SCH_1):PAGE142_I65@PURE_QUANTA.CONN112_10137002101LF(CHIPS)':
 'L4': CDS_PINID='L4';
NET_NAME
'P5E_CPU0_PE2_TX_C_DN<5>'
 '@S9S_MB_2U_LIB.S9S_MB_2U(SCH_1):P5E_CPU0_PE2_TX_C_DN'<5>:
 C_SIGNAL='@s9s_mb_2u_lib.s9s_mb_2u(sch_1):p5e_cpu0_pe2_tx_c_dn(5)';
NODE_NAME     C954 1
 '@S9S_MB_2U_LIB.S9S_MB_2U(SCH_1):PAGE164_I133@PURE_QUANTA.Q_CAP_DIFFBUS(CHIPS)':
 '1': CDS_PINID='\1\';
NODE_NAME     J105 M3
 '@S9S_MB_2U_LIB.S9S_MB_2U(SCH_1):PAGE142_I65@PURE_QUANTA.CONN112_10137002101LF(CHIPS)':
 'M3': CDS_PINID='M3';
NET_NAME
'P5E_CPU0_PE2_TX_C_DN<6>'
 '@S9S_MB_2U_LIB.S9S_MB_2U(SCH_1):P5E_CPU0_PE2_TX_C_DN'<6>:
 C_SIGNAL='@s9s_mb_2u_lib.s9s_mb_2u(sch_1):p5e_cpu0_pe2_tx_c_dn(6)';
NODE_NAME     C952 1
 '@S9S_MB_2U_LIB.S9S_MB_2U(SCH_1):PAGE164_I135@PURE_QUANTA.Q_CAP_DIFFBUS(CHIPS)':
 '1': CDS_PINID='\1\';
NODE_NAME     J105 L2
 '@S9S_MB_2U_LIB.S9S_MB_2U(SCH_1):PAGE142_I65@PURE_QUANTA.CONN112_10137002101LF(CHIPS)':
 'L2': CDS_PINID='L2';
NET_NAME
'P5E_CPU0_PE2_TX_C_DN<7>'
 '@S9S_MB_2U_LIB.S9S_MB_2U(SCH_1):P5E_CPU0_PE2_TX_C_DN'<7>:
 C_SIGNAL='@s9s_mb_2u_lib.s9s_mb_2u(sch_1):p5e_cpu0_pe2_tx_c_dn(7)';
NODE_NAME     C950 1
 '@S9S_MB_2U_LIB.S9S_MB_2U(SCH_1):PAGE164_I137@PURE_QUANTA.Q_CAP_DIFFBUS(CHIPS)':
 '1': CDS_PINID='\1\';
NODE_NAME     J105 M1
 '@S9S_MB_2U_LIB.S9S_MB_2U(SCH_1):PAGE142_I65@PURE_QUANTA.CONN112_10137002101LF(CHIPS)':
 'M1': CDS_PINID='M1';
NET_NAME
'P5E_CPU0_PE2_TX_C_DN<8>'
 '@S9S_MB_2U_LIB.S9S_MB_2U(SCH_1):P5E_CPU0_PE2_TX_C_DN'<8>:
 C_SIGNAL='@s9s_mb_2u_lib.s9s_mb_2u(sch_1):p5e_cpu0_pe2_tx_c_dn(8)';
NODE_NAME     C948 1
 '@S9S_MB_2U_LIB.S9S_MB_2U(SCH_1):PAGE164_I152@PURE_QUANTA.Q_CAP_DIFFBUS(CHIPS)':
 '1': CDS_PINID='\1\';
NODE_NAME     J106 L8
 '@S9S_MB_2U_LIB.S9S_MB_2U(SCH_1):PAGE144_I68@PURE_QUANTA.CONN112_10137002101LF(CHIPS)':
 'L8': CDS_PINID='L8';
NET_NAME
'P5E_CPU0_PE2_TX_C_DN<9>'
 '@S9S_MB_2U_LIB.S9S_MB_2U(SCH_1):P5E_CPU0_PE2_TX_C_DN'<9>:
 C_SIGNAL='@s9s_mb_2u_lib.s9s_mb_2u(sch_1):p5e_cpu0_pe2_tx_c_dn(9)';
NODE_NAME     C946 1
 '@S9S_MB_2U_LIB.S9S_MB_2U(SCH_1):PAGE164_I154@PURE_QUANTA.Q_CAP_DIFFBUS(CHIPS)':
 '1': CDS_PINID='\1\';
NODE_NAME     J106 M7
 '@S9S_MB_2U_LIB.S9S_MB_2U(SCH_1):PAGE144_I68@PURE_QUANTA.CONN112_10137002101LF(CHIPS)':
 'M7': CDS_PINID='M7';
NET_NAME
'P5E_CPU0_PE2_TX_C_DP<0>'
 '@S9S_MB_2U_LIB.S9S_MB_2U(SCH_1):P5E_CPU0_PE2_TX_C_DP'<0>:
 C_SIGNAL='@s9s_mb_2u_lib.s9s_mb_2u(sch_1):p5e_cpu0_pe2_tx_c_dp(0)';
NODE_NAME     C965 1
 '@S9S_MB_2U_LIB.S9S_MB_2U(SCH_1):PAGE164_I121@PURE_QUANTA.Q_CAP_DIFFBUS(CHIPS)':
 '1': CDS_PINID='\1\';
NODE_NAME     J105 K8
 '@S9S_MB_2U_LIB.S9S_MB_2U(SCH_1):PAGE142_I68@PURE_QUANTA.CONN112_10137002101LF(CHIPS)':
 'K8': CDS_PINID='K8';
NET_NAME
'P5E_CPU0_PE2_TX_C_DP<10>'
 '@S9S_MB_2U_LIB.S9S_MB_2U(SCH_1):P5E_CPU0_PE2_TX_C_DP'<10>:
 C_SIGNAL='@s9s_mb_2u_lib.s9s_mb_2u(sch_1):p5e_cpu0_pe2_tx_c_dp(10)';
NODE_NAME     C945 1
 '@S9S_MB_2U_LIB.S9S_MB_2U(SCH_1):PAGE164_I155@PURE_QUANTA.Q_CAP_DIFFBUS(CHIPS)':
 '1': CDS_PINID='\1\';
NODE_NAME     J106 K6
 '@S9S_MB_2U_LIB.S9S_MB_2U(SCH_1):PAGE144_I68@PURE_QUANTA.CONN112_10137002101LF(CHIPS)':
 'K6': CDS_PINID='K6';
NET_NAME
'P5E_CPU0_PE2_TX_C_DP<11>'
 '@S9S_MB_2U_LIB.S9S_MB_2U(SCH_1):P5E_CPU0_PE2_TX_C_DP'<11>:
 C_SIGNAL='@s9s_mb_2u_lib.s9s_mb_2u(sch_1):p5e_cpu0_pe2_tx_c_dp(11)';
NODE_NAME     C943 1
 '@S9S_MB_2U_LIB.S9S_MB_2U(SCH_1):PAGE164_I157@PURE_QUANTA.Q_CAP_DIFFBUS(CHIPS)':
 '1': CDS_PINID='\1\';
NODE_NAME     J106 L5
 '@S9S_MB_2U_LIB.S9S_MB_2U(SCH_1):PAGE144_I68@PURE_QUANTA.CONN112_10137002101LF(CHIPS)':
 'L5': CDS_PINID='L5';
NET_NAME
'P5E_CPU0_PE2_TX_C_DP<12>'
 '@S9S_MB_2U_LIB.S9S_MB_2U(SCH_1):P5E_CPU0_PE2_TX_C_DP'<12>:
 C_SIGNAL='@s9s_mb_2u_lib.s9s_mb_2u(sch_1):p5e_cpu0_pe2_tx_c_dp(12)';
NODE_NAME     C941 1
 '@S9S_MB_2U_LIB.S9S_MB_2U(SCH_1):PAGE164_I159@PURE_QUANTA.Q_CAP_DIFFBUS(CHIPS)':
 '1': CDS_PINID='\1\';
NODE_NAME     J106 K4
 '@S9S_MB_2U_LIB.S9S_MB_2U(SCH_1):PAGE144_I65@PURE_QUANTA.CONN112_10137002101LF(CHIPS)':
 'K4': CDS_PINID='K4';
NET_NAME
'P5E_CPU0_PE2_TX_C_DP<13>'
 '@S9S_MB_2U_LIB.S9S_MB_2U(SCH_1):P5E_CPU0_PE2_TX_C_DP'<13>:
 C_SIGNAL='@s9s_mb_2u_lib.s9s_mb_2u(sch_1):p5e_cpu0_pe2_tx_c_dp(13)';
NODE_NAME     C939 1
 '@S9S_MB_2U_LIB.S9S_MB_2U(SCH_1):PAGE164_I164@PURE_QUANTA.Q_CAP_DIFFBUS(CHIPS)':
 '1': CDS_PINID='\1\';
NODE_NAME     J106 L3
 '@S9S_MB_2U_LIB.S9S_MB_2U(SCH_1):PAGE144_I65@PURE_QUANTA.CONN112_10137002101LF(CHIPS)':
 'L3': CDS_PINID='L3';
NET_NAME
'P5E_CPU0_PE2_TX_C_DP<14>'
 '@S9S_MB_2U_LIB.S9S_MB_2U(SCH_1):P5E_CPU0_PE2_TX_C_DP'<14>:
 C_SIGNAL='@s9s_mb_2u_lib.s9s_mb_2u(sch_1):p5e_cpu0_pe2_tx_c_dp(14)';
NODE_NAME     C937 1
 '@S9S_MB_2U_LIB.S9S_MB_2U(SCH_1):PAGE164_I166@PURE_QUANTA.Q_CAP_DIFFBUS(CHIPS)':
 '1': CDS_PINID='\1\';
NODE_NAME     J106 K2
 '@S9S_MB_2U_LIB.S9S_MB_2U(SCH_1):PAGE144_I65@PURE_QUANTA.CONN112_10137002101LF(CHIPS)':
 'K2': CDS_PINID='K2';
NET_NAME
'P5E_CPU0_PE2_TX_C_DP<15>'
 '@S9S_MB_2U_LIB.S9S_MB_2U(SCH_1):P5E_CPU0_PE2_TX_C_DP'<15>:
 C_SIGNAL='@s9s_mb_2u_lib.s9s_mb_2u(sch_1):p5e_cpu0_pe2_tx_c_dp(15)';
NODE_NAME     C935 1
 '@S9S_MB_2U_LIB.S9S_MB_2U(SCH_1):PAGE164_I168@PURE_QUANTA.Q_CAP_DIFFBUS(CHIPS)':
 '1': CDS_PINID='\1\';
NODE_NAME     J106 M1
 '@S9S_MB_2U_LIB.S9S_MB_2U(SCH_1):PAGE144_I65@PURE_QUANTA.CONN112_10137002101LF(CHIPS)':
 'M1': CDS_PINID='M1';
NET_NAME
'P5E_CPU0_PE2_TX_C_DP<1>'
 '@S9S_MB_2U_LIB.S9S_MB_2U(SCH_1):P5E_CPU0_PE2_TX_C_DP'<1>:
 C_SIGNAL='@s9s_mb_2u_lib.s9s_mb_2u(sch_1):p5e_cpu0_pe2_tx_c_dp(1)';
NODE_NAME     C963 1
 '@S9S_MB_2U_LIB.S9S_MB_2U(SCH_1):PAGE164_I123@PURE_QUANTA.Q_CAP_DIFFBUS(CHIPS)':
 '1': CDS_PINID='\1\';
NODE_NAME     J105 L7
 '@S9S_MB_2U_LIB.S9S_MB_2U(SCH_1):PAGE142_I68@PURE_QUANTA.CONN112_10137002101LF(CHIPS)':
 'L7': CDS_PINID='L7';
NET_NAME
'P5E_CPU0_PE2_TX_C_DP<2>'
 '@S9S_MB_2U_LIB.S9S_MB_2U(SCH_1):P5E_CPU0_PE2_TX_C_DP'<2>:
 C_SIGNAL='@s9s_mb_2u_lib.s9s_mb_2u(sch_1):p5e_cpu0_pe2_tx_c_dp(2)';
NODE_NAME     C961 1
 '@S9S_MB_2U_LIB.S9S_MB_2U(SCH_1):PAGE164_I125@PURE_QUANTA.Q_CAP_DIFFBUS(CHIPS)':
 '1': CDS_PINID='\1\';
NODE_NAME     J105 K6
 '@S9S_MB_2U_LIB.S9S_MB_2U(SCH_1):PAGE142_I68@PURE_QUANTA.CONN112_10137002101LF(CHIPS)':
 'K6': CDS_PINID='K6';
NET_NAME
'P5E_CPU0_PE2_TX_C_DP<3>'
 '@S9S_MB_2U_LIB.S9S_MB_2U(SCH_1):P5E_CPU0_PE2_TX_C_DP'<3>:
 C_SIGNAL='@s9s_mb_2u_lib.s9s_mb_2u(sch_1):p5e_cpu0_pe2_tx_c_dp(3)';
NODE_NAME     C959 1
 '@S9S_MB_2U_LIB.S9S_MB_2U(SCH_1):PAGE164_I127@PURE_QUANTA.Q_CAP_DIFFBUS(CHIPS)':
 '1': CDS_PINID='\1\';
NODE_NAME     J105 L5
 '@S9S_MB_2U_LIB.S9S_MB_2U(SCH_1):PAGE142_I68@PURE_QUANTA.CONN112_10137002101LF(CHIPS)':
 'L5': CDS_PINID='L5';
NET_NAME
'P5E_CPU0_PE2_TX_C_DP<4>'
 '@S9S_MB_2U_LIB.S9S_MB_2U(SCH_1):P5E_CPU0_PE2_TX_C_DP'<4>:
 C_SIGNAL='@s9s_mb_2u_lib.s9s_mb_2u(sch_1):p5e_cpu0_pe2_tx_c_dp(4)';
NODE_NAME     C957 1
 '@S9S_MB_2U_LIB.S9S_MB_2U(SCH_1):PAGE164_I206@PURE_QUANTA.Q_CAP_DIFFBUS(CHIPS)':
 '1': CDS_PINID='\1\';
NODE_NAME     J105 K4
 '@S9S_MB_2U_LIB.S9S_MB_2U(SCH_1):PAGE142_I65@PURE_QUANTA.CONN112_10137002101LF(CHIPS)':
 'K4': CDS_PINID='K4';
NET_NAME
'P5E_CPU0_PE2_TX_C_DP<5>'
 '@S9S_MB_2U_LIB.S9S_MB_2U(SCH_1):P5E_CPU0_PE2_TX_C_DP'<5>:
 C_SIGNAL='@s9s_mb_2u_lib.s9s_mb_2u(sch_1):p5e_cpu0_pe2_tx_c_dp(5)';
NODE_NAME     C955 1
 '@S9S_MB_2U_LIB.S9S_MB_2U(SCH_1):PAGE164_I208@PURE_QUANTA.Q_CAP_DIFFBUS(CHIPS)':
 '1': CDS_PINID='\1\';
NODE_NAME     J105 L3
 '@S9S_MB_2U_LIB.S9S_MB_2U(SCH_1):PAGE142_I65@PURE_QUANTA.CONN112_10137002101LF(CHIPS)':
 'L3': CDS_PINID='L3';
NET_NAME
'P5E_CPU0_PE2_TX_C_DP<6>'
 '@S9S_MB_2U_LIB.S9S_MB_2U(SCH_1):P5E_CPU0_PE2_TX_C_DP'<6>:
 C_SIGNAL='@s9s_mb_2u_lib.s9s_mb_2u(sch_1):p5e_cpu0_pe2_tx_c_dp(6)';
NODE_NAME     C953 1
 '@S9S_MB_2U_LIB.S9S_MB_2U(SCH_1):PAGE164_I134@PURE_QUANTA.Q_CAP_DIFFBUS(CHIPS)':
 '1': CDS_PINID='\1\';
NODE_NAME     J105 K2
 '@S9S_MB_2U_LIB.S9S_MB_2U(SCH_1):PAGE142_I65@PURE_QUANTA.CONN112_10137002101LF(CHIPS)':
 'K2': CDS_PINID='K2';
NET_NAME
'P5E_CPU0_PE2_TX_C_DP<7>'
 '@S9S_MB_2U_LIB.S9S_MB_2U(SCH_1):P5E_CPU0_PE2_TX_C_DP'<7>:
 C_SIGNAL='@s9s_mb_2u_lib.s9s_mb_2u(sch_1):p5e_cpu0_pe2_tx_c_dp(7)';
NODE_NAME     C951 1
 '@S9S_MB_2U_LIB.S9S_MB_2U(SCH_1):PAGE164_I136@PURE_QUANTA.Q_CAP_DIFFBUS(CHIPS)':
 '1': CDS_PINID='\1\';
NODE_NAME     J105 L1
 '@S9S_MB_2U_LIB.S9S_MB_2U(SCH_1):PAGE142_I65@PURE_QUANTA.CONN112_10137002101LF(CHIPS)':
 'L1': CDS_PINID='L1';
NET_NAME
'P5E_CPU0_PE2_TX_C_DP<8>'
 '@S9S_MB_2U_LIB.S9S_MB_2U(SCH_1):P5E_CPU0_PE2_TX_C_DP'<8>:
 C_SIGNAL='@s9s_mb_2u_lib.s9s_mb_2u(sch_1):p5e_cpu0_pe2_tx_c_dp(8)';
NODE_NAME     C949 1
 '@S9S_MB_2U_LIB.S9S_MB_2U(SCH_1):PAGE164_I151@PURE_QUANTA.Q_CAP_DIFFBUS(CHIPS)':
 '1': CDS_PINID='\1\';
NODE_NAME     J106 K8
 '@S9S_MB_2U_LIB.S9S_MB_2U(SCH_1):PAGE144_I68@PURE_QUANTA.CONN112_10137002101LF(CHIPS)':
 'K8': CDS_PINID='K8';
NET_NAME
'P5E_CPU0_PE2_TX_C_DP<9>'
 '@S9S_MB_2U_LIB.S9S_MB_2U(SCH_1):P5E_CPU0_PE2_TX_C_DP'<9>:
 C_SIGNAL='@s9s_mb_2u_lib.s9s_mb_2u(sch_1):p5e_cpu0_pe2_tx_c_dp(9)';
NODE_NAME     C947 1
 '@S9S_MB_2U_LIB.S9S_MB_2U(SCH_1):PAGE164_I153@PURE_QUANTA.Q_CAP_DIFFBUS(CHIPS)':
 '1': CDS_PINID='\1\';
NODE_NAME     J106 L7
 '@S9S_MB_2U_LIB.S9S_MB_2U(SCH_1):PAGE144_I68@PURE_QUANTA.CONN112_10137002101LF(CHIPS)':
 'L7': CDS_PINID='L7';
NET_NAME
'P5E_CPU0_PE2_TX_DN<0>'
 '@S9S_MB_2U_LIB.S9S_MB_2U(SCH_1):P5E_CPU0_PE2_TX_DN'<0>:
 C_SIGNAL='@s9s_mb_2u_lib.s9s_mb_2u(sch_1):p5e_cpu0_pe2_tx_dn(0)';
NODE_NAME     U2 CU13
 '@S9S_MB_2U_LIB.S9S_MB_2U(SCH_1):PAGE30_I139@PURE_QUANTA.SOCKET4677_AZIF0045P001C01CS(CHIPS)':
 'PE2_TX_DN0': CDS_PINID='PE2_TX_DN0';
NODE_NAME     C964 2
 '@S9S_MB_2U_LIB.S9S_MB_2U(SCH_1):PAGE164_I122@PURE_QUANTA.Q_CAP_DIFFBUS(CHIPS)':
 '2': CDS_PINID='\2\';
NET_NAME
'P5E_CPU0_PE2_TX_DN<10>'
 '@S9S_MB_2U_LIB.S9S_MB_2U(SCH_1):P5E_CPU0_PE2_TX_DN'<10>:
 C_SIGNAL='@s9s_mb_2u_lib.s9s_mb_2u(sch_1):p5e_cpu0_pe2_tx_dn(10)';
NODE_NAME     U2 DU13
 '@S9S_MB_2U_LIB.S9S_MB_2U(SCH_1):PAGE30_I139@PURE_QUANTA.SOCKET4677_AZIF0045P001C01CS(CHIPS)':
 'PE2_TX_DN10': CDS_PINID='PE2_TX_DN10';
NODE_NAME     C944 2
 '@S9S_MB_2U_LIB.S9S_MB_2U(SCH_1):PAGE164_I156@PURE_QUANTA.Q_CAP_DIFFBUS(CHIPS)':
 '2': CDS_PINID='\2\';
NET_NAME
'P5E_CPU0_PE2_TX_DN<11>'
 '@S9S_MB_2U_LIB.S9S_MB_2U(SCH_1):P5E_CPU0_PE2_TX_DN'<11>:
 C_SIGNAL='@s9s_mb_2u_lib.s9s_mb_2u(sch_1):p5e_cpu0_pe2_tx_dn(11)';
NODE_NAME     U2 DV14
 '@S9S_MB_2U_LIB.S9S_MB_2U(SCH_1):PAGE30_I139@PURE_QUANTA.SOCKET4677_AZIF0045P001C01CS(CHIPS)':
 'PE2_TX_DN11': CDS_PINID='PE2_TX_DN11';
NODE_NAME     C942 2
 '@S9S_MB_2U_LIB.S9S_MB_2U(SCH_1):PAGE164_I158@PURE_QUANTA.Q_CAP_DIFFBUS(CHIPS)':
 '2': CDS_PINID='\2\';
NET_NAME
'P5E_CPU0_PE2_TX_DN<12>'
 '@S9S_MB_2U_LIB.S9S_MB_2U(SCH_1):P5E_CPU0_PE2_TX_DN'<12>:
 C_SIGNAL='@s9s_mb_2u_lib.s9s_mb_2u(sch_1):p5e_cpu0_pe2_tx_dn(12)';
NODE_NAME     U2 EA13
 '@S9S_MB_2U_LIB.S9S_MB_2U(SCH_1):PAGE30_I139@PURE_QUANTA.SOCKET4677_AZIF0045P001C01CS(CHIPS)':
 'PE2_TX_DN12': CDS_PINID='PE2_TX_DN12';
NODE_NAME     C940 2
 '@S9S_MB_2U_LIB.S9S_MB_2U(SCH_1):PAGE164_I160@PURE_QUANTA.Q_CAP_DIFFBUS(CHIPS)':
 '2': CDS_PINID='\2\';
NET_NAME
'P5E_CPU0_PE2_TX_DN<13>'
 '@S9S_MB_2U_LIB.S9S_MB_2U(SCH_1):P5E_CPU0_PE2_TX_DN'<13>:
 C_SIGNAL='@s9s_mb_2u_lib.s9s_mb_2u(sch_1):p5e_cpu0_pe2_tx_dn(13)';
NODE_NAME     U2 EB14
 '@S9S_MB_2U_LIB.S9S_MB_2U(SCH_1):PAGE30_I139@PURE_QUANTA.SOCKET4677_AZIF0045P001C01CS(CHIPS)':
 'PE2_TX_DN13': CDS_PINID='PE2_TX_DN13';
NODE_NAME     C938 2
 '@S9S_MB_2U_LIB.S9S_MB_2U(SCH_1):PAGE164_I165@PURE_QUANTA.Q_CAP_DIFFBUS(CHIPS)':
 '2': CDS_PINID='\2\';
NET_NAME
'P5E_CPU0_PE2_TX_DN<14>'
 '@S9S_MB_2U_LIB.S9S_MB_2U(SCH_1):P5E_CPU0_PE2_TX_DN'<14>:
 C_SIGNAL='@s9s_mb_2u_lib.s9s_mb_2u(sch_1):p5e_cpu0_pe2_tx_dn(14)';
NODE_NAME     U2 EE13
 '@S9S_MB_2U_LIB.S9S_MB_2U(SCH_1):PAGE30_I139@PURE_QUANTA.SOCKET4677_AZIF0045P001C01CS(CHIPS)':
 'PE2_TX_DN14': CDS_PINID='PE2_TX_DN14';
NODE_NAME     C936 2
 '@S9S_MB_2U_LIB.S9S_MB_2U(SCH_1):PAGE164_I167@PURE_QUANTA.Q_CAP_DIFFBUS(CHIPS)':
 '2': CDS_PINID='\2\';
NET_NAME
'P5E_CPU0_PE2_TX_DN<15>'
 '@S9S_MB_2U_LIB.S9S_MB_2U(SCH_1):P5E_CPU0_PE2_TX_DN'<15>:
 C_SIGNAL='@s9s_mb_2u_lib.s9s_mb_2u(sch_1):p5e_cpu0_pe2_tx_dn(15)';
NODE_NAME     U2 EF14
 '@S9S_MB_2U_LIB.S9S_MB_2U(SCH_1):PAGE30_I139@PURE_QUANTA.SOCKET4677_AZIF0045P001C01CS(CHIPS)':
 'PE2_TX_DN15': CDS_PINID='PE2_TX_DN15';
NODE_NAME     C934 2
 '@S9S_MB_2U_LIB.S9S_MB_2U(SCH_1):PAGE164_I169@PURE_QUANTA.Q_CAP_DIFFBUS(CHIPS)':
 '2': CDS_PINID='\2\';
NET_NAME
'P5E_CPU0_PE2_TX_DN<1>'
 '@S9S_MB_2U_LIB.S9S_MB_2U(SCH_1):P5E_CPU0_PE2_TX_DN'<1>:
 C_SIGNAL='@s9s_mb_2u_lib.s9s_mb_2u(sch_1):p5e_cpu0_pe2_tx_dn(1)';
NODE_NAME     U2 CV14
 '@S9S_MB_2U_LIB.S9S_MB_2U(SCH_1):PAGE30_I139@PURE_QUANTA.SOCKET4677_AZIF0045P001C01CS(CHIPS)':
 'PE2_TX_DN1': CDS_PINID='PE2_TX_DN1';
NODE_NAME     C962 2
 '@S9S_MB_2U_LIB.S9S_MB_2U(SCH_1):PAGE164_I124@PURE_QUANTA.Q_CAP_DIFFBUS(CHIPS)':
 '2': CDS_PINID='\2\';
NET_NAME
'P5E_CPU0_PE2_TX_DN<2>'
 '@S9S_MB_2U_LIB.S9S_MB_2U(SCH_1):P5E_CPU0_PE2_TX_DN'<2>:
 C_SIGNAL='@s9s_mb_2u_lib.s9s_mb_2u(sch_1):p5e_cpu0_pe2_tx_dn(2)';
NODE_NAME     U2 DA13
 '@S9S_MB_2U_LIB.S9S_MB_2U(SCH_1):PAGE30_I139@PURE_QUANTA.SOCKET4677_AZIF0045P001C01CS(CHIPS)':
 'PE2_TX_DN2': CDS_PINID='PE2_TX_DN2';
NODE_NAME     C960 2
 '@S9S_MB_2U_LIB.S9S_MB_2U(SCH_1):PAGE164_I126@PURE_QUANTA.Q_CAP_DIFFBUS(CHIPS)':
 '2': CDS_PINID='\2\';
NET_NAME
'P5E_CPU0_PE2_TX_DN<3>'
 '@S9S_MB_2U_LIB.S9S_MB_2U(SCH_1):P5E_CPU0_PE2_TX_DN'<3>:
 C_SIGNAL='@s9s_mb_2u_lib.s9s_mb_2u(sch_1):p5e_cpu0_pe2_tx_dn(3)';
NODE_NAME     U2 DB14
 '@S9S_MB_2U_LIB.S9S_MB_2U(SCH_1):PAGE30_I139@PURE_QUANTA.SOCKET4677_AZIF0045P001C01CS(CHIPS)':
 'PE2_TX_DN3': CDS_PINID='PE2_TX_DN3';
NODE_NAME     C958 2
 '@S9S_MB_2U_LIB.S9S_MB_2U(SCH_1):PAGE164_I128@PURE_QUANTA.Q_CAP_DIFFBUS(CHIPS)':
 '2': CDS_PINID='\2\';
NET_NAME
'P5E_CPU0_PE2_TX_DN<4>'
 '@S9S_MB_2U_LIB.S9S_MB_2U(SCH_1):P5E_CPU0_PE2_TX_DN'<4>:
 C_SIGNAL='@s9s_mb_2u_lib.s9s_mb_2u(sch_1):p5e_cpu0_pe2_tx_dn(4)';
NODE_NAME     U2 DE13
 '@S9S_MB_2U_LIB.S9S_MB_2U(SCH_1):PAGE30_I139@PURE_QUANTA.SOCKET4677_AZIF0045P001C01CS(CHIPS)':
 'PE2_TX_DN4': CDS_PINID='PE2_TX_DN4';
NODE_NAME     C956 2
 '@S9S_MB_2U_LIB.S9S_MB_2U(SCH_1):PAGE164_I207@PURE_QUANTA.Q_CAP_DIFFBUS(CHIPS)':
 '2': CDS_PINID='\2\';
NET_NAME
'P5E_CPU0_PE2_TX_DN<5>'
 '@S9S_MB_2U_LIB.S9S_MB_2U(SCH_1):P5E_CPU0_PE2_TX_DN'<5>:
 C_SIGNAL='@s9s_mb_2u_lib.s9s_mb_2u(sch_1):p5e_cpu0_pe2_tx_dn(5)';
NODE_NAME     U2 DF14
 '@S9S_MB_2U_LIB.S9S_MB_2U(SCH_1):PAGE30_I139@PURE_QUANTA.SOCKET4677_AZIF0045P001C01CS(CHIPS)':
 'PE2_TX_DN5': CDS_PINID='PE2_TX_DN5';
NODE_NAME     C954 2
 '@S9S_MB_2U_LIB.S9S_MB_2U(SCH_1):PAGE164_I133@PURE_QUANTA.Q_CAP_DIFFBUS(CHIPS)':
 '2': CDS_PINID='\2\';
NET_NAME
'P5E_CPU0_PE2_TX_DN<6>'
 '@S9S_MB_2U_LIB.S9S_MB_2U(SCH_1):P5E_CPU0_PE2_TX_DN'<6>:
 C_SIGNAL='@s9s_mb_2u_lib.s9s_mb_2u(sch_1):p5e_cpu0_pe2_tx_dn(6)';
NODE_NAME     U2 DJ13
 '@S9S_MB_2U_LIB.S9S_MB_2U(SCH_1):PAGE30_I139@PURE_QUANTA.SOCKET4677_AZIF0045P001C01CS(CHIPS)':
 'PE2_TX_DN6': CDS_PINID='PE2_TX_DN6';
NODE_NAME     C952 2
 '@S9S_MB_2U_LIB.S9S_MB_2U(SCH_1):PAGE164_I135@PURE_QUANTA.Q_CAP_DIFFBUS(CHIPS)':
 '2': CDS_PINID='\2\';
NET_NAME
'P5E_CPU0_PE2_TX_DN<7>'
 '@S9S_MB_2U_LIB.S9S_MB_2U(SCH_1):P5E_CPU0_PE2_TX_DN'<7>:
 C_SIGNAL='@s9s_mb_2u_lib.s9s_mb_2u(sch_1):p5e_cpu0_pe2_tx_dn(7)';
NODE_NAME     U2 DK14
 '@S9S_MB_2U_LIB.S9S_MB_2U(SCH_1):PAGE30_I139@PURE_QUANTA.SOCKET4677_AZIF0045P001C01CS(CHIPS)':
 'PE2_TX_DN7': CDS_PINID='PE2_TX_DN7';
NODE_NAME     C950 2
 '@S9S_MB_2U_LIB.S9S_MB_2U(SCH_1):PAGE164_I137@PURE_QUANTA.Q_CAP_DIFFBUS(CHIPS)':
 '2': CDS_PINID='\2\';
NET_NAME
'P5E_CPU0_PE2_TX_DN<8>'
 '@S9S_MB_2U_LIB.S9S_MB_2U(SCH_1):P5E_CPU0_PE2_TX_DN'<8>:
 C_SIGNAL='@s9s_mb_2u_lib.s9s_mb_2u(sch_1):p5e_cpu0_pe2_tx_dn(8)';
NODE_NAME     U2 DN13
 '@S9S_MB_2U_LIB.S9S_MB_2U(SCH_1):PAGE30_I139@PURE_QUANTA.SOCKET4677_AZIF0045P001C01CS(CHIPS)':
 'PE2_TX_DN8': CDS_PINID='PE2_TX_DN8';
NODE_NAME     C948 2
 '@S9S_MB_2U_LIB.S9S_MB_2U(SCH_1):PAGE164_I152@PURE_QUANTA.Q_CAP_DIFFBUS(CHIPS)':
 '2': CDS_PINID='\2\';
NET_NAME
'P5E_CPU0_PE2_TX_DN<9>'
 '@S9S_MB_2U_LIB.S9S_MB_2U(SCH_1):P5E_CPU0_PE2_TX_DN'<9>:
 C_SIGNAL='@s9s_mb_2u_lib.s9s_mb_2u(sch_1):p5e_cpu0_pe2_tx_dn(9)';
NODE_NAME     U2 DP14
 '@S9S_MB_2U_LIB.S9S_MB_2U(SCH_1):PAGE30_I139@PURE_QUANTA.SOCKET4677_AZIF0045P001C01CS(CHIPS)':
 'PE2_TX_DN9': CDS_PINID='PE2_TX_DN9';
NODE_NAME     C946 2
 '@S9S_MB_2U_LIB.S9S_MB_2U(SCH_1):PAGE164_I154@PURE_QUANTA.Q_CAP_DIFFBUS(CHIPS)':
 '2': CDS_PINID='\2\';
NET_NAME
'P5E_CPU0_PE2_TX_DP<0>'
 '@S9S_MB_2U_LIB.S9S_MB_2U(SCH_1):P5E_CPU0_PE2_TX_DP'<0>:
 C_SIGNAL='@s9s_mb_2u_lib.s9s_mb_2u(sch_1):p5e_cpu0_pe2_tx_dp(0)';
NODE_NAME     U2 CT14
 '@S9S_MB_2U_LIB.S9S_MB_2U(SCH_1):PAGE30_I139@PURE_QUANTA.SOCKET4677_AZIF0045P001C01CS(CHIPS)':
 'PE2_TX_DP0': CDS_PINID='PE2_TX_DP0';
NODE_NAME     C965 2
 '@S9S_MB_2U_LIB.S9S_MB_2U(SCH_1):PAGE164_I121@PURE_QUANTA.Q_CAP_DIFFBUS(CHIPS)':
 '2': CDS_PINID='\2\';
NET_NAME
'P5E_CPU0_PE2_TX_DP<10>'
 '@S9S_MB_2U_LIB.S9S_MB_2U(SCH_1):P5E_CPU0_PE2_TX_DP'<10>:
 C_SIGNAL='@s9s_mb_2u_lib.s9s_mb_2u(sch_1):p5e_cpu0_pe2_tx_dp(10)';
NODE_NAME     U2 DT14
 '@S9S_MB_2U_LIB.S9S_MB_2U(SCH_1):PAGE30_I139@PURE_QUANTA.SOCKET4677_AZIF0045P001C01CS(CHIPS)':
 'PE2_TX_DP10': CDS_PINID='PE2_TX_DP10';
NODE_NAME     C945 2
 '@S9S_MB_2U_LIB.S9S_MB_2U(SCH_1):PAGE164_I155@PURE_QUANTA.Q_CAP_DIFFBUS(CHIPS)':
 '2': CDS_PINID='\2\';
NET_NAME
'P5E_CPU0_PE2_TX_DP<11>'
 '@S9S_MB_2U_LIB.S9S_MB_2U(SCH_1):P5E_CPU0_PE2_TX_DP'<11>:
 C_SIGNAL='@s9s_mb_2u_lib.s9s_mb_2u(sch_1):p5e_cpu0_pe2_tx_dp(11)';
NODE_NAME     U2 DW15
 '@S9S_MB_2U_LIB.S9S_MB_2U(SCH_1):PAGE30_I139@PURE_QUANTA.SOCKET4677_AZIF0045P001C01CS(CHIPS)':
 'PE2_TX_DP11': CDS_PINID='PE2_TX_DP11';
NODE_NAME     C943 2
 '@S9S_MB_2U_LIB.S9S_MB_2U(SCH_1):PAGE164_I157@PURE_QUANTA.Q_CAP_DIFFBUS(CHIPS)':
 '2': CDS_PINID='\2\';
NET_NAME
'P5E_CPU0_PE2_TX_DP<12>'
 '@S9S_MB_2U_LIB.S9S_MB_2U(SCH_1):P5E_CPU0_PE2_TX_DP'<12>:
 C_SIGNAL='@s9s_mb_2u_lib.s9s_mb_2u(sch_1):p5e_cpu0_pe2_tx_dp(12)';
NODE_NAME     U2 DY14
 '@S9S_MB_2U_LIB.S9S_MB_2U(SCH_1):PAGE30_I139@PURE_QUANTA.SOCKET4677_AZIF0045P001C01CS(CHIPS)':
 'PE2_TX_DP12': CDS_PINID='PE2_TX_DP12';
NODE_NAME     C941 2
 '@S9S_MB_2U_LIB.S9S_MB_2U(SCH_1):PAGE164_I159@PURE_QUANTA.Q_CAP_DIFFBUS(CHIPS)':
 '2': CDS_PINID='\2\';
NET_NAME
'P5E_CPU0_PE2_TX_DP<13>'
 '@S9S_MB_2U_LIB.S9S_MB_2U(SCH_1):P5E_CPU0_PE2_TX_DP'<13>:
 C_SIGNAL='@s9s_mb_2u_lib.s9s_mb_2u(sch_1):p5e_cpu0_pe2_tx_dp(13)';
NODE_NAME     U2 EC15
 '@S9S_MB_2U_LIB.S9S_MB_2U(SCH_1):PAGE30_I139@PURE_QUANTA.SOCKET4677_AZIF0045P001C01CS(CHIPS)':
 'PE2_TX_DP13': CDS_PINID='PE2_TX_DP13';
NODE_NAME     C939 2
 '@S9S_MB_2U_LIB.S9S_MB_2U(SCH_1):PAGE164_I164@PURE_QUANTA.Q_CAP_DIFFBUS(CHIPS)':
 '2': CDS_PINID='\2\';
NET_NAME
'P5E_CPU0_PE2_TX_DP<14>'
 '@S9S_MB_2U_LIB.S9S_MB_2U(SCH_1):P5E_CPU0_PE2_TX_DP'<14>:
 C_SIGNAL='@s9s_mb_2u_lib.s9s_mb_2u(sch_1):p5e_cpu0_pe2_tx_dp(14)';
NODE_NAME     U2 ED14
 '@S9S_MB_2U_LIB.S9S_MB_2U(SCH_1):PAGE30_I139@PURE_QUANTA.SOCKET4677_AZIF0045P001C01CS(CHIPS)':
 'PE2_TX_DP14': CDS_PINID='PE2_TX_DP14';
NODE_NAME     C937 2
 '@S9S_MB_2U_LIB.S9S_MB_2U(SCH_1):PAGE164_I166@PURE_QUANTA.Q_CAP_DIFFBUS(CHIPS)':
 '2': CDS_PINID='\2\';
NET_NAME
'P5E_CPU0_PE2_TX_DP<15>'
 '@S9S_MB_2U_LIB.S9S_MB_2U(SCH_1):P5E_CPU0_PE2_TX_DP'<15>:
 C_SIGNAL='@s9s_mb_2u_lib.s9s_mb_2u(sch_1):p5e_cpu0_pe2_tx_dp(15)';
NODE_NAME     U2 EG15
 '@S9S_MB_2U_LIB.S9S_MB_2U(SCH_1):PAGE30_I139@PURE_QUANTA.SOCKET4677_AZIF0045P001C01CS(CHIPS)':
 'PE2_TX_DP15': CDS_PINID='PE2_TX_DP15';
NODE_NAME     C935 2
 '@S9S_MB_2U_LIB.S9S_MB_2U(SCH_1):PAGE164_I168@PURE_QUANTA.Q_CAP_DIFFBUS(CHIPS)':
 '2': CDS_PINID='\2\';
NET_NAME
'P5E_CPU0_PE2_TX_DP<1>'
 '@S9S_MB_2U_LIB.S9S_MB_2U(SCH_1):P5E_CPU0_PE2_TX_DP'<1>:
 C_SIGNAL='@s9s_mb_2u_lib.s9s_mb_2u(sch_1):p5e_cpu0_pe2_tx_dp(1)';
NODE_NAME     U2 CW15
 '@S9S_MB_2U_LIB.S9S_MB_2U(SCH_1):PAGE30_I139@PURE_QUANTA.SOCKET4677_AZIF0045P001C01CS(CHIPS)':
 'PE2_TX_DP1': CDS_PINID='PE2_TX_DP1';
NODE_NAME     C963 2
 '@S9S_MB_2U_LIB.S9S_MB_2U(SCH_1):PAGE164_I123@PURE_QUANTA.Q_CAP_DIFFBUS(CHIPS)':
 '2': CDS_PINID='\2\';
NET_NAME
'P5E_CPU0_PE2_TX_DP<2>'
 '@S9S_MB_2U_LIB.S9S_MB_2U(SCH_1):P5E_CPU0_PE2_TX_DP'<2>:
 C_SIGNAL='@s9s_mb_2u_lib.s9s_mb_2u(sch_1):p5e_cpu0_pe2_tx_dp(2)';
NODE_NAME     U2 CY14
 '@S9S_MB_2U_LIB.S9S_MB_2U(SCH_1):PAGE30_I139@PURE_QUANTA.SOCKET4677_AZIF0045P001C01CS(CHIPS)':
 'PE2_TX_DP2': CDS_PINID='PE2_TX_DP2';
NODE_NAME     C961 2
 '@S9S_MB_2U_LIB.S9S_MB_2U(SCH_1):PAGE164_I125@PURE_QUANTA.Q_CAP_DIFFBUS(CHIPS)':
 '2': CDS_PINID='\2\';
NET_NAME
'P5E_CPU0_PE2_TX_DP<3>'
 '@S9S_MB_2U_LIB.S9S_MB_2U(SCH_1):P5E_CPU0_PE2_TX_DP'<3>:
 C_SIGNAL='@s9s_mb_2u_lib.s9s_mb_2u(sch_1):p5e_cpu0_pe2_tx_dp(3)';
NODE_NAME     U2 DC15
 '@S9S_MB_2U_LIB.S9S_MB_2U(SCH_1):PAGE30_I139@PURE_QUANTA.SOCKET4677_AZIF0045P001C01CS(CHIPS)':
 'PE2_TX_DP3': CDS_PINID='PE2_TX_DP3';
NODE_NAME     C959 2
 '@S9S_MB_2U_LIB.S9S_MB_2U(SCH_1):PAGE164_I127@PURE_QUANTA.Q_CAP_DIFFBUS(CHIPS)':
 '2': CDS_PINID='\2\';
NET_NAME
'P5E_CPU0_PE2_TX_DP<4>'
 '@S9S_MB_2U_LIB.S9S_MB_2U(SCH_1):P5E_CPU0_PE2_TX_DP'<4>:
 C_SIGNAL='@s9s_mb_2u_lib.s9s_mb_2u(sch_1):p5e_cpu0_pe2_tx_dp(4)';
NODE_NAME     U2 DD14
 '@S9S_MB_2U_LIB.S9S_MB_2U(SCH_1):PAGE30_I139@PURE_QUANTA.SOCKET4677_AZIF0045P001C01CS(CHIPS)':
 'PE2_TX_DP4': CDS_PINID='PE2_TX_DP4';
NODE_NAME     C957 2
 '@S9S_MB_2U_LIB.S9S_MB_2U(SCH_1):PAGE164_I206@PURE_QUANTA.Q_CAP_DIFFBUS(CHIPS)':
 '2': CDS_PINID='\2\';
NET_NAME
'P5E_CPU0_PE2_TX_DP<5>'
 '@S9S_MB_2U_LIB.S9S_MB_2U(SCH_1):P5E_CPU0_PE2_TX_DP'<5>:
 C_SIGNAL='@s9s_mb_2u_lib.s9s_mb_2u(sch_1):p5e_cpu0_pe2_tx_dp(5)';
NODE_NAME     U2 DG15
 '@S9S_MB_2U_LIB.S9S_MB_2U(SCH_1):PAGE30_I139@PURE_QUANTA.SOCKET4677_AZIF0045P001C01CS(CHIPS)':
 'PE2_TX_DP5': CDS_PINID='PE2_TX_DP5';
NODE_NAME     C955 2
 '@S9S_MB_2U_LIB.S9S_MB_2U(SCH_1):PAGE164_I208@PURE_QUANTA.Q_CAP_DIFFBUS(CHIPS)':
 '2': CDS_PINID='\2\';
NET_NAME
'P5E_CPU0_PE2_TX_DP<6>'
 '@S9S_MB_2U_LIB.S9S_MB_2U(SCH_1):P5E_CPU0_PE2_TX_DP'<6>:
 C_SIGNAL='@s9s_mb_2u_lib.s9s_mb_2u(sch_1):p5e_cpu0_pe2_tx_dp(6)';
NODE_NAME     U2 DH14
 '@S9S_MB_2U_LIB.S9S_MB_2U(SCH_1):PAGE30_I139@PURE_QUANTA.SOCKET4677_AZIF0045P001C01CS(CHIPS)':
 'PE2_TX_DP6': CDS_PINID='PE2_TX_DP6';
NODE_NAME     C953 2
 '@S9S_MB_2U_LIB.S9S_MB_2U(SCH_1):PAGE164_I134@PURE_QUANTA.Q_CAP_DIFFBUS(CHIPS)':
 '2': CDS_PINID='\2\';
NET_NAME
'P5E_CPU0_PE2_TX_DP<7>'
 '@S9S_MB_2U_LIB.S9S_MB_2U(SCH_1):P5E_CPU0_PE2_TX_DP'<7>:
 C_SIGNAL='@s9s_mb_2u_lib.s9s_mb_2u(sch_1):p5e_cpu0_pe2_tx_dp(7)';
NODE_NAME     U2 DL15
 '@S9S_MB_2U_LIB.S9S_MB_2U(SCH_1):PAGE30_I139@PURE_QUANTA.SOCKET4677_AZIF0045P001C01CS(CHIPS)':
 'PE2_TX_DP7': CDS_PINID='PE2_TX_DP7';
NODE_NAME     C951 2
 '@S9S_MB_2U_LIB.S9S_MB_2U(SCH_1):PAGE164_I136@PURE_QUANTA.Q_CAP_DIFFBUS(CHIPS)':
 '2': CDS_PINID='\2\';
NET_NAME
'P5E_CPU0_PE2_TX_DP<8>'
 '@S9S_MB_2U_LIB.S9S_MB_2U(SCH_1):P5E_CPU0_PE2_TX_DP'<8>:
 C_SIGNAL='@s9s_mb_2u_lib.s9s_mb_2u(sch_1):p5e_cpu0_pe2_tx_dp(8)';
NODE_NAME     U2 DM14
 '@S9S_MB_2U_LIB.S9S_MB_2U(SCH_1):PAGE30_I139@PURE_QUANTA.SOCKET4677_AZIF0045P001C01CS(CHIPS)':
 'PE2_TX_DP8': CDS_PINID='PE2_TX_DP8';
NODE_NAME     C949 2
 '@S9S_MB_2U_LIB.S9S_MB_2U(SCH_1):PAGE164_I151@PURE_QUANTA.Q_CAP_DIFFBUS(CHIPS)':
 '2': CDS_PINID='\2\';
NET_NAME
'P5E_CPU0_PE2_TX_DP<9>'
 '@S9S_MB_2U_LIB.S9S_MB_2U(SCH_1):P5E_CPU0_PE2_TX_DP'<9>:
 C_SIGNAL='@s9s_mb_2u_lib.s9s_mb_2u(sch_1):p5e_cpu0_pe2_tx_dp(9)';
NODE_NAME     U2 DR15
 '@S9S_MB_2U_LIB.S9S_MB_2U(SCH_1):PAGE30_I139@PURE_QUANTA.SOCKET4677_AZIF0045P001C01CS(CHIPS)':
 'PE2_TX_DP9': CDS_PINID='PE2_TX_DP9';
NODE_NAME     C947 2
 '@S9S_MB_2U_LIB.S9S_MB_2U(SCH_1):PAGE164_I153@PURE_QUANTA.Q_CAP_DIFFBUS(CHIPS)':
 '2': CDS_PINID='\2\';
NET_NAME
'P5E_CPU0_PE3_RX_DN<0>'
 '@S9S_MB_2U_LIB.S9S_MB_2U(SCH_1):P5E_CPU0_PE3_RX_DN'<0>:
 C_SIGNAL='@s9s_mb_2u_lib.s9s_mb_2u(sch_1):p5e_cpu0_pe3_rx_dn(0)';
NODE_NAME     U2 EH89
 '@S9S_MB_2U_LIB.S9S_MB_2U(SCH_1):PAGE30_I140@PURE_QUANTA.SOCKET4677_AZIF0045P001C01CS(CHIPS)':
 'PE3_RX_DN0': CDS_PINID='PE3_RX_DN0';
NODE_NAME     J105 C8
 '@S9S_MB_2U_LIB.S9S_MB_2U(SCH_1):PAGE142_I68@PURE_QUANTA.CONN112_10137002101LF(CHIPS)':
 'C8': CDS_PINID='C8';
NET_NAME
'P5E_CPU0_PE3_RX_DN<10>'
 '@S9S_MB_2U_LIB.S9S_MB_2U(SCH_1):P5E_CPU0_PE3_RX_DN'<10>:
 C_SIGNAL='@s9s_mb_2u_lib.s9s_mb_2u(sch_1):p5e_cpu0_pe3_rx_dn(10)';
NODE_NAME     U2 DG90
 '@S9S_MB_2U_LIB.S9S_MB_2U(SCH_1):PAGE30_I140@PURE_QUANTA.SOCKET4677_AZIF0045P001C01CS(CHIPS)':
 'PE3_RX_DN10': CDS_PINID='PE3_RX_DN10';
NODE_NAME     J106 B6
 '@S9S_MB_2U_LIB.S9S_MB_2U(SCH_1):PAGE144_I68@PURE_QUANTA.CONN112_10137002101LF(CHIPS)':
 'B6': CDS_PINID='B6';
NET_NAME
'P5E_CPU0_PE3_RX_DN<11>'
 '@S9S_MB_2U_LIB.S9S_MB_2U(SCH_1):P5E_CPU0_PE3_RX_DN'<11>:
 C_SIGNAL='@s9s_mb_2u_lib.s9s_mb_2u(sch_1):p5e_cpu0_pe3_rx_dn(11)';
NODE_NAME     U2 DD91
 '@S9S_MB_2U_LIB.S9S_MB_2U(SCH_1):PAGE30_I140@PURE_QUANTA.SOCKET4677_AZIF0045P001C01CS(CHIPS)':
 'PE3_RX_DN11': CDS_PINID='PE3_RX_DN11';
NODE_NAME     J106 C5
 '@S9S_MB_2U_LIB.S9S_MB_2U(SCH_1):PAGE144_I68@PURE_QUANTA.CONN112_10137002101LF(CHIPS)':
 'C5': CDS_PINID='C5';
NET_NAME
'P5E_CPU0_PE3_RX_DN<12>'
 '@S9S_MB_2U_LIB.S9S_MB_2U(SCH_1):P5E_CPU0_PE3_RX_DN'<12>:
 C_SIGNAL='@s9s_mb_2u_lib.s9s_mb_2u(sch_1):p5e_cpu0_pe3_rx_dn(12)';
NODE_NAME     U2 DB89
 '@S9S_MB_2U_LIB.S9S_MB_2U(SCH_1):PAGE30_I140@PURE_QUANTA.SOCKET4677_AZIF0045P001C01CS(CHIPS)':
 'PE3_RX_DN12': CDS_PINID='PE3_RX_DN12';
NODE_NAME     J106 C4
 '@S9S_MB_2U_LIB.S9S_MB_2U(SCH_1):PAGE144_I65@PURE_QUANTA.CONN112_10137002101LF(CHIPS)':
 'C4': CDS_PINID='C4';
NET_NAME
'P5E_CPU0_PE3_RX_DN<13>'
 '@S9S_MB_2U_LIB.S9S_MB_2U(SCH_1):P5E_CPU0_PE3_RX_DN'<13>:
 C_SIGNAL='@s9s_mb_2u_lib.s9s_mb_2u(sch_1):p5e_cpu0_pe3_rx_dn(13)';
NODE_NAME     U2 DA90
 '@S9S_MB_2U_LIB.S9S_MB_2U(SCH_1):PAGE30_I140@PURE_QUANTA.SOCKET4677_AZIF0045P001C01CS(CHIPS)':
 'PE3_RX_DN13': CDS_PINID='PE3_RX_DN13';
NODE_NAME     J106 D3
 '@S9S_MB_2U_LIB.S9S_MB_2U(SCH_1):PAGE144_I65@PURE_QUANTA.CONN112_10137002101LF(CHIPS)':
 'D3': CDS_PINID='D3';
NET_NAME
'P5E_CPU0_PE3_RX_DN<14>'
 '@S9S_MB_2U_LIB.S9S_MB_2U(SCH_1):P5E_CPU0_PE3_RX_DN'<14>:
 C_SIGNAL='@s9s_mb_2u_lib.s9s_mb_2u(sch_1):p5e_cpu0_pe3_rx_dn(14)';
NODE_NAME     U2 CV89
 '@S9S_MB_2U_LIB.S9S_MB_2U(SCH_1):PAGE30_I140@PURE_QUANTA.SOCKET4677_AZIF0045P001C01CS(CHIPS)':
 'PE3_RX_DN14': CDS_PINID='PE3_RX_DN14';
NODE_NAME     J106 C2
 '@S9S_MB_2U_LIB.S9S_MB_2U(SCH_1):PAGE144_I65@PURE_QUANTA.CONN112_10137002101LF(CHIPS)':
 'C2': CDS_PINID='C2';
NET_NAME
'P5E_CPU0_PE3_RX_DN<15>'
 '@S9S_MB_2U_LIB.S9S_MB_2U(SCH_1):P5E_CPU0_PE3_RX_DN'<15>:
 C_SIGNAL='@s9s_mb_2u_lib.s9s_mb_2u(sch_1):p5e_cpu0_pe3_rx_dn(15)';
NODE_NAME     U2 CU90
 '@S9S_MB_2U_LIB.S9S_MB_2U(SCH_1):PAGE30_I140@PURE_QUANTA.SOCKET4677_AZIF0045P001C01CS(CHIPS)':
 'PE3_RX_DN15': CDS_PINID='PE3_RX_DN15';
NODE_NAME     J106 D1
 '@S9S_MB_2U_LIB.S9S_MB_2U(SCH_1):PAGE144_I65@PURE_QUANTA.CONN112_10137002101LF(CHIPS)':
 'D1': CDS_PINID='D1';
NET_NAME
'P5E_CPU0_PE3_RX_DN<1>'
 '@S9S_MB_2U_LIB.S9S_MB_2U(SCH_1):P5E_CPU0_PE3_RX_DN'<1>:
 C_SIGNAL='@s9s_mb_2u_lib.s9s_mb_2u(sch_1):p5e_cpu0_pe3_rx_dn(1)';
NODE_NAME     U2 ED91
 '@S9S_MB_2U_LIB.S9S_MB_2U(SCH_1):PAGE30_I140@PURE_QUANTA.SOCKET4677_AZIF0045P001C01CS(CHIPS)':
 'PE3_RX_DN1': CDS_PINID='PE3_RX_DN1';
NODE_NAME     J105 C7
 '@S9S_MB_2U_LIB.S9S_MB_2U(SCH_1):PAGE142_I68@PURE_QUANTA.CONN112_10137002101LF(CHIPS)':
 'C7': CDS_PINID='C7';
NET_NAME
'P5E_CPU0_PE3_RX_DN<2>'
 '@S9S_MB_2U_LIB.S9S_MB_2U(SCH_1):P5E_CPU0_PE3_RX_DN'<2>:
 C_SIGNAL='@s9s_mb_2u_lib.s9s_mb_2u(sch_1):p5e_cpu0_pe3_rx_dn(2)';
NODE_NAME     U2 EC90
 '@S9S_MB_2U_LIB.S9S_MB_2U(SCH_1):PAGE30_I140@PURE_QUANTA.SOCKET4677_AZIF0045P001C01CS(CHIPS)':
 'PE3_RX_DN2': CDS_PINID='PE3_RX_DN2';
NODE_NAME     J105 B6
 '@S9S_MB_2U_LIB.S9S_MB_2U(SCH_1):PAGE142_I68@PURE_QUANTA.CONN112_10137002101LF(CHIPS)':
 'B6': CDS_PINID='B6';
NET_NAME
'P5E_CPU0_PE3_RX_DN<3>'
 '@S9S_MB_2U_LIB.S9S_MB_2U(SCH_1):P5E_CPU0_PE3_RX_DN'<3>:
 C_SIGNAL='@s9s_mb_2u_lib.s9s_mb_2u(sch_1):p5e_cpu0_pe3_rx_dn(3)';
NODE_NAME     U2 DY91
 '@S9S_MB_2U_LIB.S9S_MB_2U(SCH_1):PAGE30_I140@PURE_QUANTA.SOCKET4677_AZIF0045P001C01CS(CHIPS)':
 'PE3_RX_DN3': CDS_PINID='PE3_RX_DN3';
NODE_NAME     J105 C5
 '@S9S_MB_2U_LIB.S9S_MB_2U(SCH_1):PAGE142_I68@PURE_QUANTA.CONN112_10137002101LF(CHIPS)':
 'C5': CDS_PINID='C5';
NET_NAME
'P5E_CPU0_PE3_RX_DN<4>'
 '@S9S_MB_2U_LIB.S9S_MB_2U(SCH_1):P5E_CPU0_PE3_RX_DN'<4>:
 C_SIGNAL='@s9s_mb_2u_lib.s9s_mb_2u(sch_1):p5e_cpu0_pe3_rx_dn(4)';
NODE_NAME     U2 DV89
 '@S9S_MB_2U_LIB.S9S_MB_2U(SCH_1):PAGE30_I140@PURE_QUANTA.SOCKET4677_AZIF0045P001C01CS(CHIPS)':
 'PE3_RX_DN4': CDS_PINID='PE3_RX_DN4';
NODE_NAME     J105 C4
 '@S9S_MB_2U_LIB.S9S_MB_2U(SCH_1):PAGE142_I65@PURE_QUANTA.CONN112_10137002101LF(CHIPS)':
 'C4': CDS_PINID='C4';
NET_NAME
'P5E_CPU0_PE3_RX_DN<5>'
 '@S9S_MB_2U_LIB.S9S_MB_2U(SCH_1):P5E_CPU0_PE3_RX_DN'<5>:
 C_SIGNAL='@s9s_mb_2u_lib.s9s_mb_2u(sch_1):p5e_cpu0_pe3_rx_dn(5)';
NODE_NAME     U2 DU90
 '@S9S_MB_2U_LIB.S9S_MB_2U(SCH_1):PAGE30_I140@PURE_QUANTA.SOCKET4677_AZIF0045P001C01CS(CHIPS)':
 'PE3_RX_DN5': CDS_PINID='PE3_RX_DN5';
NODE_NAME     J105 D3
 '@S9S_MB_2U_LIB.S9S_MB_2U(SCH_1):PAGE142_I65@PURE_QUANTA.CONN112_10137002101LF(CHIPS)':
 'D3': CDS_PINID='D3';
NET_NAME
'P5E_CPU0_PE3_RX_DN<6>'
 '@S9S_MB_2U_LIB.S9S_MB_2U(SCH_1):P5E_CPU0_PE3_RX_DN'<6>:
 C_SIGNAL='@s9s_mb_2u_lib.s9s_mb_2u(sch_1):p5e_cpu0_pe3_rx_dn(6)';
NODE_NAME     U2 DP89
 '@S9S_MB_2U_LIB.S9S_MB_2U(SCH_1):PAGE30_I140@PURE_QUANTA.SOCKET4677_AZIF0045P001C01CS(CHIPS)':
 'PE3_RX_DN6': CDS_PINID='PE3_RX_DN6';
NODE_NAME     J105 C2
 '@S9S_MB_2U_LIB.S9S_MB_2U(SCH_1):PAGE142_I65@PURE_QUANTA.CONN112_10137002101LF(CHIPS)':
 'C2': CDS_PINID='C2';
NET_NAME
'P5E_CPU0_PE3_RX_DN<7>'
 '@S9S_MB_2U_LIB.S9S_MB_2U(SCH_1):P5E_CPU0_PE3_RX_DN'<7>:
 C_SIGNAL='@s9s_mb_2u_lib.s9s_mb_2u(sch_1):p5e_cpu0_pe3_rx_dn(7)';
NODE_NAME     U2 DN90
 '@S9S_MB_2U_LIB.S9S_MB_2U(SCH_1):PAGE30_I140@PURE_QUANTA.SOCKET4677_AZIF0045P001C01CS(CHIPS)':
 'PE3_RX_DN7': CDS_PINID='PE3_RX_DN7';
NODE_NAME     J105 D1
 '@S9S_MB_2U_LIB.S9S_MB_2U(SCH_1):PAGE142_I65@PURE_QUANTA.CONN112_10137002101LF(CHIPS)':
 'D1': CDS_PINID='D1';
NET_NAME
'P5E_CPU0_PE3_RX_DN<8>'
 '@S9S_MB_2U_LIB.S9S_MB_2U(SCH_1):P5E_CPU0_PE3_RX_DN'<8>:
 C_SIGNAL='@s9s_mb_2u_lib.s9s_mb_2u(sch_1):p5e_cpu0_pe3_rx_dn(8)';
NODE_NAME     U2 DL90
 '@S9S_MB_2U_LIB.S9S_MB_2U(SCH_1):PAGE30_I140@PURE_QUANTA.SOCKET4677_AZIF0045P001C01CS(CHIPS)':
 'PE3_RX_DN8': CDS_PINID='PE3_RX_DN8';
NODE_NAME     J106 B8
 '@S9S_MB_2U_LIB.S9S_MB_2U(SCH_1):PAGE144_I68@PURE_QUANTA.CONN112_10137002101LF(CHIPS)':
 'B8': CDS_PINID='B8';
NET_NAME
'P5E_CPU0_PE3_RX_DN<9>'
 '@S9S_MB_2U_LIB.S9S_MB_2U(SCH_1):P5E_CPU0_PE3_RX_DN'<9>:
 C_SIGNAL='@s9s_mb_2u_lib.s9s_mb_2u(sch_1):p5e_cpu0_pe3_rx_dn(9)';
NODE_NAME     U2 DH91
 '@S9S_MB_2U_LIB.S9S_MB_2U(SCH_1):PAGE30_I140@PURE_QUANTA.SOCKET4677_AZIF0045P001C01CS(CHIPS)':
 'PE3_RX_DN9': CDS_PINID='PE3_RX_DN9';
NODE_NAME     J106 C7
 '@S9S_MB_2U_LIB.S9S_MB_2U(SCH_1):PAGE144_I68@PURE_QUANTA.CONN112_10137002101LF(CHIPS)':
 'C7': CDS_PINID='C7';
NET_NAME
'P5E_CPU0_PE3_RX_DP<0>'
 '@S9S_MB_2U_LIB.S9S_MB_2U(SCH_1):P5E_CPU0_PE3_RX_DP'<0>:
 C_SIGNAL='@s9s_mb_2u_lib.s9s_mb_2u(sch_1):p5e_cpu0_pe3_rx_dp(0)';
NODE_NAME     U2 EJ90
 '@S9S_MB_2U_LIB.S9S_MB_2U(SCH_1):PAGE30_I140@PURE_QUANTA.SOCKET4677_AZIF0045P001C01CS(CHIPS)':
 'PE3_RX_DP0': CDS_PINID='PE3_RX_DP0';
NODE_NAME     J105 B8
 '@S9S_MB_2U_LIB.S9S_MB_2U(SCH_1):PAGE142_I68@PURE_QUANTA.CONN112_10137002101LF(CHIPS)':
 'B8': CDS_PINID='B8';
NET_NAME
'P5E_CPU0_PE3_RX_DP<10>'
 '@S9S_MB_2U_LIB.S9S_MB_2U(SCH_1):P5E_CPU0_PE3_RX_DP'<10>:
 C_SIGNAL='@s9s_mb_2u_lib.s9s_mb_2u(sch_1):p5e_cpu0_pe3_rx_dp(10)';
NODE_NAME     U2 DF89
 '@S9S_MB_2U_LIB.S9S_MB_2U(SCH_1):PAGE30_I140@PURE_QUANTA.SOCKET4677_AZIF0045P001C01CS(CHIPS)':
 'PE3_RX_DP10': CDS_PINID='PE3_RX_DP10';
NODE_NAME     J106 C6
 '@S9S_MB_2U_LIB.S9S_MB_2U(SCH_1):PAGE144_I68@PURE_QUANTA.CONN112_10137002101LF(CHIPS)':
 'C6': CDS_PINID='C6';
NET_NAME
'P5E_CPU0_PE3_RX_DP<11>'
 '@S9S_MB_2U_LIB.S9S_MB_2U(SCH_1):P5E_CPU0_PE3_RX_DP'<11>:
 C_SIGNAL='@s9s_mb_2u_lib.s9s_mb_2u(sch_1):p5e_cpu0_pe3_rx_dp(11)';
NODE_NAME     U2 DE90
 '@S9S_MB_2U_LIB.S9S_MB_2U(SCH_1):PAGE30_I140@PURE_QUANTA.SOCKET4677_AZIF0045P001C01CS(CHIPS)':
 'PE3_RX_DP11': CDS_PINID='PE3_RX_DP11';
NODE_NAME     J106 D5
 '@S9S_MB_2U_LIB.S9S_MB_2U(SCH_1):PAGE144_I68@PURE_QUANTA.CONN112_10137002101LF(CHIPS)':
 'D5': CDS_PINID='D5';
NET_NAME
'P5E_CPU0_PE3_RX_DP<12>'
 '@S9S_MB_2U_LIB.S9S_MB_2U(SCH_1):P5E_CPU0_PE3_RX_DP'<12>:
 C_SIGNAL='@s9s_mb_2u_lib.s9s_mb_2u(sch_1):p5e_cpu0_pe3_rx_dp(12)';
NODE_NAME     U2 DC90
 '@S9S_MB_2U_LIB.S9S_MB_2U(SCH_1):PAGE30_I140@PURE_QUANTA.SOCKET4677_AZIF0045P001C01CS(CHIPS)':
 'PE3_RX_DP12': CDS_PINID='PE3_RX_DP12';
NODE_NAME     J106 B4
 '@S9S_MB_2U_LIB.S9S_MB_2U(SCH_1):PAGE144_I65@PURE_QUANTA.CONN112_10137002101LF(CHIPS)':
 'B4': CDS_PINID='B4';
NET_NAME
'P5E_CPU0_PE3_RX_DP<13>'
 '@S9S_MB_2U_LIB.S9S_MB_2U(SCH_1):P5E_CPU0_PE3_RX_DP'<13>:
 C_SIGNAL='@s9s_mb_2u_lib.s9s_mb_2u(sch_1):p5e_cpu0_pe3_rx_dp(13)';
NODE_NAME     U2 CY91
 '@S9S_MB_2U_LIB.S9S_MB_2U(SCH_1):PAGE30_I140@PURE_QUANTA.SOCKET4677_AZIF0045P001C01CS(CHIPS)':
 'PE3_RX_DP13': CDS_PINID='PE3_RX_DP13';
NODE_NAME     J106 C3
 '@S9S_MB_2U_LIB.S9S_MB_2U(SCH_1):PAGE144_I65@PURE_QUANTA.CONN112_10137002101LF(CHIPS)':
 'C3': CDS_PINID='C3';
NET_NAME
'P5E_CPU0_PE3_RX_DP<14>'
 '@S9S_MB_2U_LIB.S9S_MB_2U(SCH_1):P5E_CPU0_PE3_RX_DP'<14>:
 C_SIGNAL='@s9s_mb_2u_lib.s9s_mb_2u(sch_1):p5e_cpu0_pe3_rx_dp(14)';
NODE_NAME     U2 CW90
 '@S9S_MB_2U_LIB.S9S_MB_2U(SCH_1):PAGE30_I140@PURE_QUANTA.SOCKET4677_AZIF0045P001C01CS(CHIPS)':
 'PE3_RX_DP14': CDS_PINID='PE3_RX_DP14';
NODE_NAME     J106 B2
 '@S9S_MB_2U_LIB.S9S_MB_2U(SCH_1):PAGE144_I65@PURE_QUANTA.CONN112_10137002101LF(CHIPS)':
 'B2': CDS_PINID='B2';
NET_NAME
'P5E_CPU0_PE3_RX_DP<15>'
 '@S9S_MB_2U_LIB.S9S_MB_2U(SCH_1):P5E_CPU0_PE3_RX_DP'<15>:
 C_SIGNAL='@s9s_mb_2u_lib.s9s_mb_2u(sch_1):p5e_cpu0_pe3_rx_dp(15)';
NODE_NAME     U2 CT91
 '@S9S_MB_2U_LIB.S9S_MB_2U(SCH_1):PAGE30_I140@PURE_QUANTA.SOCKET4677_AZIF0045P001C01CS(CHIPS)':
 'PE3_RX_DP15': CDS_PINID='PE3_RX_DP15';
NODE_NAME     J106 C1
 '@S9S_MB_2U_LIB.S9S_MB_2U(SCH_1):PAGE144_I65@PURE_QUANTA.CONN112_10137002101LF(CHIPS)':
 'C1': CDS_PINID='C1';
NET_NAME
'P5E_CPU0_PE3_RX_DP<1>'
 '@S9S_MB_2U_LIB.S9S_MB_2U(SCH_1):P5E_CPU0_PE3_RX_DP'<1>:
 C_SIGNAL='@s9s_mb_2u_lib.s9s_mb_2u(sch_1):p5e_cpu0_pe3_rx_dp(1)';
NODE_NAME     U2 EE90
 '@S9S_MB_2U_LIB.S9S_MB_2U(SCH_1):PAGE30_I140@PURE_QUANTA.SOCKET4677_AZIF0045P001C01CS(CHIPS)':
 'PE3_RX_DP1': CDS_PINID='PE3_RX_DP1';
NODE_NAME     J105 D7
 '@S9S_MB_2U_LIB.S9S_MB_2U(SCH_1):PAGE142_I68@PURE_QUANTA.CONN112_10137002101LF(CHIPS)':
 'D7': CDS_PINID='D7';
NET_NAME
'P5E_CPU0_PE3_RX_DP<2>'
 '@S9S_MB_2U_LIB.S9S_MB_2U(SCH_1):P5E_CPU0_PE3_RX_DP'<2>:
 C_SIGNAL='@s9s_mb_2u_lib.s9s_mb_2u(sch_1):p5e_cpu0_pe3_rx_dp(2)';
NODE_NAME     U2 EB89
 '@S9S_MB_2U_LIB.S9S_MB_2U(SCH_1):PAGE30_I140@PURE_QUANTA.SOCKET4677_AZIF0045P001C01CS(CHIPS)':
 'PE3_RX_DP2': CDS_PINID='PE3_RX_DP2';
NODE_NAME     J105 C6
 '@S9S_MB_2U_LIB.S9S_MB_2U(SCH_1):PAGE142_I68@PURE_QUANTA.CONN112_10137002101LF(CHIPS)':
 'C6': CDS_PINID='C6';
NET_NAME
'P5E_CPU0_PE3_RX_DP<3>'
 '@S9S_MB_2U_LIB.S9S_MB_2U(SCH_1):P5E_CPU0_PE3_RX_DP'<3>:
 C_SIGNAL='@s9s_mb_2u_lib.s9s_mb_2u(sch_1):p5e_cpu0_pe3_rx_dp(3)';
NODE_NAME     U2 EA90
 '@S9S_MB_2U_LIB.S9S_MB_2U(SCH_1):PAGE30_I140@PURE_QUANTA.SOCKET4677_AZIF0045P001C01CS(CHIPS)':
 'PE3_RX_DP3': CDS_PINID='PE3_RX_DP3';
NODE_NAME     J105 D5
 '@S9S_MB_2U_LIB.S9S_MB_2U(SCH_1):PAGE142_I68@PURE_QUANTA.CONN112_10137002101LF(CHIPS)':
 'D5': CDS_PINID='D5';
NET_NAME
'P5E_CPU0_PE3_RX_DP<4>'
 '@S9S_MB_2U_LIB.S9S_MB_2U(SCH_1):P5E_CPU0_PE3_RX_DP'<4>:
 C_SIGNAL='@s9s_mb_2u_lib.s9s_mb_2u(sch_1):p5e_cpu0_pe3_rx_dp(4)';
NODE_NAME     U2 DW90
 '@S9S_MB_2U_LIB.S9S_MB_2U(SCH_1):PAGE30_I140@PURE_QUANTA.SOCKET4677_AZIF0045P001C01CS(CHIPS)':
 'PE3_RX_DP4': CDS_PINID='PE3_RX_DP4';
NODE_NAME     J105 B4
 '@S9S_MB_2U_LIB.S9S_MB_2U(SCH_1):PAGE142_I65@PURE_QUANTA.CONN112_10137002101LF(CHIPS)':
 'B4': CDS_PINID='B4';
NET_NAME
'P5E_CPU0_PE3_RX_DP<5>'
 '@S9S_MB_2U_LIB.S9S_MB_2U(SCH_1):P5E_CPU0_PE3_RX_DP'<5>:
 C_SIGNAL='@s9s_mb_2u_lib.s9s_mb_2u(sch_1):p5e_cpu0_pe3_rx_dp(5)';
NODE_NAME     U2 DT91
 '@S9S_MB_2U_LIB.S9S_MB_2U(SCH_1):PAGE30_I140@PURE_QUANTA.SOCKET4677_AZIF0045P001C01CS(CHIPS)':
 'PE3_RX_DP5': CDS_PINID='PE3_RX_DP5';
NODE_NAME     J105 C3
 '@S9S_MB_2U_LIB.S9S_MB_2U(SCH_1):PAGE142_I65@PURE_QUANTA.CONN112_10137002101LF(CHIPS)':
 'C3': CDS_PINID='C3';
NET_NAME
'P5E_CPU0_PE3_RX_DP<6>'
 '@S9S_MB_2U_LIB.S9S_MB_2U(SCH_1):P5E_CPU0_PE3_RX_DP'<6>:
 C_SIGNAL='@s9s_mb_2u_lib.s9s_mb_2u(sch_1):p5e_cpu0_pe3_rx_dp(6)';
NODE_NAME     U2 DR90
 '@S9S_MB_2U_LIB.S9S_MB_2U(SCH_1):PAGE30_I140@PURE_QUANTA.SOCKET4677_AZIF0045P001C01CS(CHIPS)':
 'PE3_RX_DP6': CDS_PINID='PE3_RX_DP6';
NODE_NAME     J105 B2
 '@S9S_MB_2U_LIB.S9S_MB_2U(SCH_1):PAGE142_I65@PURE_QUANTA.CONN112_10137002101LF(CHIPS)':
 'B2': CDS_PINID='B2';
NET_NAME
'P5E_CPU0_PE3_RX_DP<7>'
 '@S9S_MB_2U_LIB.S9S_MB_2U(SCH_1):P5E_CPU0_PE3_RX_DP'<7>:
 C_SIGNAL='@s9s_mb_2u_lib.s9s_mb_2u(sch_1):p5e_cpu0_pe3_rx_dp(7)';
NODE_NAME     U2 DM91
 '@S9S_MB_2U_LIB.S9S_MB_2U(SCH_1):PAGE30_I140@PURE_QUANTA.SOCKET4677_AZIF0045P001C01CS(CHIPS)':
 'PE3_RX_DP7': CDS_PINID='PE3_RX_DP7';
NODE_NAME     J105 C1
 '@S9S_MB_2U_LIB.S9S_MB_2U(SCH_1):PAGE142_I65@PURE_QUANTA.CONN112_10137002101LF(CHIPS)':
 'C1': CDS_PINID='C1';
NET_NAME
'P5E_CPU0_PE3_RX_DP<8>'
 '@S9S_MB_2U_LIB.S9S_MB_2U(SCH_1):P5E_CPU0_PE3_RX_DP'<8>:
 C_SIGNAL='@s9s_mb_2u_lib.s9s_mb_2u(sch_1):p5e_cpu0_pe3_rx_dp(8)';
NODE_NAME     U2 DK89
 '@S9S_MB_2U_LIB.S9S_MB_2U(SCH_1):PAGE30_I140@PURE_QUANTA.SOCKET4677_AZIF0045P001C01CS(CHIPS)':
 'PE3_RX_DP8': CDS_PINID='PE3_RX_DP8';
NODE_NAME     J106 C8
 '@S9S_MB_2U_LIB.S9S_MB_2U(SCH_1):PAGE144_I68@PURE_QUANTA.CONN112_10137002101LF(CHIPS)':
 'C8': CDS_PINID='C8';
NET_NAME
'P5E_CPU0_PE3_RX_DP<9>'
 '@S9S_MB_2U_LIB.S9S_MB_2U(SCH_1):P5E_CPU0_PE3_RX_DP'<9>:
 C_SIGNAL='@s9s_mb_2u_lib.s9s_mb_2u(sch_1):p5e_cpu0_pe3_rx_dp(9)';
NODE_NAME     U2 DJ90
 '@S9S_MB_2U_LIB.S9S_MB_2U(SCH_1):PAGE30_I140@PURE_QUANTA.SOCKET4677_AZIF0045P001C01CS(CHIPS)':
 'PE3_RX_DP9': CDS_PINID='PE3_RX_DP9';
NODE_NAME     J106 D7
 '@S9S_MB_2U_LIB.S9S_MB_2U(SCH_1):PAGE144_I68@PURE_QUANTA.CONN112_10137002101LF(CHIPS)':
 'D7': CDS_PINID='D7';
NET_NAME
'P5E_CPU0_PE3_TX_C_DN<0>'
 '@S9S_MB_2U_LIB.S9S_MB_2U(SCH_1):P5E_CPU0_PE3_TX_C_DN'<0>:
 C_SIGNAL='@s9s_mb_2u_lib.s9s_mb_2u(sch_1):p5e_cpu0_pe3_tx_c_dn(0)';
NODE_NAME     C900 1
 '@S9S_MB_2U_LIB.S9S_MB_2U(SCH_1):PAGE165_I121@PURE_QUANTA.Q_CAP_DIFFBUS(CHIPS)':
 '1': CDS_PINID='\1\';
NODE_NAME     J105 I8
 '@S9S_MB_2U_LIB.S9S_MB_2U(SCH_1):PAGE142_I68@PURE_QUANTA.CONN112_10137002101LF(CHIPS)':
 'I8': CDS_PINID='I8';
NET_NAME
'P5E_CPU0_PE3_TX_C_DN<10>'
 '@S9S_MB_2U_LIB.S9S_MB_2U(SCH_1):P5E_CPU0_PE3_TX_C_DN'<10>:
 C_SIGNAL='@s9s_mb_2u_lib.s9s_mb_2u(sch_1):p5e_cpu0_pe3_tx_c_dn(10)';
NODE_NAME     C880 1
 '@S9S_MB_2U_LIB.S9S_MB_2U(SCH_1):PAGE165_I156@PURE_QUANTA.Q_CAP_DIFFBUS(CHIPS)':
 '1': CDS_PINID='\1\';
NODE_NAME     J106 H6
 '@S9S_MB_2U_LIB.S9S_MB_2U(SCH_1):PAGE144_I68@PURE_QUANTA.CONN112_10137002101LF(CHIPS)':
 'H6': CDS_PINID='H6';
NET_NAME
'P5E_CPU0_PE3_TX_C_DN<11>'
 '@S9S_MB_2U_LIB.S9S_MB_2U(SCH_1):P5E_CPU0_PE3_TX_C_DN'<11>:
 C_SIGNAL='@s9s_mb_2u_lib.s9s_mb_2u(sch_1):p5e_cpu0_pe3_tx_c_dn(11)';
NODE_NAME     C878 1
 '@S9S_MB_2U_LIB.S9S_MB_2U(SCH_1):PAGE165_I157@PURE_QUANTA.Q_CAP_DIFFBUS(CHIPS)':
 '1': CDS_PINID='\1\';
NODE_NAME     J106 I5
 '@S9S_MB_2U_LIB.S9S_MB_2U(SCH_1):PAGE144_I68@PURE_QUANTA.CONN112_10137002101LF(CHIPS)':
 'I5': CDS_PINID='I5';
NET_NAME
'P5E_CPU0_PE3_TX_C_DN<12>'
 '@S9S_MB_2U_LIB.S9S_MB_2U(SCH_1):P5E_CPU0_PE3_TX_C_DN'<12>:
 C_SIGNAL='@s9s_mb_2u_lib.s9s_mb_2u(sch_1):p5e_cpu0_pe3_tx_c_dn(12)';
NODE_NAME     C876 1
 '@S9S_MB_2U_LIB.S9S_MB_2U(SCH_1):PAGE165_I160@PURE_QUANTA.Q_CAP_DIFFBUS(CHIPS)':
 '1': CDS_PINID='\1\';
NODE_NAME     J106 H4
 '@S9S_MB_2U_LIB.S9S_MB_2U(SCH_1):PAGE144_I65@PURE_QUANTA.CONN112_10137002101LF(CHIPS)':
 'H4': CDS_PINID='H4';
NET_NAME
'P5E_CPU0_PE3_TX_C_DN<13>'
 '@S9S_MB_2U_LIB.S9S_MB_2U(SCH_1):P5E_CPU0_PE3_TX_C_DN'<13>:
 C_SIGNAL='@s9s_mb_2u_lib.s9s_mb_2u(sch_1):p5e_cpu0_pe3_tx_c_dn(13)';
NODE_NAME     C874 1
 '@S9S_MB_2U_LIB.S9S_MB_2U(SCH_1):PAGE165_I165@PURE_QUANTA.Q_CAP_DIFFBUS(CHIPS)':
 '1': CDS_PINID='\1\';
NODE_NAME     J106 I3
 '@S9S_MB_2U_LIB.S9S_MB_2U(SCH_1):PAGE144_I65@PURE_QUANTA.CONN112_10137002101LF(CHIPS)':
 'I3': CDS_PINID='I3';
NET_NAME
'P5E_CPU0_PE3_TX_C_DN<14>'
 '@S9S_MB_2U_LIB.S9S_MB_2U(SCH_1):P5E_CPU0_PE3_TX_C_DN'<14>:
 C_SIGNAL='@s9s_mb_2u_lib.s9s_mb_2u(sch_1):p5e_cpu0_pe3_tx_c_dn(14)';
NODE_NAME     C872 1
 '@S9S_MB_2U_LIB.S9S_MB_2U(SCH_1):PAGE165_I167@PURE_QUANTA.Q_CAP_DIFFBUS(CHIPS)':
 '1': CDS_PINID='\1\';
NODE_NAME     J106 H2
 '@S9S_MB_2U_LIB.S9S_MB_2U(SCH_1):PAGE144_I65@PURE_QUANTA.CONN112_10137002101LF(CHIPS)':
 'H2': CDS_PINID='H2';
NET_NAME
'P5E_CPU0_PE3_TX_C_DN<15>'
 '@S9S_MB_2U_LIB.S9S_MB_2U(SCH_1):P5E_CPU0_PE3_TX_C_DN'<15>:
 C_SIGNAL='@s9s_mb_2u_lib.s9s_mb_2u(sch_1):p5e_cpu0_pe3_tx_c_dn(15)';
NODE_NAME     C870 1
 '@S9S_MB_2U_LIB.S9S_MB_2U(SCH_1):PAGE165_I169@PURE_QUANTA.Q_CAP_DIFFBUS(CHIPS)':
 '1': CDS_PINID='\1\';
NODE_NAME     J106 I1
 '@S9S_MB_2U_LIB.S9S_MB_2U(SCH_1):PAGE144_I65@PURE_QUANTA.CONN112_10137002101LF(CHIPS)':
 'I1': CDS_PINID='I1';
NET_NAME
'P5E_CPU0_PE3_TX_C_DN<1>'
 '@S9S_MB_2U_LIB.S9S_MB_2U(SCH_1):P5E_CPU0_PE3_TX_C_DN'<1>:
 C_SIGNAL='@s9s_mb_2u_lib.s9s_mb_2u(sch_1):p5e_cpu0_pe3_tx_c_dn(1)';
NODE_NAME     C898 1
 '@S9S_MB_2U_LIB.S9S_MB_2U(SCH_1):PAGE165_I206@PURE_QUANTA.Q_CAP_DIFFBUS(CHIPS)':
 '1': CDS_PINID='\1\';
NODE_NAME     J105 I7
 '@S9S_MB_2U_LIB.S9S_MB_2U(SCH_1):PAGE142_I68@PURE_QUANTA.CONN112_10137002101LF(CHIPS)':
 'I7': CDS_PINID='I7';
NET_NAME
'P5E_CPU0_PE3_TX_C_DN<2>'
 '@S9S_MB_2U_LIB.S9S_MB_2U(SCH_1):P5E_CPU0_PE3_TX_C_DN'<2>:
 C_SIGNAL='@s9s_mb_2u_lib.s9s_mb_2u(sch_1):p5e_cpu0_pe3_tx_c_dn(2)';
NODE_NAME     C896 1
 '@S9S_MB_2U_LIB.S9S_MB_2U(SCH_1):PAGE165_I124@PURE_QUANTA.Q_CAP_DIFFBUS(CHIPS)':
 '1': CDS_PINID='\1\';
NODE_NAME     J105 H6
 '@S9S_MB_2U_LIB.S9S_MB_2U(SCH_1):PAGE142_I68@PURE_QUANTA.CONN112_10137002101LF(CHIPS)':
 'H6': CDS_PINID='H6';
NET_NAME
'P5E_CPU0_PE3_TX_C_DN<3>'
 '@S9S_MB_2U_LIB.S9S_MB_2U(SCH_1):P5E_CPU0_PE3_TX_C_DN'<3>:
 C_SIGNAL='@s9s_mb_2u_lib.s9s_mb_2u(sch_1):p5e_cpu0_pe3_tx_c_dn(3)';
NODE_NAME     C894 1
 '@S9S_MB_2U_LIB.S9S_MB_2U(SCH_1):PAGE165_I126@PURE_QUANTA.Q_CAP_DIFFBUS(CHIPS)':
 '1': CDS_PINID='\1\';
NODE_NAME     J105 I5
 '@S9S_MB_2U_LIB.S9S_MB_2U(SCH_1):PAGE142_I68@PURE_QUANTA.CONN112_10137002101LF(CHIPS)':
 'I5': CDS_PINID='I5';
NET_NAME
'P5E_CPU0_PE3_TX_C_DN<4>'
 '@S9S_MB_2U_LIB.S9S_MB_2U(SCH_1):P5E_CPU0_PE3_TX_C_DN'<4>:
 C_SIGNAL='@s9s_mb_2u_lib.s9s_mb_2u(sch_1):p5e_cpu0_pe3_tx_c_dn(4)';
NODE_NAME     C892 1
 '@S9S_MB_2U_LIB.S9S_MB_2U(SCH_1):PAGE165_I127@PURE_QUANTA.Q_CAP_DIFFBUS(CHIPS)':
 '1': CDS_PINID='\1\';
NODE_NAME     J105 H4
 '@S9S_MB_2U_LIB.S9S_MB_2U(SCH_1):PAGE142_I65@PURE_QUANTA.CONN112_10137002101LF(CHIPS)':
 'H4': CDS_PINID='H4';
NET_NAME
'P5E_CPU0_PE3_TX_C_DN<5>'
 '@S9S_MB_2U_LIB.S9S_MB_2U(SCH_1):P5E_CPU0_PE3_TX_C_DN'<5>:
 C_SIGNAL='@s9s_mb_2u_lib.s9s_mb_2u(sch_1):p5e_cpu0_pe3_tx_c_dn(5)';
NODE_NAME     C890 1
 '@S9S_MB_2U_LIB.S9S_MB_2U(SCH_1):PAGE165_I133@PURE_QUANTA.Q_CAP_DIFFBUS(CHIPS)':
 '1': CDS_PINID='\1\';
NODE_NAME     J105 I3
 '@S9S_MB_2U_LIB.S9S_MB_2U(SCH_1):PAGE142_I65@PURE_QUANTA.CONN112_10137002101LF(CHIPS)':
 'I3': CDS_PINID='I3';
NET_NAME
'P5E_CPU0_PE3_TX_C_DN<6>'
 '@S9S_MB_2U_LIB.S9S_MB_2U(SCH_1):P5E_CPU0_PE3_TX_C_DN'<6>:
 C_SIGNAL='@s9s_mb_2u_lib.s9s_mb_2u(sch_1):p5e_cpu0_pe3_tx_c_dn(6)';
NODE_NAME     C888 1
 '@S9S_MB_2U_LIB.S9S_MB_2U(SCH_1):PAGE165_I135@PURE_QUANTA.Q_CAP_DIFFBUS(CHIPS)':
 '1': CDS_PINID='\1\';
NODE_NAME     J105 H2
 '@S9S_MB_2U_LIB.S9S_MB_2U(SCH_1):PAGE142_I65@PURE_QUANTA.CONN112_10137002101LF(CHIPS)':
 'H2': CDS_PINID='H2';
NET_NAME
'P5E_CPU0_PE3_TX_C_DN<7>'
 '@S9S_MB_2U_LIB.S9S_MB_2U(SCH_1):P5E_CPU0_PE3_TX_C_DN'<7>:
 C_SIGNAL='@s9s_mb_2u_lib.s9s_mb_2u(sch_1):p5e_cpu0_pe3_tx_c_dn(7)';
NODE_NAME     C886 1
 '@S9S_MB_2U_LIB.S9S_MB_2U(SCH_1):PAGE165_I137@PURE_QUANTA.Q_CAP_DIFFBUS(CHIPS)':
 '1': CDS_PINID='\1\';
NODE_NAME     J105 I1
 '@S9S_MB_2U_LIB.S9S_MB_2U(SCH_1):PAGE142_I65@PURE_QUANTA.CONN112_10137002101LF(CHIPS)':
 'I1': CDS_PINID='I1';
NET_NAME
'P5E_CPU0_PE3_TX_C_DN<8>'
 '@S9S_MB_2U_LIB.S9S_MB_2U(SCH_1):P5E_CPU0_PE3_TX_C_DN'<8>:
 C_SIGNAL='@s9s_mb_2u_lib.s9s_mb_2u(sch_1):p5e_cpu0_pe3_tx_c_dn(8)';
NODE_NAME     C884 1
 '@S9S_MB_2U_LIB.S9S_MB_2U(SCH_1):PAGE165_I151@PURE_QUANTA.Q_CAP_DIFFBUS(CHIPS)':
 '1': CDS_PINID='\1\';
NODE_NAME     J106 H8
 '@S9S_MB_2U_LIB.S9S_MB_2U(SCH_1):PAGE144_I68@PURE_QUANTA.CONN112_10137002101LF(CHIPS)':
 'H8': CDS_PINID='H8';
NET_NAME
'P5E_CPU0_PE3_TX_C_DN<9>'
 '@S9S_MB_2U_LIB.S9S_MB_2U(SCH_1):P5E_CPU0_PE3_TX_C_DN'<9>:
 C_SIGNAL='@s9s_mb_2u_lib.s9s_mb_2u(sch_1):p5e_cpu0_pe3_tx_c_dn(9)';
NODE_NAME     C882 1
 '@S9S_MB_2U_LIB.S9S_MB_2U(SCH_1):PAGE165_I154@PURE_QUANTA.Q_CAP_DIFFBUS(CHIPS)':
 '1': CDS_PINID='\1\';
NODE_NAME     J106 I7
 '@S9S_MB_2U_LIB.S9S_MB_2U(SCH_1):PAGE144_I68@PURE_QUANTA.CONN112_10137002101LF(CHIPS)':
 'I7': CDS_PINID='I7';
NET_NAME
'P5E_CPU0_PE3_TX_C_DP<0>'
 '@S9S_MB_2U_LIB.S9S_MB_2U(SCH_1):P5E_CPU0_PE3_TX_C_DP'<0>:
 C_SIGNAL='@s9s_mb_2u_lib.s9s_mb_2u(sch_1):p5e_cpu0_pe3_tx_c_dp(0)';
NODE_NAME     C901 1
 '@S9S_MB_2U_LIB.S9S_MB_2U(SCH_1):PAGE165_I120@PURE_QUANTA.Q_CAP_DIFFBUS(CHIPS)':
 '1': CDS_PINID='\1\';
NODE_NAME     J105 H8
 '@S9S_MB_2U_LIB.S9S_MB_2U(SCH_1):PAGE142_I68@PURE_QUANTA.CONN112_10137002101LF(CHIPS)':
 'H8': CDS_PINID='H8';
NET_NAME
'P5E_CPU0_PE3_TX_C_DP<10>'
 '@S9S_MB_2U_LIB.S9S_MB_2U(SCH_1):P5E_CPU0_PE3_TX_C_DP'<10>:
 C_SIGNAL='@s9s_mb_2u_lib.s9s_mb_2u(sch_1):p5e_cpu0_pe3_tx_c_dp(10)';
NODE_NAME     C881 1
 '@S9S_MB_2U_LIB.S9S_MB_2U(SCH_1):PAGE165_I155@PURE_QUANTA.Q_CAP_DIFFBUS(CHIPS)':
 '1': CDS_PINID='\1\';
NODE_NAME     J106 I6
 '@S9S_MB_2U_LIB.S9S_MB_2U(SCH_1):PAGE144_I68@PURE_QUANTA.CONN112_10137002101LF(CHIPS)':
 'I6': CDS_PINID='I6';
NET_NAME
'P5E_CPU0_PE3_TX_C_DP<11>'
 '@S9S_MB_2U_LIB.S9S_MB_2U(SCH_1):P5E_CPU0_PE3_TX_C_DP'<11>:
 C_SIGNAL='@s9s_mb_2u_lib.s9s_mb_2u(sch_1):p5e_cpu0_pe3_tx_c_dp(11)';
NODE_NAME     C879 1
 '@S9S_MB_2U_LIB.S9S_MB_2U(SCH_1):PAGE165_I158@PURE_QUANTA.Q_CAP_DIFFBUS(CHIPS)':
 '1': CDS_PINID='\1\';
NODE_NAME     J106 J5
 '@S9S_MB_2U_LIB.S9S_MB_2U(SCH_1):PAGE144_I68@PURE_QUANTA.CONN112_10137002101LF(CHIPS)':
 'J5': CDS_PINID='J5';
NET_NAME
'P5E_CPU0_PE3_TX_C_DP<12>'
 '@S9S_MB_2U_LIB.S9S_MB_2U(SCH_1):P5E_CPU0_PE3_TX_C_DP'<12>:
 C_SIGNAL='@s9s_mb_2u_lib.s9s_mb_2u(sch_1):p5e_cpu0_pe3_tx_c_dp(12)';
NODE_NAME     C877 1
 '@S9S_MB_2U_LIB.S9S_MB_2U(SCH_1):PAGE165_I159@PURE_QUANTA.Q_CAP_DIFFBUS(CHIPS)':
 '1': CDS_PINID='\1\';
NODE_NAME     J106 I4
 '@S9S_MB_2U_LIB.S9S_MB_2U(SCH_1):PAGE144_I65@PURE_QUANTA.CONN112_10137002101LF(CHIPS)':
 'I4': CDS_PINID='I4';
NET_NAME
'P5E_CPU0_PE3_TX_C_DP<13>'
 '@S9S_MB_2U_LIB.S9S_MB_2U(SCH_1):P5E_CPU0_PE3_TX_C_DP'<13>:
 C_SIGNAL='@s9s_mb_2u_lib.s9s_mb_2u(sch_1):p5e_cpu0_pe3_tx_c_dp(13)';
NODE_NAME     C875 1
 '@S9S_MB_2U_LIB.S9S_MB_2U(SCH_1):PAGE165_I164@PURE_QUANTA.Q_CAP_DIFFBUS(CHIPS)':
 '1': CDS_PINID='\1\';
NODE_NAME     J106 J3
 '@S9S_MB_2U_LIB.S9S_MB_2U(SCH_1):PAGE144_I65@PURE_QUANTA.CONN112_10137002101LF(CHIPS)':
 'J3': CDS_PINID='J3';
NET_NAME
'P5E_CPU0_PE3_TX_C_DP<14>'
 '@S9S_MB_2U_LIB.S9S_MB_2U(SCH_1):P5E_CPU0_PE3_TX_C_DP'<14>:
 C_SIGNAL='@s9s_mb_2u_lib.s9s_mb_2u(sch_1):p5e_cpu0_pe3_tx_c_dp(14)';
NODE_NAME     C873 1
 '@S9S_MB_2U_LIB.S9S_MB_2U(SCH_1):PAGE165_I166@PURE_QUANTA.Q_CAP_DIFFBUS(CHIPS)':
 '1': CDS_PINID='\1\';
NODE_NAME     J106 I2
 '@S9S_MB_2U_LIB.S9S_MB_2U(SCH_1):PAGE144_I65@PURE_QUANTA.CONN112_10137002101LF(CHIPS)':
 'I2': CDS_PINID='I2';
NET_NAME
'P5E_CPU0_PE3_TX_C_DP<15>'
 '@S9S_MB_2U_LIB.S9S_MB_2U(SCH_1):P5E_CPU0_PE3_TX_C_DP'<15>:
 C_SIGNAL='@s9s_mb_2u_lib.s9s_mb_2u(sch_1):p5e_cpu0_pe3_tx_c_dp(15)';
NODE_NAME     C871 1
 '@S9S_MB_2U_LIB.S9S_MB_2U(SCH_1):PAGE165_I168@PURE_QUANTA.Q_CAP_DIFFBUS(CHIPS)':
 '1': CDS_PINID='\1\';
NODE_NAME     J106 J1
 '@S9S_MB_2U_LIB.S9S_MB_2U(SCH_1):PAGE144_I65@PURE_QUANTA.CONN112_10137002101LF(CHIPS)':
 'J1': CDS_PINID='J1';
NET_NAME
'P5E_CPU0_PE3_TX_C_DP<1>'
 '@S9S_MB_2U_LIB.S9S_MB_2U(SCH_1):P5E_CPU0_PE3_TX_C_DP'<1>:
 C_SIGNAL='@s9s_mb_2u_lib.s9s_mb_2u(sch_1):p5e_cpu0_pe3_tx_c_dp(1)';
NODE_NAME     C899 1
 '@S9S_MB_2U_LIB.S9S_MB_2U(SCH_1):PAGE165_I122@PURE_QUANTA.Q_CAP_DIFFBUS(CHIPS)':
 '1': CDS_PINID='\1\';
NODE_NAME     J105 J7
 '@S9S_MB_2U_LIB.S9S_MB_2U(SCH_1):PAGE142_I68@PURE_QUANTA.CONN112_10137002101LF(CHIPS)':
 'J7': CDS_PINID='J7';
NET_NAME
'P5E_CPU0_PE3_TX_C_DP<2>'
 '@S9S_MB_2U_LIB.S9S_MB_2U(SCH_1):P5E_CPU0_PE3_TX_C_DP'<2>:
 C_SIGNAL='@s9s_mb_2u_lib.s9s_mb_2u(sch_1):p5e_cpu0_pe3_tx_c_dp(2)';
NODE_NAME     C897 1
 '@S9S_MB_2U_LIB.S9S_MB_2U(SCH_1):PAGE165_I123@PURE_QUANTA.Q_CAP_DIFFBUS(CHIPS)':
 '1': CDS_PINID='\1\';
NODE_NAME     J105 I6
 '@S9S_MB_2U_LIB.S9S_MB_2U(SCH_1):PAGE142_I68@PURE_QUANTA.CONN112_10137002101LF(CHIPS)':
 'I6': CDS_PINID='I6';
NET_NAME
'P5E_CPU0_PE3_TX_C_DP<3>'
 '@S9S_MB_2U_LIB.S9S_MB_2U(SCH_1):P5E_CPU0_PE3_TX_C_DP'<3>:
 C_SIGNAL='@s9s_mb_2u_lib.s9s_mb_2u(sch_1):p5e_cpu0_pe3_tx_c_dp(3)';
NODE_NAME     C895 1
 '@S9S_MB_2U_LIB.S9S_MB_2U(SCH_1):PAGE165_I125@PURE_QUANTA.Q_CAP_DIFFBUS(CHIPS)':
 '1': CDS_PINID='\1\';
NODE_NAME     J105 J5
 '@S9S_MB_2U_LIB.S9S_MB_2U(SCH_1):PAGE142_I68@PURE_QUANTA.CONN112_10137002101LF(CHIPS)':
 'J5': CDS_PINID='J5';
NET_NAME
'P5E_CPU0_PE3_TX_C_DP<4>'
 '@S9S_MB_2U_LIB.S9S_MB_2U(SCH_1):P5E_CPU0_PE3_TX_C_DP'<4>:
 C_SIGNAL='@s9s_mb_2u_lib.s9s_mb_2u(sch_1):p5e_cpu0_pe3_tx_c_dp(4)';
NODE_NAME     C893 1
 '@S9S_MB_2U_LIB.S9S_MB_2U(SCH_1):PAGE165_I128@PURE_QUANTA.Q_CAP_DIFFBUS(CHIPS)':
 '1': CDS_PINID='\1\';
NODE_NAME     J105 I4
 '@S9S_MB_2U_LIB.S9S_MB_2U(SCH_1):PAGE142_I65@PURE_QUANTA.CONN112_10137002101LF(CHIPS)':
 'I4': CDS_PINID='I4';
NET_NAME
'P5E_CPU0_PE3_TX_C_DP<5>'
 '@S9S_MB_2U_LIB.S9S_MB_2U(SCH_1):P5E_CPU0_PE3_TX_C_DP'<5>:
 C_SIGNAL='@s9s_mb_2u_lib.s9s_mb_2u(sch_1):p5e_cpu0_pe3_tx_c_dp(5)';
NODE_NAME     C891 1
 '@S9S_MB_2U_LIB.S9S_MB_2U(SCH_1):PAGE165_I132@PURE_QUANTA.Q_CAP_DIFFBUS(CHIPS)':
 '1': CDS_PINID='\1\';
NODE_NAME     J105 J3
 '@S9S_MB_2U_LIB.S9S_MB_2U(SCH_1):PAGE142_I65@PURE_QUANTA.CONN112_10137002101LF(CHIPS)':
 'J3': CDS_PINID='J3';
NET_NAME
'P5E_CPU0_PE3_TX_C_DP<6>'
 '@S9S_MB_2U_LIB.S9S_MB_2U(SCH_1):P5E_CPU0_PE3_TX_C_DP'<6>:
 C_SIGNAL='@s9s_mb_2u_lib.s9s_mb_2u(sch_1):p5e_cpu0_pe3_tx_c_dp(6)';
NODE_NAME     C889 1
 '@S9S_MB_2U_LIB.S9S_MB_2U(SCH_1):PAGE165_I134@PURE_QUANTA.Q_CAP_DIFFBUS(CHIPS)':
 '1': CDS_PINID='\1\';
NODE_NAME     J105 I2
 '@S9S_MB_2U_LIB.S9S_MB_2U(SCH_1):PAGE142_I65@PURE_QUANTA.CONN112_10137002101LF(CHIPS)':
 'I2': CDS_PINID='I2';
NET_NAME
'P5E_CPU0_PE3_TX_C_DP<7>'
 '@S9S_MB_2U_LIB.S9S_MB_2U(SCH_1):P5E_CPU0_PE3_TX_C_DP'<7>:
 C_SIGNAL='@s9s_mb_2u_lib.s9s_mb_2u(sch_1):p5e_cpu0_pe3_tx_c_dp(7)';
NODE_NAME     C887 1
 '@S9S_MB_2U_LIB.S9S_MB_2U(SCH_1):PAGE165_I136@PURE_QUANTA.Q_CAP_DIFFBUS(CHIPS)':
 '1': CDS_PINID='\1\';
NODE_NAME     J105 J1
 '@S9S_MB_2U_LIB.S9S_MB_2U(SCH_1):PAGE142_I65@PURE_QUANTA.CONN112_10137002101LF(CHIPS)':
 'J1': CDS_PINID='J1';
NET_NAME
'P5E_CPU0_PE3_TX_C_DP<8>'
 '@S9S_MB_2U_LIB.S9S_MB_2U(SCH_1):P5E_CPU0_PE3_TX_C_DP'<8>:
 C_SIGNAL='@s9s_mb_2u_lib.s9s_mb_2u(sch_1):p5e_cpu0_pe3_tx_c_dp(8)';
NODE_NAME     C885 1
 '@S9S_MB_2U_LIB.S9S_MB_2U(SCH_1):PAGE165_I152@PURE_QUANTA.Q_CAP_DIFFBUS(CHIPS)':
 '1': CDS_PINID='\1\';
NODE_NAME     J106 I8
 '@S9S_MB_2U_LIB.S9S_MB_2U(SCH_1):PAGE144_I68@PURE_QUANTA.CONN112_10137002101LF(CHIPS)':
 'I8': CDS_PINID='I8';
NET_NAME
'P5E_CPU0_PE3_TX_C_DP<9>'
 '@S9S_MB_2U_LIB.S9S_MB_2U(SCH_1):P5E_CPU0_PE3_TX_C_DP'<9>:
 C_SIGNAL='@s9s_mb_2u_lib.s9s_mb_2u(sch_1):p5e_cpu0_pe3_tx_c_dp(9)';
NODE_NAME     C883 1
 '@S9S_MB_2U_LIB.S9S_MB_2U(SCH_1):PAGE165_I153@PURE_QUANTA.Q_CAP_DIFFBUS(CHIPS)':
 '1': CDS_PINID='\1\';
NODE_NAME     J106 J7
 '@S9S_MB_2U_LIB.S9S_MB_2U(SCH_1):PAGE144_I68@PURE_QUANTA.CONN112_10137002101LF(CHIPS)':
 'J7': CDS_PINID='J7';
NET_NAME
'P5E_CPU0_PE3_TX_DN<0>'
 '@S9S_MB_2U_LIB.S9S_MB_2U(SCH_1):P5E_CPU0_PE3_TX_DN'<0>:
 C_SIGNAL='@s9s_mb_2u_lib.s9s_mb_2u(sch_1):p5e_cpu0_pe3_tx_dn(0)';
NODE_NAME     U2 EE86
 '@S9S_MB_2U_LIB.S9S_MB_2U(SCH_1):PAGE30_I140@PURE_QUANTA.SOCKET4677_AZIF0045P001C01CS(CHIPS)':
 'PE3_TX_DN0': CDS_PINID='PE3_TX_DN0';
NODE_NAME     C900 2
 '@S9S_MB_2U_LIB.S9S_MB_2U(SCH_1):PAGE165_I121@PURE_QUANTA.Q_CAP_DIFFBUS(CHIPS)':
 '2': CDS_PINID='\2\';
NET_NAME
'P5E_CPU0_PE3_TX_DN<10>'
 '@S9S_MB_2U_LIB.S9S_MB_2U(SCH_1):P5E_CPU0_PE3_TX_DN'<10>:
 C_SIGNAL='@s9s_mb_2u_lib.s9s_mb_2u(sch_1):p5e_cpu0_pe3_tx_dn(10)';
NODE_NAME     U2 DD87
 '@S9S_MB_2U_LIB.S9S_MB_2U(SCH_1):PAGE30_I140@PURE_QUANTA.SOCKET4677_AZIF0045P001C01CS(CHIPS)':
 'PE3_TX_DN10': CDS_PINID='PE3_TX_DN10';
NODE_NAME     C880 2
 '@S9S_MB_2U_LIB.S9S_MB_2U(SCH_1):PAGE165_I156@PURE_QUANTA.Q_CAP_DIFFBUS(CHIPS)':
 '2': CDS_PINID='\2\';
NET_NAME
'P5E_CPU0_PE3_TX_DN<11>'
 '@S9S_MB_2U_LIB.S9S_MB_2U(SCH_1):P5E_CPU0_PE3_TX_DN'<11>:
 C_SIGNAL='@s9s_mb_2u_lib.s9s_mb_2u(sch_1):p5e_cpu0_pe3_tx_dn(11)';
NODE_NAME     U2 DB85
 '@S9S_MB_2U_LIB.S9S_MB_2U(SCH_1):PAGE30_I140@PURE_QUANTA.SOCKET4677_AZIF0045P001C01CS(CHIPS)':
 'PE3_TX_DN11': CDS_PINID='PE3_TX_DN11';
NODE_NAME     C878 2
 '@S9S_MB_2U_LIB.S9S_MB_2U(SCH_1):PAGE165_I157@PURE_QUANTA.Q_CAP_DIFFBUS(CHIPS)':
 '2': CDS_PINID='\2\';
NET_NAME
'P5E_CPU0_PE3_TX_DN<12>'
 '@S9S_MB_2U_LIB.S9S_MB_2U(SCH_1):P5E_CPU0_PE3_TX_DN'<12>:
 C_SIGNAL='@s9s_mb_2u_lib.s9s_mb_2u(sch_1):p5e_cpu0_pe3_tx_dn(12)';
NODE_NAME     U2 CY87
 '@S9S_MB_2U_LIB.S9S_MB_2U(SCH_1):PAGE30_I140@PURE_QUANTA.SOCKET4677_AZIF0045P001C01CS(CHIPS)':
 'PE3_TX_DN12': CDS_PINID='PE3_TX_DN12';
NODE_NAME     C876 2
 '@S9S_MB_2U_LIB.S9S_MB_2U(SCH_1):PAGE165_I160@PURE_QUANTA.Q_CAP_DIFFBUS(CHIPS)':
 '2': CDS_PINID='\2\';
NET_NAME
'P5E_CPU0_PE3_TX_DN<13>'
 '@S9S_MB_2U_LIB.S9S_MB_2U(SCH_1):P5E_CPU0_PE3_TX_DN'<13>:
 C_SIGNAL='@s9s_mb_2u_lib.s9s_mb_2u(sch_1):p5e_cpu0_pe3_tx_dn(13)';
NODE_NAME     U2 CV85
 '@S9S_MB_2U_LIB.S9S_MB_2U(SCH_1):PAGE30_I140@PURE_QUANTA.SOCKET4677_AZIF0045P001C01CS(CHIPS)':
 'PE3_TX_DN13': CDS_PINID='PE3_TX_DN13';
NODE_NAME     C874 2
 '@S9S_MB_2U_LIB.S9S_MB_2U(SCH_1):PAGE165_I165@PURE_QUANTA.Q_CAP_DIFFBUS(CHIPS)':
 '2': CDS_PINID='\2\';
NET_NAME
'P5E_CPU0_PE3_TX_DN<14>'
 '@S9S_MB_2U_LIB.S9S_MB_2U(SCH_1):P5E_CPU0_PE3_TX_DN'<14>:
 C_SIGNAL='@s9s_mb_2u_lib.s9s_mb_2u(sch_1):p5e_cpu0_pe3_tx_dn(14)';
NODE_NAME     U2 CT87
 '@S9S_MB_2U_LIB.S9S_MB_2U(SCH_1):PAGE30_I140@PURE_QUANTA.SOCKET4677_AZIF0045P001C01CS(CHIPS)':
 'PE3_TX_DN14': CDS_PINID='PE3_TX_DN14';
NODE_NAME     C872 2
 '@S9S_MB_2U_LIB.S9S_MB_2U(SCH_1):PAGE165_I167@PURE_QUANTA.Q_CAP_DIFFBUS(CHIPS)':
 '2': CDS_PINID='\2\';
NET_NAME
'P5E_CPU0_PE3_TX_DN<15>'
 '@S9S_MB_2U_LIB.S9S_MB_2U(SCH_1):P5E_CPU0_PE3_TX_DN'<15>:
 C_SIGNAL='@s9s_mb_2u_lib.s9s_mb_2u(sch_1):p5e_cpu0_pe3_tx_dn(15)';
NODE_NAME     U2 CP85
 '@S9S_MB_2U_LIB.S9S_MB_2U(SCH_1):PAGE30_I140@PURE_QUANTA.SOCKET4677_AZIF0045P001C01CS(CHIPS)':
 'PE3_TX_DN15': CDS_PINID='PE3_TX_DN15';
NODE_NAME     C870 2
 '@S9S_MB_2U_LIB.S9S_MB_2U(SCH_1):PAGE165_I169@PURE_QUANTA.Q_CAP_DIFFBUS(CHIPS)':
 '2': CDS_PINID='\2\';
NET_NAME
'P5E_CPU0_PE3_TX_DN<1>'
 '@S9S_MB_2U_LIB.S9S_MB_2U(SCH_1):P5E_CPU0_PE3_TX_DN'<1>:
 C_SIGNAL='@s9s_mb_2u_lib.s9s_mb_2u(sch_1):p5e_cpu0_pe3_tx_dn(1)';
NODE_NAME     U2 EB85
 '@S9S_MB_2U_LIB.S9S_MB_2U(SCH_1):PAGE30_I140@PURE_QUANTA.SOCKET4677_AZIF0045P001C01CS(CHIPS)':
 'PE3_TX_DN1': CDS_PINID='PE3_TX_DN1';
NODE_NAME     C898 2
 '@S9S_MB_2U_LIB.S9S_MB_2U(SCH_1):PAGE165_I206@PURE_QUANTA.Q_CAP_DIFFBUS(CHIPS)':
 '2': CDS_PINID='\2\';
NET_NAME
'P5E_CPU0_PE3_TX_DN<2>'
 '@S9S_MB_2U_LIB.S9S_MB_2U(SCH_1):P5E_CPU0_PE3_TX_DN'<2>:
 C_SIGNAL='@s9s_mb_2u_lib.s9s_mb_2u(sch_1):p5e_cpu0_pe3_tx_dn(2)';
NODE_NAME     U2 DY87
 '@S9S_MB_2U_LIB.S9S_MB_2U(SCH_1):PAGE30_I140@PURE_QUANTA.SOCKET4677_AZIF0045P001C01CS(CHIPS)':
 'PE3_TX_DN2': CDS_PINID='PE3_TX_DN2';
NODE_NAME     C896 2
 '@S9S_MB_2U_LIB.S9S_MB_2U(SCH_1):PAGE165_I124@PURE_QUANTA.Q_CAP_DIFFBUS(CHIPS)':
 '2': CDS_PINID='\2\';
NET_NAME
'P5E_CPU0_PE3_TX_DN<3>'
 '@S9S_MB_2U_LIB.S9S_MB_2U(SCH_1):P5E_CPU0_PE3_TX_DN'<3>:
 C_SIGNAL='@s9s_mb_2u_lib.s9s_mb_2u(sch_1):p5e_cpu0_pe3_tx_dn(3)';
NODE_NAME     U2 DV85
 '@S9S_MB_2U_LIB.S9S_MB_2U(SCH_1):PAGE30_I140@PURE_QUANTA.SOCKET4677_AZIF0045P001C01CS(CHIPS)':
 'PE3_TX_DN3': CDS_PINID='PE3_TX_DN3';
NODE_NAME     C894 2
 '@S9S_MB_2U_LIB.S9S_MB_2U(SCH_1):PAGE165_I126@PURE_QUANTA.Q_CAP_DIFFBUS(CHIPS)':
 '2': CDS_PINID='\2\';
NET_NAME
'P5E_CPU0_PE3_TX_DN<4>'
 '@S9S_MB_2U_LIB.S9S_MB_2U(SCH_1):P5E_CPU0_PE3_TX_DN'<4>:
 C_SIGNAL='@s9s_mb_2u_lib.s9s_mb_2u(sch_1):p5e_cpu0_pe3_tx_dn(4)';
NODE_NAME     U2 DT87
 '@S9S_MB_2U_LIB.S9S_MB_2U(SCH_1):PAGE30_I140@PURE_QUANTA.SOCKET4677_AZIF0045P001C01CS(CHIPS)':
 'PE3_TX_DN4': CDS_PINID='PE3_TX_DN4';
NODE_NAME     C892 2
 '@S9S_MB_2U_LIB.S9S_MB_2U(SCH_1):PAGE165_I127@PURE_QUANTA.Q_CAP_DIFFBUS(CHIPS)':
 '2': CDS_PINID='\2\';
NET_NAME
'P5E_CPU0_PE3_TX_DN<5>'
 '@S9S_MB_2U_LIB.S9S_MB_2U(SCH_1):P5E_CPU0_PE3_TX_DN'<5>:
 C_SIGNAL='@s9s_mb_2u_lib.s9s_mb_2u(sch_1):p5e_cpu0_pe3_tx_dn(5)';
NODE_NAME     U2 DP85
 '@S9S_MB_2U_LIB.S9S_MB_2U(SCH_1):PAGE30_I140@PURE_QUANTA.SOCKET4677_AZIF0045P001C01CS(CHIPS)':
 'PE3_TX_DN5': CDS_PINID='PE3_TX_DN5';
NODE_NAME     C890 2
 '@S9S_MB_2U_LIB.S9S_MB_2U(SCH_1):PAGE165_I133@PURE_QUANTA.Q_CAP_DIFFBUS(CHIPS)':
 '2': CDS_PINID='\2\';
NET_NAME
'P5E_CPU0_PE3_TX_DN<6>'
 '@S9S_MB_2U_LIB.S9S_MB_2U(SCH_1):P5E_CPU0_PE3_TX_DN'<6>:
 C_SIGNAL='@s9s_mb_2u_lib.s9s_mb_2u(sch_1):p5e_cpu0_pe3_tx_dn(6)';
NODE_NAME     U2 DM87
 '@S9S_MB_2U_LIB.S9S_MB_2U(SCH_1):PAGE30_I140@PURE_QUANTA.SOCKET4677_AZIF0045P001C01CS(CHIPS)':
 'PE3_TX_DN6': CDS_PINID='PE3_TX_DN6';
NODE_NAME     C888 2
 '@S9S_MB_2U_LIB.S9S_MB_2U(SCH_1):PAGE165_I135@PURE_QUANTA.Q_CAP_DIFFBUS(CHIPS)':
 '2': CDS_PINID='\2\';
NET_NAME
'P5E_CPU0_PE3_TX_DN<7>'
 '@S9S_MB_2U_LIB.S9S_MB_2U(SCH_1):P5E_CPU0_PE3_TX_DN'<7>:
 C_SIGNAL='@s9s_mb_2u_lib.s9s_mb_2u(sch_1):p5e_cpu0_pe3_tx_dn(7)';
NODE_NAME     U2 DK85
 '@S9S_MB_2U_LIB.S9S_MB_2U(SCH_1):PAGE30_I140@PURE_QUANTA.SOCKET4677_AZIF0045P001C01CS(CHIPS)':
 'PE3_TX_DN7': CDS_PINID='PE3_TX_DN7';
NODE_NAME     C886 2
 '@S9S_MB_2U_LIB.S9S_MB_2U(SCH_1):PAGE165_I137@PURE_QUANTA.Q_CAP_DIFFBUS(CHIPS)':
 '2': CDS_PINID='\2\';
NET_NAME
'P5E_CPU0_PE3_TX_DN<8>'
 '@S9S_MB_2U_LIB.S9S_MB_2U(SCH_1):P5E_CPU0_PE3_TX_DN'<8>:
 C_SIGNAL='@s9s_mb_2u_lib.s9s_mb_2u(sch_1):p5e_cpu0_pe3_tx_dn(8)';
NODE_NAME     U2 DH87
 '@S9S_MB_2U_LIB.S9S_MB_2U(SCH_1):PAGE30_I140@PURE_QUANTA.SOCKET4677_AZIF0045P001C01CS(CHIPS)':
 'PE3_TX_DN8': CDS_PINID='PE3_TX_DN8';
NODE_NAME     C884 2
 '@S9S_MB_2U_LIB.S9S_MB_2U(SCH_1):PAGE165_I151@PURE_QUANTA.Q_CAP_DIFFBUS(CHIPS)':
 '2': CDS_PINID='\2\';
NET_NAME
'P5E_CPU0_PE3_TX_DN<9>'
 '@S9S_MB_2U_LIB.S9S_MB_2U(SCH_1):P5E_CPU0_PE3_TX_DN'<9>:
 C_SIGNAL='@s9s_mb_2u_lib.s9s_mb_2u(sch_1):p5e_cpu0_pe3_tx_dn(9)';
NODE_NAME     U2 DF85
 '@S9S_MB_2U_LIB.S9S_MB_2U(SCH_1):PAGE30_I140@PURE_QUANTA.SOCKET4677_AZIF0045P001C01CS(CHIPS)':
 'PE3_TX_DN9': CDS_PINID='PE3_TX_DN9';
NODE_NAME     C882 2
 '@S9S_MB_2U_LIB.S9S_MB_2U(SCH_1):PAGE165_I154@PURE_QUANTA.Q_CAP_DIFFBUS(CHIPS)':
 '2': CDS_PINID='\2\';
NET_NAME
'P5E_CPU0_PE3_TX_DP<0>'
 '@S9S_MB_2U_LIB.S9S_MB_2U(SCH_1):P5E_CPU0_PE3_TX_DP'<0>:
 C_SIGNAL='@s9s_mb_2u_lib.s9s_mb_2u(sch_1):p5e_cpu0_pe3_tx_dp(0)';
NODE_NAME     U2 ED87
 '@S9S_MB_2U_LIB.S9S_MB_2U(SCH_1):PAGE30_I140@PURE_QUANTA.SOCKET4677_AZIF0045P001C01CS(CHIPS)':
 'PE3_TX_DP0': CDS_PINID='PE3_TX_DP0';
NODE_NAME     C901 2
 '@S9S_MB_2U_LIB.S9S_MB_2U(SCH_1):PAGE165_I120@PURE_QUANTA.Q_CAP_DIFFBUS(CHIPS)':
 '2': CDS_PINID='\2\';
NET_NAME
'P5E_CPU0_PE3_TX_DP<10>'
 '@S9S_MB_2U_LIB.S9S_MB_2U(SCH_1):P5E_CPU0_PE3_TX_DP'<10>:
 C_SIGNAL='@s9s_mb_2u_lib.s9s_mb_2u(sch_1):p5e_cpu0_pe3_tx_dp(10)';
NODE_NAME     U2 DE86
 '@S9S_MB_2U_LIB.S9S_MB_2U(SCH_1):PAGE30_I140@PURE_QUANTA.SOCKET4677_AZIF0045P001C01CS(CHIPS)':
 'PE3_TX_DP10': CDS_PINID='PE3_TX_DP10';
NODE_NAME     C881 2
 '@S9S_MB_2U_LIB.S9S_MB_2U(SCH_1):PAGE165_I155@PURE_QUANTA.Q_CAP_DIFFBUS(CHIPS)':
 '2': CDS_PINID='\2\';
NET_NAME
'P5E_CPU0_PE3_TX_DP<11>'
 '@S9S_MB_2U_LIB.S9S_MB_2U(SCH_1):P5E_CPU0_PE3_TX_DP'<11>:
 C_SIGNAL='@s9s_mb_2u_lib.s9s_mb_2u(sch_1):p5e_cpu0_pe3_tx_dp(11)';
NODE_NAME     U2 DC86
 '@S9S_MB_2U_LIB.S9S_MB_2U(SCH_1):PAGE30_I140@PURE_QUANTA.SOCKET4677_AZIF0045P001C01CS(CHIPS)':
 'PE3_TX_DP11': CDS_PINID='PE3_TX_DP11';
NODE_NAME     C879 2
 '@S9S_MB_2U_LIB.S9S_MB_2U(SCH_1):PAGE165_I158@PURE_QUANTA.Q_CAP_DIFFBUS(CHIPS)':
 '2': CDS_PINID='\2\';
NET_NAME
'P5E_CPU0_PE3_TX_DP<12>'
 '@S9S_MB_2U_LIB.S9S_MB_2U(SCH_1):P5E_CPU0_PE3_TX_DP'<12>:
 C_SIGNAL='@s9s_mb_2u_lib.s9s_mb_2u(sch_1):p5e_cpu0_pe3_tx_dp(12)';
NODE_NAME     U2 DA86
 '@S9S_MB_2U_LIB.S9S_MB_2U(SCH_1):PAGE30_I140@PURE_QUANTA.SOCKET4677_AZIF0045P001C01CS(CHIPS)':
 'PE3_TX_DP12': CDS_PINID='PE3_TX_DP12';
NODE_NAME     C877 2
 '@S9S_MB_2U_LIB.S9S_MB_2U(SCH_1):PAGE165_I159@PURE_QUANTA.Q_CAP_DIFFBUS(CHIPS)':
 '2': CDS_PINID='\2\';
NET_NAME
'P5E_CPU0_PE3_TX_DP<13>'
 '@S9S_MB_2U_LIB.S9S_MB_2U(SCH_1):P5E_CPU0_PE3_TX_DP'<13>:
 C_SIGNAL='@s9s_mb_2u_lib.s9s_mb_2u(sch_1):p5e_cpu0_pe3_tx_dp(13)';
NODE_NAME     U2 CW86
 '@S9S_MB_2U_LIB.S9S_MB_2U(SCH_1):PAGE30_I140@PURE_QUANTA.SOCKET4677_AZIF0045P001C01CS(CHIPS)':
 'PE3_TX_DP13': CDS_PINID='PE3_TX_DP13';
NODE_NAME     C875 2
 '@S9S_MB_2U_LIB.S9S_MB_2U(SCH_1):PAGE165_I164@PURE_QUANTA.Q_CAP_DIFFBUS(CHIPS)':
 '2': CDS_PINID='\2\';
NET_NAME
'P5E_CPU0_PE3_TX_DP<14>'
 '@S9S_MB_2U_LIB.S9S_MB_2U(SCH_1):P5E_CPU0_PE3_TX_DP'<14>:
 C_SIGNAL='@s9s_mb_2u_lib.s9s_mb_2u(sch_1):p5e_cpu0_pe3_tx_dp(14)';
NODE_NAME     U2 CU86
 '@S9S_MB_2U_LIB.S9S_MB_2U(SCH_1):PAGE30_I140@PURE_QUANTA.SOCKET4677_AZIF0045P001C01CS(CHIPS)':
 'PE3_TX_DP14': CDS_PINID='PE3_TX_DP14';
NODE_NAME     C873 2
 '@S9S_MB_2U_LIB.S9S_MB_2U(SCH_1):PAGE165_I166@PURE_QUANTA.Q_CAP_DIFFBUS(CHIPS)':
 '2': CDS_PINID='\2\';
NET_NAME
'P5E_CPU0_PE3_TX_DP<15>'
 '@S9S_MB_2U_LIB.S9S_MB_2U(SCH_1):P5E_CPU0_PE3_TX_DP'<15>:
 C_SIGNAL='@s9s_mb_2u_lib.s9s_mb_2u(sch_1):p5e_cpu0_pe3_tx_dp(15)';
NODE_NAME     U2 CR86
 '@S9S_MB_2U_LIB.S9S_MB_2U(SCH_1):PAGE30_I140@PURE_QUANTA.SOCKET4677_AZIF0045P001C01CS(CHIPS)':
 'PE3_TX_DP15': CDS_PINID='PE3_TX_DP15';
NODE_NAME     C871 2
 '@S9S_MB_2U_LIB.S9S_MB_2U(SCH_1):PAGE165_I168@PURE_QUANTA.Q_CAP_DIFFBUS(CHIPS)':
 '2': CDS_PINID='\2\';
NET_NAME
'P5E_CPU0_PE3_TX_DP<1>'
 '@S9S_MB_2U_LIB.S9S_MB_2U(SCH_1):P5E_CPU0_PE3_TX_DP'<1>:
 C_SIGNAL='@s9s_mb_2u_lib.s9s_mb_2u(sch_1):p5e_cpu0_pe3_tx_dp(1)';
NODE_NAME     U2 EC86
 '@S9S_MB_2U_LIB.S9S_MB_2U(SCH_1):PAGE30_I140@PURE_QUANTA.SOCKET4677_AZIF0045P001C01CS(CHIPS)':
 'PE3_TX_DP1': CDS_PINID='PE3_TX_DP1';
NODE_NAME     C899 2
 '@S9S_MB_2U_LIB.S9S_MB_2U(SCH_1):PAGE165_I122@PURE_QUANTA.Q_CAP_DIFFBUS(CHIPS)':
 '2': CDS_PINID='\2\';
NET_NAME
'P5E_CPU0_PE3_TX_DP<2>'
 '@S9S_MB_2U_LIB.S9S_MB_2U(SCH_1):P5E_CPU0_PE3_TX_DP'<2>:
 C_SIGNAL='@s9s_mb_2u_lib.s9s_mb_2u(sch_1):p5e_cpu0_pe3_tx_dp(2)';
NODE_NAME     U2 EA86
 '@S9S_MB_2U_LIB.S9S_MB_2U(SCH_1):PAGE30_I140@PURE_QUANTA.SOCKET4677_AZIF0045P001C01CS(CHIPS)':
 'PE3_TX_DP2': CDS_PINID='PE3_TX_DP2';
NODE_NAME     C897 2
 '@S9S_MB_2U_LIB.S9S_MB_2U(SCH_1):PAGE165_I123@PURE_QUANTA.Q_CAP_DIFFBUS(CHIPS)':
 '2': CDS_PINID='\2\';
NET_NAME
'P5E_CPU0_PE3_TX_DP<3>'
 '@S9S_MB_2U_LIB.S9S_MB_2U(SCH_1):P5E_CPU0_PE3_TX_DP'<3>:
 C_SIGNAL='@s9s_mb_2u_lib.s9s_mb_2u(sch_1):p5e_cpu0_pe3_tx_dp(3)';
NODE_NAME     U2 DW86
 '@S9S_MB_2U_LIB.S9S_MB_2U(SCH_1):PAGE30_I140@PURE_QUANTA.SOCKET4677_AZIF0045P001C01CS(CHIPS)':
 'PE3_TX_DP3': CDS_PINID='PE3_TX_DP3';
NODE_NAME     C895 2
 '@S9S_MB_2U_LIB.S9S_MB_2U(SCH_1):PAGE165_I125@PURE_QUANTA.Q_CAP_DIFFBUS(CHIPS)':
 '2': CDS_PINID='\2\';
NET_NAME
'P5E_CPU0_PE3_TX_DP<4>'
 '@S9S_MB_2U_LIB.S9S_MB_2U(SCH_1):P5E_CPU0_PE3_TX_DP'<4>:
 C_SIGNAL='@s9s_mb_2u_lib.s9s_mb_2u(sch_1):p5e_cpu0_pe3_tx_dp(4)';
NODE_NAME     U2 DU86
 '@S9S_MB_2U_LIB.S9S_MB_2U(SCH_1):PAGE30_I140@PURE_QUANTA.SOCKET4677_AZIF0045P001C01CS(CHIPS)':
 'PE3_TX_DP4': CDS_PINID='PE3_TX_DP4';
NODE_NAME     C893 2
 '@S9S_MB_2U_LIB.S9S_MB_2U(SCH_1):PAGE165_I128@PURE_QUANTA.Q_CAP_DIFFBUS(CHIPS)':
 '2': CDS_PINID='\2\';
NET_NAME
'P5E_CPU0_PE3_TX_DP<5>'
 '@S9S_MB_2U_LIB.S9S_MB_2U(SCH_1):P5E_CPU0_PE3_TX_DP'<5>:
 C_SIGNAL='@s9s_mb_2u_lib.s9s_mb_2u(sch_1):p5e_cpu0_pe3_tx_dp(5)';
NODE_NAME     U2 DR86
 '@S9S_MB_2U_LIB.S9S_MB_2U(SCH_1):PAGE30_I140@PURE_QUANTA.SOCKET4677_AZIF0045P001C01CS(CHIPS)':
 'PE3_TX_DP5': CDS_PINID='PE3_TX_DP5';
NODE_NAME     C891 2
 '@S9S_MB_2U_LIB.S9S_MB_2U(SCH_1):PAGE165_I132@PURE_QUANTA.Q_CAP_DIFFBUS(CHIPS)':
 '2': CDS_PINID='\2\';
NET_NAME
'P5E_CPU0_PE3_TX_DP<6>'
 '@S9S_MB_2U_LIB.S9S_MB_2U(SCH_1):P5E_CPU0_PE3_TX_DP'<6>:
 C_SIGNAL='@s9s_mb_2u_lib.s9s_mb_2u(sch_1):p5e_cpu0_pe3_tx_dp(6)';
NODE_NAME     U2 DN86
 '@S9S_MB_2U_LIB.S9S_MB_2U(SCH_1):PAGE30_I140@PURE_QUANTA.SOCKET4677_AZIF0045P001C01CS(CHIPS)':
 'PE3_TX_DP6': CDS_PINID='PE3_TX_DP6';
NODE_NAME     C889 2
 '@S9S_MB_2U_LIB.S9S_MB_2U(SCH_1):PAGE165_I134@PURE_QUANTA.Q_CAP_DIFFBUS(CHIPS)':
 '2': CDS_PINID='\2\';
NET_NAME
'P5E_CPU0_PE3_TX_DP<7>'
 '@S9S_MB_2U_LIB.S9S_MB_2U(SCH_1):P5E_CPU0_PE3_TX_DP'<7>:
 C_SIGNAL='@s9s_mb_2u_lib.s9s_mb_2u(sch_1):p5e_cpu0_pe3_tx_dp(7)';
NODE_NAME     U2 DL86
 '@S9S_MB_2U_LIB.S9S_MB_2U(SCH_1):PAGE30_I140@PURE_QUANTA.SOCKET4677_AZIF0045P001C01CS(CHIPS)':
 'PE3_TX_DP7': CDS_PINID='PE3_TX_DP7';
NODE_NAME     C887 2
 '@S9S_MB_2U_LIB.S9S_MB_2U(SCH_1):PAGE165_I136@PURE_QUANTA.Q_CAP_DIFFBUS(CHIPS)':
 '2': CDS_PINID='\2\';
NET_NAME
'P5E_CPU0_PE3_TX_DP<8>'
 '@S9S_MB_2U_LIB.S9S_MB_2U(SCH_1):P5E_CPU0_PE3_TX_DP'<8>:
 C_SIGNAL='@s9s_mb_2u_lib.s9s_mb_2u(sch_1):p5e_cpu0_pe3_tx_dp(8)';
NODE_NAME     U2 DJ86
 '@S9S_MB_2U_LIB.S9S_MB_2U(SCH_1):PAGE30_I140@PURE_QUANTA.SOCKET4677_AZIF0045P001C01CS(CHIPS)':
 'PE3_TX_DP8': CDS_PINID='PE3_TX_DP8';
NODE_NAME     C885 2
 '@S9S_MB_2U_LIB.S9S_MB_2U(SCH_1):PAGE165_I152@PURE_QUANTA.Q_CAP_DIFFBUS(CHIPS)':
 '2': CDS_PINID='\2\';
NET_NAME
'P5E_CPU0_PE3_TX_DP<9>'
 '@S9S_MB_2U_LIB.S9S_MB_2U(SCH_1):P5E_CPU0_PE3_TX_DP'<9>:
 C_SIGNAL='@s9s_mb_2u_lib.s9s_mb_2u(sch_1):p5e_cpu0_pe3_tx_dp(9)';
NODE_NAME     U2 DG86
 '@S9S_MB_2U_LIB.S9S_MB_2U(SCH_1):PAGE30_I140@PURE_QUANTA.SOCKET4677_AZIF0045P001C01CS(CHIPS)':
 'PE3_TX_DP9': CDS_PINID='PE3_TX_DP9';
NODE_NAME     C883 2
 '@S9S_MB_2U_LIB.S9S_MB_2U(SCH_1):PAGE165_I153@PURE_QUANTA.Q_CAP_DIFFBUS(CHIPS)':
 '2': CDS_PINID='\2\';
NET_NAME
'P5E_CPU0_PE4_RX_DN<0>'
 '@S9S_MB_2U_LIB.S9S_MB_2U(SCH_1):P5E_CPU0_PE4_RX_DN'<0>:
 C_SIGNAL='@s9s_mb_2u_lib.s9s_mb_2u(sch_1):p5e_cpu0_pe4_rx_dn(0)';
NODE_NAME     U2 J90
 '@S9S_MB_2U_LIB.S9S_MB_2U(SCH_1):PAGE31_I139@PURE_QUANTA.SOCKET4677_AZIF0045P001C01CS(CHIPS)':
 'PE4_RX_DN0': CDS_PINID='PE4_RX_DN0';
NODE_NAME     J108 F1
 '@S9S_MB_2U_LIB.S9S_MB_2U(SCH_1):PAGE320_I57@PURE_QUANTA.CONN112_10137002101LF(CHIPS)':
 'F1': CDS_PINID='F1';
NET_NAME
'P5E_CPU0_PE4_RX_DN<10>'
 '@S9S_MB_2U_LIB.S9S_MB_2U(SCH_1):P5E_CPU0_PE4_RX_DN'<10>:
 C_SIGNAL='@s9s_mb_2u_lib.s9s_mb_2u(sch_1):p5e_cpu0_pe4_rx_dn(10)';
NODE_NAME     U2 AM91
 '@S9S_MB_2U_LIB.S9S_MB_2U(SCH_1):PAGE31_I139@PURE_QUANTA.SOCKET4677_AZIF0045P001C01CS(CHIPS)':
 'PE4_RX_DN10': CDS_PINID='PE4_RX_DN10';
NODE_NAME     J107 F3
 '@S9S_MB_2U_LIB.S9S_MB_2U(SCH_1):PAGE317_I58@PURE_QUANTA.CONN112_10137002101LF(CHIPS)':
 'F3': CDS_PINID='F3';
NET_NAME
'P5E_CPU0_PE4_RX_DN<11>'
 '@S9S_MB_2U_LIB.S9S_MB_2U(SCH_1):P5E_CPU0_PE4_RX_DN'<11>:
 C_SIGNAL='@s9s_mb_2u_lib.s9s_mb_2u(sch_1):p5e_cpu0_pe4_rx_dn(11)';
NODE_NAME     U2 AP89
 '@S9S_MB_2U_LIB.S9S_MB_2U(SCH_1):PAGE31_I139@PURE_QUANTA.SOCKET4677_AZIF0045P001C01CS(CHIPS)':
 'PE4_RX_DN11': CDS_PINID='PE4_RX_DN11';
NODE_NAME     J107 F4
 '@S9S_MB_2U_LIB.S9S_MB_2U(SCH_1):PAGE317_I58@PURE_QUANTA.CONN112_10137002101LF(CHIPS)':
 'F4': CDS_PINID='F4';
NET_NAME
'P5E_CPU0_PE4_RX_DN<12>'
 '@S9S_MB_2U_LIB.S9S_MB_2U(SCH_1):P5E_CPU0_PE4_RX_DN'<12>:
 C_SIGNAL='@s9s_mb_2u_lib.s9s_mb_2u(sch_1):p5e_cpu0_pe4_rx_dn(12)';
NODE_NAME     U2 AT91
 '@S9S_MB_2U_LIB.S9S_MB_2U(SCH_1):PAGE31_I139@PURE_QUANTA.SOCKET4677_AZIF0045P001C01CS(CHIPS)':
 'PE4_RX_DN12': CDS_PINID='PE4_RX_DN12';
NODE_NAME     J107 F5
 '@S9S_MB_2U_LIB.S9S_MB_2U(SCH_1):PAGE317_I38@PURE_QUANTA.CONN112_10137002101LF(CHIPS)':
 'F5': CDS_PINID='F5';
NET_NAME
'P5E_CPU0_PE4_RX_DN<13>'
 '@S9S_MB_2U_LIB.S9S_MB_2U(SCH_1):P5E_CPU0_PE4_RX_DN'<13>:
 C_SIGNAL='@s9s_mb_2u_lib.s9s_mb_2u(sch_1):p5e_cpu0_pe4_rx_dn(13)';
NODE_NAME     U2 AV89
 '@S9S_MB_2U_LIB.S9S_MB_2U(SCH_1):PAGE31_I139@PURE_QUANTA.SOCKET4677_AZIF0045P001C01CS(CHIPS)':
 'PE4_RX_DN13': CDS_PINID='PE4_RX_DN13';
NODE_NAME     J107 F6
 '@S9S_MB_2U_LIB.S9S_MB_2U(SCH_1):PAGE317_I38@PURE_QUANTA.CONN112_10137002101LF(CHIPS)':
 'F6': CDS_PINID='F6';
NET_NAME
'P5E_CPU0_PE4_RX_DN<14>'
 '@S9S_MB_2U_LIB.S9S_MB_2U(SCH_1):P5E_CPU0_PE4_RX_DN'<14>:
 C_SIGNAL='@s9s_mb_2u_lib.s9s_mb_2u(sch_1):p5e_cpu0_pe4_rx_dn(14)';
NODE_NAME     U2 AY91
 '@S9S_MB_2U_LIB.S9S_MB_2U(SCH_1):PAGE31_I139@PURE_QUANTA.SOCKET4677_AZIF0045P001C01CS(CHIPS)':
 'PE4_RX_DN14': CDS_PINID='PE4_RX_DN14';
NODE_NAME     J107 F7
 '@S9S_MB_2U_LIB.S9S_MB_2U(SCH_1):PAGE317_I38@PURE_QUANTA.CONN112_10137002101LF(CHIPS)':
 'F7': CDS_PINID='F7';
NET_NAME
'P5E_CPU0_PE4_RX_DN<15>'
 '@S9S_MB_2U_LIB.S9S_MB_2U(SCH_1):P5E_CPU0_PE4_RX_DN'<15>:
 C_SIGNAL='@s9s_mb_2u_lib.s9s_mb_2u(sch_1):p5e_cpu0_pe4_rx_dn(15)';
NODE_NAME     U2 BB89
 '@S9S_MB_2U_LIB.S9S_MB_2U(SCH_1):PAGE31_I139@PURE_QUANTA.SOCKET4677_AZIF0045P001C01CS(CHIPS)':
 'PE4_RX_DN15': CDS_PINID='PE4_RX_DN15';
NODE_NAME     J107 F8
 '@S9S_MB_2U_LIB.S9S_MB_2U(SCH_1):PAGE317_I38@PURE_QUANTA.CONN112_10137002101LF(CHIPS)':
 'F8': CDS_PINID='F8';
NET_NAME
'P5E_CPU0_PE4_RX_DN<1>'
 '@S9S_MB_2U_LIB.S9S_MB_2U(SCH_1):P5E_CPU0_PE4_RX_DN'<1>:
 C_SIGNAL='@s9s_mb_2u_lib.s9s_mb_2u(sch_1):p5e_cpu0_pe4_rx_dn(1)';
NODE_NAME     U2 P89
 '@S9S_MB_2U_LIB.S9S_MB_2U(SCH_1):PAGE31_I139@PURE_QUANTA.SOCKET4677_AZIF0045P001C01CS(CHIPS)':
 'PE4_RX_DN1': CDS_PINID='PE4_RX_DN1';
NODE_NAME     J108 F2
 '@S9S_MB_2U_LIB.S9S_MB_2U(SCH_1):PAGE320_I57@PURE_QUANTA.CONN112_10137002101LF(CHIPS)':
 'F2': CDS_PINID='F2';
NET_NAME
'P5E_CPU0_PE4_RX_DN<2>'
 '@S9S_MB_2U_LIB.S9S_MB_2U(SCH_1):P5E_CPU0_PE4_RX_DN'<2>:
 C_SIGNAL='@s9s_mb_2u_lib.s9s_mb_2u(sch_1):p5e_cpu0_pe4_rx_dn(2)';
NODE_NAME     U2 T91
 '@S9S_MB_2U_LIB.S9S_MB_2U(SCH_1):PAGE31_I139@PURE_QUANTA.SOCKET4677_AZIF0045P001C01CS(CHIPS)':
 'PE4_RX_DN2': CDS_PINID='PE4_RX_DN2';
NODE_NAME     J108 F3
 '@S9S_MB_2U_LIB.S9S_MB_2U(SCH_1):PAGE320_I57@PURE_QUANTA.CONN112_10137002101LF(CHIPS)':
 'F3': CDS_PINID='F3';
NET_NAME
'P5E_CPU0_PE4_RX_DN<3>'
 '@S9S_MB_2U_LIB.S9S_MB_2U(SCH_1):P5E_CPU0_PE4_RX_DN'<3>:
 C_SIGNAL='@s9s_mb_2u_lib.s9s_mb_2u(sch_1):p5e_cpu0_pe4_rx_dn(3)';
NODE_NAME     U2 V89
 '@S9S_MB_2U_LIB.S9S_MB_2U(SCH_1):PAGE31_I139@PURE_QUANTA.SOCKET4677_AZIF0045P001C01CS(CHIPS)':
 'PE4_RX_DN3': CDS_PINID='PE4_RX_DN3';
NODE_NAME     J108 F4
 '@S9S_MB_2U_LIB.S9S_MB_2U(SCH_1):PAGE320_I57@PURE_QUANTA.CONN112_10137002101LF(CHIPS)':
 'F4': CDS_PINID='F4';
NET_NAME
'P5E_CPU0_PE4_RX_DN<4>'
 '@S9S_MB_2U_LIB.S9S_MB_2U(SCH_1):P5E_CPU0_PE4_RX_DN'<4>:
 C_SIGNAL='@s9s_mb_2u_lib.s9s_mb_2u(sch_1):p5e_cpu0_pe4_rx_dn(4)';
NODE_NAME     U2 Y91
 '@S9S_MB_2U_LIB.S9S_MB_2U(SCH_1):PAGE31_I139@PURE_QUANTA.SOCKET4677_AZIF0045P001C01CS(CHIPS)':
 'PE4_RX_DN4': CDS_PINID='PE4_RX_DN4';
NODE_NAME     J108 F5
 '@S9S_MB_2U_LIB.S9S_MB_2U(SCH_1):PAGE320_I76@PURE_QUANTA.CONN112_10137002101LF(CHIPS)':
 'F5': CDS_PINID='F5';
NET_NAME
'P5E_CPU0_PE4_RX_DN<5>'
 '@S9S_MB_2U_LIB.S9S_MB_2U(SCH_1):P5E_CPU0_PE4_RX_DN'<5>:
 C_SIGNAL='@s9s_mb_2u_lib.s9s_mb_2u(sch_1):p5e_cpu0_pe4_rx_dn(5)';
NODE_NAME     U2 AB89
 '@S9S_MB_2U_LIB.S9S_MB_2U(SCH_1):PAGE31_I139@PURE_QUANTA.SOCKET4677_AZIF0045P001C01CS(CHIPS)':
 'PE4_RX_DN5': CDS_PINID='PE4_RX_DN5';
NODE_NAME     J108 F6
 '@S9S_MB_2U_LIB.S9S_MB_2U(SCH_1):PAGE320_I76@PURE_QUANTA.CONN112_10137002101LF(CHIPS)':
 'F6': CDS_PINID='F6';
NET_NAME
'P5E_CPU0_PE4_RX_DN<6>'
 '@S9S_MB_2U_LIB.S9S_MB_2U(SCH_1):P5E_CPU0_PE4_RX_DN'<6>:
 C_SIGNAL='@s9s_mb_2u_lib.s9s_mb_2u(sch_1):p5e_cpu0_pe4_rx_dn(6)';
NODE_NAME     U2 AD91
 '@S9S_MB_2U_LIB.S9S_MB_2U(SCH_1):PAGE31_I139@PURE_QUANTA.SOCKET4677_AZIF0045P001C01CS(CHIPS)':
 'PE4_RX_DN6': CDS_PINID='PE4_RX_DN6';
NODE_NAME     J108 F7
 '@S9S_MB_2U_LIB.S9S_MB_2U(SCH_1):PAGE320_I76@PURE_QUANTA.CONN112_10137002101LF(CHIPS)':
 'F7': CDS_PINID='F7';
NET_NAME
'P5E_CPU0_PE4_RX_DN<7>'
 '@S9S_MB_2U_LIB.S9S_MB_2U(SCH_1):P5E_CPU0_PE4_RX_DN'<7>:
 C_SIGNAL='@s9s_mb_2u_lib.s9s_mb_2u(sch_1):p5e_cpu0_pe4_rx_dn(7)';
NODE_NAME     U2 AF89
 '@S9S_MB_2U_LIB.S9S_MB_2U(SCH_1):PAGE31_I139@PURE_QUANTA.SOCKET4677_AZIF0045P001C01CS(CHIPS)':
 'PE4_RX_DN7': CDS_PINID='PE4_RX_DN7';
NODE_NAME     J108 F8
 '@S9S_MB_2U_LIB.S9S_MB_2U(SCH_1):PAGE320_I76@PURE_QUANTA.CONN112_10137002101LF(CHIPS)':
 'F8': CDS_PINID='F8';
NET_NAME
'P5E_CPU0_PE4_RX_DN<8>'
 '@S9S_MB_2U_LIB.S9S_MB_2U(SCH_1):P5E_CPU0_PE4_RX_DN'<8>:
 C_SIGNAL='@s9s_mb_2u_lib.s9s_mb_2u(sch_1):p5e_cpu0_pe4_rx_dn(8)';
NODE_NAME     U2 AH91
 '@S9S_MB_2U_LIB.S9S_MB_2U(SCH_1):PAGE31_I139@PURE_QUANTA.SOCKET4677_AZIF0045P001C01CS(CHIPS)':
 'PE4_RX_DN8': CDS_PINID='PE4_RX_DN8';
NODE_NAME     J107 F1
 '@S9S_MB_2U_LIB.S9S_MB_2U(SCH_1):PAGE317_I58@PURE_QUANTA.CONN112_10137002101LF(CHIPS)':
 'F1': CDS_PINID='F1';
NET_NAME
'P5E_CPU0_PE4_RX_DN<9>'
 '@S9S_MB_2U_LIB.S9S_MB_2U(SCH_1):P5E_CPU0_PE4_RX_DN'<9>:
 C_SIGNAL='@s9s_mb_2u_lib.s9s_mb_2u(sch_1):p5e_cpu0_pe4_rx_dn(9)';
NODE_NAME     U2 AK89
 '@S9S_MB_2U_LIB.S9S_MB_2U(SCH_1):PAGE31_I139@PURE_QUANTA.SOCKET4677_AZIF0045P001C01CS(CHIPS)':
 'PE4_RX_DN9': CDS_PINID='PE4_RX_DN9';
NODE_NAME     J107 F2
 '@S9S_MB_2U_LIB.S9S_MB_2U(SCH_1):PAGE317_I58@PURE_QUANTA.CONN112_10137002101LF(CHIPS)':
 'F2': CDS_PINID='F2';
NET_NAME
'P5E_CPU0_PE4_RX_DP<0>'
 '@S9S_MB_2U_LIB.S9S_MB_2U(SCH_1):P5E_CPU0_PE4_RX_DP'<0>:
 C_SIGNAL='@s9s_mb_2u_lib.s9s_mb_2u(sch_1):p5e_cpu0_pe4_rx_dp(0)';
NODE_NAME     U2 K89
 '@S9S_MB_2U_LIB.S9S_MB_2U(SCH_1):PAGE31_I139@PURE_QUANTA.SOCKET4677_AZIF0045P001C01CS(CHIPS)':
 'PE4_RX_DP0': CDS_PINID='PE4_RX_DP0';
NODE_NAME     J108 G1
 '@S9S_MB_2U_LIB.S9S_MB_2U(SCH_1):PAGE320_I57@PURE_QUANTA.CONN112_10137002101LF(CHIPS)':
 'G1': CDS_PINID='G1';
NET_NAME
'P5E_CPU0_PE4_RX_DP<10>'
 '@S9S_MB_2U_LIB.S9S_MB_2U(SCH_1):P5E_CPU0_PE4_RX_DP'<10>:
 C_SIGNAL='@s9s_mb_2u_lib.s9s_mb_2u(sch_1):p5e_cpu0_pe4_rx_dp(10)';
NODE_NAME     U2 AL90
 '@S9S_MB_2U_LIB.S9S_MB_2U(SCH_1):PAGE31_I139@PURE_QUANTA.SOCKET4677_AZIF0045P001C01CS(CHIPS)':
 'PE4_RX_DP10': CDS_PINID='PE4_RX_DP10';
NODE_NAME     J107 G3
 '@S9S_MB_2U_LIB.S9S_MB_2U(SCH_1):PAGE317_I58@PURE_QUANTA.CONN112_10137002101LF(CHIPS)':
 'G3': CDS_PINID='G3';
NET_NAME
'P5E_CPU0_PE4_RX_DP<11>'
 '@S9S_MB_2U_LIB.S9S_MB_2U(SCH_1):P5E_CPU0_PE4_RX_DP'<11>:
 C_SIGNAL='@s9s_mb_2u_lib.s9s_mb_2u(sch_1):p5e_cpu0_pe4_rx_dp(11)';
NODE_NAME     U2 AN90
 '@S9S_MB_2U_LIB.S9S_MB_2U(SCH_1):PAGE31_I139@PURE_QUANTA.SOCKET4677_AZIF0045P001C01CS(CHIPS)':
 'PE4_RX_DP11': CDS_PINID='PE4_RX_DP11';
NODE_NAME     J107 E4
 '@S9S_MB_2U_LIB.S9S_MB_2U(SCH_1):PAGE317_I58@PURE_QUANTA.CONN112_10137002101LF(CHIPS)':
 'E4': CDS_PINID='E4';
NET_NAME
'P5E_CPU0_PE4_RX_DP<12>'
 '@S9S_MB_2U_LIB.S9S_MB_2U(SCH_1):P5E_CPU0_PE4_RX_DP'<12>:
 C_SIGNAL='@s9s_mb_2u_lib.s9s_mb_2u(sch_1):p5e_cpu0_pe4_rx_dp(12)';
NODE_NAME     U2 AR90
 '@S9S_MB_2U_LIB.S9S_MB_2U(SCH_1):PAGE31_I139@PURE_QUANTA.SOCKET4677_AZIF0045P001C01CS(CHIPS)':
 'PE4_RX_DP12': CDS_PINID='PE4_RX_DP12';
NODE_NAME     J107 G5
 '@S9S_MB_2U_LIB.S9S_MB_2U(SCH_1):PAGE317_I38@PURE_QUANTA.CONN112_10137002101LF(CHIPS)':
 'G5': CDS_PINID='G5';
NET_NAME
'P5E_CPU0_PE4_RX_DP<13>'
 '@S9S_MB_2U_LIB.S9S_MB_2U(SCH_1):P5E_CPU0_PE4_RX_DP'<13>:
 C_SIGNAL='@s9s_mb_2u_lib.s9s_mb_2u(sch_1):p5e_cpu0_pe4_rx_dp(13)';
NODE_NAME     U2 AU90
 '@S9S_MB_2U_LIB.S9S_MB_2U(SCH_1):PAGE31_I139@PURE_QUANTA.SOCKET4677_AZIF0045P001C01CS(CHIPS)':
 'PE4_RX_DP13': CDS_PINID='PE4_RX_DP13';
NODE_NAME     J107 E6
 '@S9S_MB_2U_LIB.S9S_MB_2U(SCH_1):PAGE317_I38@PURE_QUANTA.CONN112_10137002101LF(CHIPS)':
 'E6': CDS_PINID='E6';
NET_NAME
'P5E_CPU0_PE4_RX_DP<14>'
 '@S9S_MB_2U_LIB.S9S_MB_2U(SCH_1):P5E_CPU0_PE4_RX_DP'<14>:
 C_SIGNAL='@s9s_mb_2u_lib.s9s_mb_2u(sch_1):p5e_cpu0_pe4_rx_dp(14)';
NODE_NAME     U2 AW90
 '@S9S_MB_2U_LIB.S9S_MB_2U(SCH_1):PAGE31_I139@PURE_QUANTA.SOCKET4677_AZIF0045P001C01CS(CHIPS)':
 'PE4_RX_DP14': CDS_PINID='PE4_RX_DP14';
NODE_NAME     J107 G7
 '@S9S_MB_2U_LIB.S9S_MB_2U(SCH_1):PAGE317_I38@PURE_QUANTA.CONN112_10137002101LF(CHIPS)':
 'G7': CDS_PINID='G7';
NET_NAME
'P5E_CPU0_PE4_RX_DP<15>'
 '@S9S_MB_2U_LIB.S9S_MB_2U(SCH_1):P5E_CPU0_PE4_RX_DP'<15>:
 C_SIGNAL='@s9s_mb_2u_lib.s9s_mb_2u(sch_1):p5e_cpu0_pe4_rx_dp(15)';
NODE_NAME     U2 BA90
 '@S9S_MB_2U_LIB.S9S_MB_2U(SCH_1):PAGE31_I139@PURE_QUANTA.SOCKET4677_AZIF0045P001C01CS(CHIPS)':
 'PE4_RX_DP15': CDS_PINID='PE4_RX_DP15';
NODE_NAME     J107 E8
 '@S9S_MB_2U_LIB.S9S_MB_2U(SCH_1):PAGE317_I38@PURE_QUANTA.CONN112_10137002101LF(CHIPS)':
 'E8': CDS_PINID='E8';
NET_NAME
'P5E_CPU0_PE4_RX_DP<1>'
 '@S9S_MB_2U_LIB.S9S_MB_2U(SCH_1):P5E_CPU0_PE4_RX_DP'<1>:
 C_SIGNAL='@s9s_mb_2u_lib.s9s_mb_2u(sch_1):p5e_cpu0_pe4_rx_dp(1)';
NODE_NAME     U2 N90
 '@S9S_MB_2U_LIB.S9S_MB_2U(SCH_1):PAGE31_I139@PURE_QUANTA.SOCKET4677_AZIF0045P001C01CS(CHIPS)':
 'PE4_RX_DP1': CDS_PINID='PE4_RX_DP1';
NODE_NAME     J108 E2
 '@S9S_MB_2U_LIB.S9S_MB_2U(SCH_1):PAGE320_I57@PURE_QUANTA.CONN112_10137002101LF(CHIPS)':
 'E2': CDS_PINID='E2';
NET_NAME
'P5E_CPU0_PE4_RX_DP<2>'
 '@S9S_MB_2U_LIB.S9S_MB_2U(SCH_1):P5E_CPU0_PE4_RX_DP'<2>:
 C_SIGNAL='@s9s_mb_2u_lib.s9s_mb_2u(sch_1):p5e_cpu0_pe4_rx_dp(2)';
NODE_NAME     U2 R90
 '@S9S_MB_2U_LIB.S9S_MB_2U(SCH_1):PAGE31_I139@PURE_QUANTA.SOCKET4677_AZIF0045P001C01CS(CHIPS)':
 'PE4_RX_DP2': CDS_PINID='PE4_RX_DP2';
NODE_NAME     J108 G3
 '@S9S_MB_2U_LIB.S9S_MB_2U(SCH_1):PAGE320_I57@PURE_QUANTA.CONN112_10137002101LF(CHIPS)':
 'G3': CDS_PINID='G3';
NET_NAME
'P5E_CPU0_PE4_RX_DP<3>'
 '@S9S_MB_2U_LIB.S9S_MB_2U(SCH_1):P5E_CPU0_PE4_RX_DP'<3>:
 C_SIGNAL='@s9s_mb_2u_lib.s9s_mb_2u(sch_1):p5e_cpu0_pe4_rx_dp(3)';
NODE_NAME     U2 U90
 '@S9S_MB_2U_LIB.S9S_MB_2U(SCH_1):PAGE31_I139@PURE_QUANTA.SOCKET4677_AZIF0045P001C01CS(CHIPS)':
 'PE4_RX_DP3': CDS_PINID='PE4_RX_DP3';
NODE_NAME     J108 E4
 '@S9S_MB_2U_LIB.S9S_MB_2U(SCH_1):PAGE320_I57@PURE_QUANTA.CONN112_10137002101LF(CHIPS)':
 'E4': CDS_PINID='E4';
NET_NAME
'P5E_CPU0_PE4_RX_DP<4>'
 '@S9S_MB_2U_LIB.S9S_MB_2U(SCH_1):P5E_CPU0_PE4_RX_DP'<4>:
 C_SIGNAL='@s9s_mb_2u_lib.s9s_mb_2u(sch_1):p5e_cpu0_pe4_rx_dp(4)';
NODE_NAME     U2 W90
 '@S9S_MB_2U_LIB.S9S_MB_2U(SCH_1):PAGE31_I139@PURE_QUANTA.SOCKET4677_AZIF0045P001C01CS(CHIPS)':
 'PE4_RX_DP4': CDS_PINID='PE4_RX_DP4';
NODE_NAME     J108 G5
 '@S9S_MB_2U_LIB.S9S_MB_2U(SCH_1):PAGE320_I76@PURE_QUANTA.CONN112_10137002101LF(CHIPS)':
 'G5': CDS_PINID='G5';
NET_NAME
'P5E_CPU0_PE4_RX_DP<5>'
 '@S9S_MB_2U_LIB.S9S_MB_2U(SCH_1):P5E_CPU0_PE4_RX_DP'<5>:
 C_SIGNAL='@s9s_mb_2u_lib.s9s_mb_2u(sch_1):p5e_cpu0_pe4_rx_dp(5)';
NODE_NAME     U2 AA90
 '@S9S_MB_2U_LIB.S9S_MB_2U(SCH_1):PAGE31_I139@PURE_QUANTA.SOCKET4677_AZIF0045P001C01CS(CHIPS)':
 'PE4_RX_DP5': CDS_PINID='PE4_RX_DP5';
NODE_NAME     J108 E6
 '@S9S_MB_2U_LIB.S9S_MB_2U(SCH_1):PAGE320_I76@PURE_QUANTA.CONN112_10137002101LF(CHIPS)':
 'E6': CDS_PINID='E6';
NET_NAME
'P5E_CPU0_PE4_RX_DP<6>'
 '@S9S_MB_2U_LIB.S9S_MB_2U(SCH_1):P5E_CPU0_PE4_RX_DP'<6>:
 C_SIGNAL='@s9s_mb_2u_lib.s9s_mb_2u(sch_1):p5e_cpu0_pe4_rx_dp(6)';
NODE_NAME     U2 AC90
 '@S9S_MB_2U_LIB.S9S_MB_2U(SCH_1):PAGE31_I139@PURE_QUANTA.SOCKET4677_AZIF0045P001C01CS(CHIPS)':
 'PE4_RX_DP6': CDS_PINID='PE4_RX_DP6';
NODE_NAME     J108 G7
 '@S9S_MB_2U_LIB.S9S_MB_2U(SCH_1):PAGE320_I76@PURE_QUANTA.CONN112_10137002101LF(CHIPS)':
 'G7': CDS_PINID='G7';
NET_NAME
'P5E_CPU0_PE4_RX_DP<7>'
 '@S9S_MB_2U_LIB.S9S_MB_2U(SCH_1):P5E_CPU0_PE4_RX_DP'<7>:
 C_SIGNAL='@s9s_mb_2u_lib.s9s_mb_2u(sch_1):p5e_cpu0_pe4_rx_dp(7)';
NODE_NAME     U2 AE90
 '@S9S_MB_2U_LIB.S9S_MB_2U(SCH_1):PAGE31_I139@PURE_QUANTA.SOCKET4677_AZIF0045P001C01CS(CHIPS)':
 'PE4_RX_DP7': CDS_PINID='PE4_RX_DP7';
NODE_NAME     J108 E8
 '@S9S_MB_2U_LIB.S9S_MB_2U(SCH_1):PAGE320_I76@PURE_QUANTA.CONN112_10137002101LF(CHIPS)':
 'E8': CDS_PINID='E8';
NET_NAME
'P5E_CPU0_PE4_RX_DP<8>'
 '@S9S_MB_2U_LIB.S9S_MB_2U(SCH_1):P5E_CPU0_PE4_RX_DP'<8>:
 C_SIGNAL='@s9s_mb_2u_lib.s9s_mb_2u(sch_1):p5e_cpu0_pe4_rx_dp(8)';
NODE_NAME     U2 AG90
 '@S9S_MB_2U_LIB.S9S_MB_2U(SCH_1):PAGE31_I139@PURE_QUANTA.SOCKET4677_AZIF0045P001C01CS(CHIPS)':
 'PE4_RX_DP8': CDS_PINID='PE4_RX_DP8';
NODE_NAME     J107 G1
 '@S9S_MB_2U_LIB.S9S_MB_2U(SCH_1):PAGE317_I58@PURE_QUANTA.CONN112_10137002101LF(CHIPS)':
 'G1': CDS_PINID='G1';
NET_NAME
'P5E_CPU0_PE4_RX_DP<9>'
 '@S9S_MB_2U_LIB.S9S_MB_2U(SCH_1):P5E_CPU0_PE4_RX_DP'<9>:
 C_SIGNAL='@s9s_mb_2u_lib.s9s_mb_2u(sch_1):p5e_cpu0_pe4_rx_dp(9)';
NODE_NAME     U2 AJ90
 '@S9S_MB_2U_LIB.S9S_MB_2U(SCH_1):PAGE31_I139@PURE_QUANTA.SOCKET4677_AZIF0045P001C01CS(CHIPS)':
 'PE4_RX_DP9': CDS_PINID='PE4_RX_DP9';
NODE_NAME     J107 E2
 '@S9S_MB_2U_LIB.S9S_MB_2U(SCH_1):PAGE317_I58@PURE_QUANTA.CONN112_10137002101LF(CHIPS)':
 'E2': CDS_PINID='E2';
NET_NAME
'P5E_CPU0_PE4_TX_C_DN<0>'
 '@S9S_MB_2U_LIB.S9S_MB_2U(SCH_1):P5E_CPU0_PE4_TX_C_DN'<0>:
 C_SIGNAL='@s9s_mb_2u_lib.s9s_mb_2u(sch_1):p5e_cpu0_pe4_tx_c_dn(0)';
NODE_NAME     C1578 1
 '@S9S_MB_2U_LIB.S9S_MB_2U(SCH_1):PAGE166_I230@PURE_QUANTA.Q_CAP_DIFFBUS(CHIPS)':
 '1': CDS_PINID='\1\';
NODE_NAME     J108 L1
 '@S9S_MB_2U_LIB.S9S_MB_2U(SCH_1):PAGE320_I57@PURE_QUANTA.CONN112_10137002101LF(CHIPS)':
 'L1': CDS_PINID='L1';
NET_NAME
'P5E_CPU0_PE4_TX_C_DN<10>'
 '@S9S_MB_2U_LIB.S9S_MB_2U(SCH_1):P5E_CPU0_PE4_TX_C_DN'<10>:
 C_SIGNAL='@s9s_mb_2u_lib.s9s_mb_2u(sch_1):p5e_cpu0_pe4_tx_c_dn(10)';
NODE_NAME     C1558 1
 '@S9S_MB_2U_LIB.S9S_MB_2U(SCH_1):PAGE166_I264@PURE_QUANTA.Q_CAP_DIFFBUS(CHIPS)':
 '1': CDS_PINID='\1\';
NODE_NAME     J107 L3
 '@S9S_MB_2U_LIB.S9S_MB_2U(SCH_1):PAGE317_I58@PURE_QUANTA.CONN112_10137002101LF(CHIPS)':
 'L3': CDS_PINID='L3';
NET_NAME
'P5E_CPU0_PE4_TX_C_DN<11>'
 '@S9S_MB_2U_LIB.S9S_MB_2U(SCH_1):P5E_CPU0_PE4_TX_C_DN'<11>:
 C_SIGNAL='@s9s_mb_2u_lib.s9s_mb_2u(sch_1):p5e_cpu0_pe4_tx_c_dn(11)';
NODE_NAME     C1556 1
 '@S9S_MB_2U_LIB.S9S_MB_2U(SCH_1):PAGE166_I265@PURE_QUANTA.Q_CAP_DIFFBUS(CHIPS)':
 '1': CDS_PINID='\1\';
NODE_NAME     J107 L4
 '@S9S_MB_2U_LIB.S9S_MB_2U(SCH_1):PAGE317_I58@PURE_QUANTA.CONN112_10137002101LF(CHIPS)':
 'L4': CDS_PINID='L4';
NET_NAME
'P5E_CPU0_PE4_TX_C_DN<12>'
 '@S9S_MB_2U_LIB.S9S_MB_2U(SCH_1):P5E_CPU0_PE4_TX_C_DN'<12>:
 C_SIGNAL='@s9s_mb_2u_lib.s9s_mb_2u(sch_1):p5e_cpu0_pe4_tx_c_dn(12)';
NODE_NAME     C1554 1
 '@S9S_MB_2U_LIB.S9S_MB_2U(SCH_1):PAGE166_I268@PURE_QUANTA.Q_CAP_DIFFBUS(CHIPS)':
 '1': CDS_PINID='\1\';
NODE_NAME     J107 L5
 '@S9S_MB_2U_LIB.S9S_MB_2U(SCH_1):PAGE317_I38@PURE_QUANTA.CONN112_10137002101LF(CHIPS)':
 'L5': CDS_PINID='L5';
NET_NAME
'P5E_CPU0_PE4_TX_C_DN<13>'
 '@S9S_MB_2U_LIB.S9S_MB_2U(SCH_1):P5E_CPU0_PE4_TX_C_DN'<13>:
 C_SIGNAL='@s9s_mb_2u_lib.s9s_mb_2u(sch_1):p5e_cpu0_pe4_tx_c_dn(13)';
NODE_NAME     C1552 1
 '@S9S_MB_2U_LIB.S9S_MB_2U(SCH_1):PAGE166_I270@PURE_QUANTA.Q_CAP_DIFFBUS(CHIPS)':
 '1': CDS_PINID='\1\';
NODE_NAME     J107 K6
 '@S9S_MB_2U_LIB.S9S_MB_2U(SCH_1):PAGE317_I38@PURE_QUANTA.CONN112_10137002101LF(CHIPS)':
 'K6': CDS_PINID='K6';
NET_NAME
'P5E_CPU0_PE4_TX_C_DN<14>'
 '@S9S_MB_2U_LIB.S9S_MB_2U(SCH_1):P5E_CPU0_PE4_TX_C_DN'<14>:
 C_SIGNAL='@s9s_mb_2u_lib.s9s_mb_2u(sch_1):p5e_cpu0_pe4_tx_c_dn(14)';
NODE_NAME     C1550 1
 '@S9S_MB_2U_LIB.S9S_MB_2U(SCH_1):PAGE166_I272@PURE_QUANTA.Q_CAP_DIFFBUS(CHIPS)':
 '1': CDS_PINID='\1\';
NODE_NAME     J107 L7
 '@S9S_MB_2U_LIB.S9S_MB_2U(SCH_1):PAGE317_I38@PURE_QUANTA.CONN112_10137002101LF(CHIPS)':
 'L7': CDS_PINID='L7';
NET_NAME
'P5E_CPU0_PE4_TX_C_DN<15>'
 '@S9S_MB_2U_LIB.S9S_MB_2U(SCH_1):P5E_CPU0_PE4_TX_C_DN'<15>:
 C_SIGNAL='@s9s_mb_2u_lib.s9s_mb_2u(sch_1):p5e_cpu0_pe4_tx_c_dn(15)';
NODE_NAME     C1548 1
 '@S9S_MB_2U_LIB.S9S_MB_2U(SCH_1):PAGE166_I273@PURE_QUANTA.Q_CAP_DIFFBUS(CHIPS)':
 '1': CDS_PINID='\1\';
NODE_NAME     J107 K8
 '@S9S_MB_2U_LIB.S9S_MB_2U(SCH_1):PAGE317_I38@PURE_QUANTA.CONN112_10137002101LF(CHIPS)':
 'K8': CDS_PINID='K8';
NET_NAME
'P5E_CPU0_PE4_TX_C_DN<1>'
 '@S9S_MB_2U_LIB.S9S_MB_2U(SCH_1):P5E_CPU0_PE4_TX_C_DN'<1>:
 C_SIGNAL='@s9s_mb_2u_lib.s9s_mb_2u(sch_1):p5e_cpu0_pe4_tx_c_dn(1)';
NODE_NAME     C1576 1
 '@S9S_MB_2U_LIB.S9S_MB_2U(SCH_1):PAGE166_I312@PURE_QUANTA.Q_CAP_DIFFBUS(CHIPS)':
 '1': CDS_PINID='\1\';
NODE_NAME     J108 L2
 '@S9S_MB_2U_LIB.S9S_MB_2U(SCH_1):PAGE320_I57@PURE_QUANTA.CONN112_10137002101LF(CHIPS)':
 'L2': CDS_PINID='L2';
NET_NAME
'P5E_CPU0_PE4_TX_C_DN<2>'
 '@S9S_MB_2U_LIB.S9S_MB_2U(SCH_1):P5E_CPU0_PE4_TX_C_DN'<2>:
 C_SIGNAL='@s9s_mb_2u_lib.s9s_mb_2u(sch_1):p5e_cpu0_pe4_tx_c_dn(2)';
NODE_NAME     C1574 1
 '@S9S_MB_2U_LIB.S9S_MB_2U(SCH_1):PAGE166_I232@PURE_QUANTA.Q_CAP_DIFFBUS(CHIPS)':
 '1': CDS_PINID='\1\';
NODE_NAME     J108 L3
 '@S9S_MB_2U_LIB.S9S_MB_2U(SCH_1):PAGE320_I57@PURE_QUANTA.CONN112_10137002101LF(CHIPS)':
 'L3': CDS_PINID='L3';
NET_NAME
'P5E_CPU0_PE4_TX_C_DN<3>'
 '@S9S_MB_2U_LIB.S9S_MB_2U(SCH_1):P5E_CPU0_PE4_TX_C_DN'<3>:
 C_SIGNAL='@s9s_mb_2u_lib.s9s_mb_2u(sch_1):p5e_cpu0_pe4_tx_c_dn(3)';
NODE_NAME     C1572 1
 '@S9S_MB_2U_LIB.S9S_MB_2U(SCH_1):PAGE166_I234@PURE_QUANTA.Q_CAP_DIFFBUS(CHIPS)':
 '1': CDS_PINID='\1\';
NODE_NAME     J108 K4
 '@S9S_MB_2U_LIB.S9S_MB_2U(SCH_1):PAGE320_I57@PURE_QUANTA.CONN112_10137002101LF(CHIPS)':
 'K4': CDS_PINID='K4';
NET_NAME
'P5E_CPU0_PE4_TX_C_DN<4>'
 '@S9S_MB_2U_LIB.S9S_MB_2U(SCH_1):P5E_CPU0_PE4_TX_C_DN'<4>:
 C_SIGNAL='@s9s_mb_2u_lib.s9s_mb_2u(sch_1):p5e_cpu0_pe4_tx_c_dn(4)';
NODE_NAME     C1570 1
 '@S9S_MB_2U_LIB.S9S_MB_2U(SCH_1):PAGE166_I235@PURE_QUANTA.Q_CAP_DIFFBUS(CHIPS)':
 '1': CDS_PINID='\1\';
NODE_NAME     J108 L5
 '@S9S_MB_2U_LIB.S9S_MB_2U(SCH_1):PAGE320_I76@PURE_QUANTA.CONN112_10137002101LF(CHIPS)':
 'L5': CDS_PINID='L5';
NET_NAME
'P5E_CPU0_PE4_TX_C_DN<5>'
 '@S9S_MB_2U_LIB.S9S_MB_2U(SCH_1):P5E_CPU0_PE4_TX_C_DN'<5>:
 C_SIGNAL='@s9s_mb_2u_lib.s9s_mb_2u(sch_1):p5e_cpu0_pe4_tx_c_dn(5)';
NODE_NAME     C1568 1
 '@S9S_MB_2U_LIB.S9S_MB_2U(SCH_1):PAGE166_I238@PURE_QUANTA.Q_CAP_DIFFBUS(CHIPS)':
 '1': CDS_PINID='\1\';
NODE_NAME     J108 K6
 '@S9S_MB_2U_LIB.S9S_MB_2U(SCH_1):PAGE320_I76@PURE_QUANTA.CONN112_10137002101LF(CHIPS)':
 'K6': CDS_PINID='K6';
NET_NAME
'P5E_CPU0_PE4_TX_C_DN<6>'
 '@S9S_MB_2U_LIB.S9S_MB_2U(SCH_1):P5E_CPU0_PE4_TX_C_DN'<6>:
 C_SIGNAL='@s9s_mb_2u_lib.s9s_mb_2u(sch_1):p5e_cpu0_pe4_tx_c_dn(6)';
NODE_NAME     C1566 1
 '@S9S_MB_2U_LIB.S9S_MB_2U(SCH_1):PAGE166_I240@PURE_QUANTA.Q_CAP_DIFFBUS(CHIPS)':
 '1': CDS_PINID='\1\';
NODE_NAME     J108 L7
 '@S9S_MB_2U_LIB.S9S_MB_2U(SCH_1):PAGE320_I76@PURE_QUANTA.CONN112_10137002101LF(CHIPS)':
 'L7': CDS_PINID='L7';
NET_NAME
'P5E_CPU0_PE4_TX_C_DN<7>'
 '@S9S_MB_2U_LIB.S9S_MB_2U(SCH_1):P5E_CPU0_PE4_TX_C_DN'<7>:
 C_SIGNAL='@s9s_mb_2u_lib.s9s_mb_2u(sch_1):p5e_cpu0_pe4_tx_c_dn(7)';
NODE_NAME     C1564 1
 '@S9S_MB_2U_LIB.S9S_MB_2U(SCH_1):PAGE166_I242@PURE_QUANTA.Q_CAP_DIFFBUS(CHIPS)':
 '1': CDS_PINID='\1\';
NODE_NAME     J108 K8
 '@S9S_MB_2U_LIB.S9S_MB_2U(SCH_1):PAGE320_I76@PURE_QUANTA.CONN112_10137002101LF(CHIPS)':
 'K8': CDS_PINID='K8';
NET_NAME
'P5E_CPU0_PE4_TX_C_DN<8>'
 '@S9S_MB_2U_LIB.S9S_MB_2U(SCH_1):P5E_CPU0_PE4_TX_C_DN'<8>:
 C_SIGNAL='@s9s_mb_2u_lib.s9s_mb_2u(sch_1):p5e_cpu0_pe4_tx_c_dn(8)';
NODE_NAME     C1794 1
 '@S9S_MB_2U_LIB.S9S_MB_2U(SCH_1):PAGE166_I260@PURE_QUANTA.Q_CAP_DIFFBUS(CHIPS)':
 '1': CDS_PINID='\1\';
NODE_NAME     J107 L1
 '@S9S_MB_2U_LIB.S9S_MB_2U(SCH_1):PAGE317_I58@PURE_QUANTA.CONN112_10137002101LF(CHIPS)':
 'L1': CDS_PINID='L1';
NET_NAME
'P5E_CPU0_PE4_TX_C_DN<9>'
 '@S9S_MB_2U_LIB.S9S_MB_2U(SCH_1):P5E_CPU0_PE4_TX_C_DN'<9>:
 C_SIGNAL='@s9s_mb_2u_lib.s9s_mb_2u(sch_1):p5e_cpu0_pe4_tx_c_dn(9)';
NODE_NAME     C1560 1
 '@S9S_MB_2U_LIB.S9S_MB_2U(SCH_1):PAGE166_I262@PURE_QUANTA.Q_CAP_DIFFBUS(CHIPS)':
 '1': CDS_PINID='\1\';
NODE_NAME     J107 K2
 '@S9S_MB_2U_LIB.S9S_MB_2U(SCH_1):PAGE317_I58@PURE_QUANTA.CONN112_10137002101LF(CHIPS)':
 'K2': CDS_PINID='K2';
NET_NAME
'P5E_CPU0_PE4_TX_C_DP<0>'
 '@S9S_MB_2U_LIB.S9S_MB_2U(SCH_1):P5E_CPU0_PE4_TX_C_DP'<0>:
 C_SIGNAL='@s9s_mb_2u_lib.s9s_mb_2u(sch_1):p5e_cpu0_pe4_tx_c_dp(0)';
NODE_NAME     C1579 1
 '@S9S_MB_2U_LIB.S9S_MB_2U(SCH_1):PAGE166_I229@PURE_QUANTA.Q_CAP_DIFFBUS(CHIPS)':
 '1': CDS_PINID='\1\';
NODE_NAME     J108 M1
 '@S9S_MB_2U_LIB.S9S_MB_2U(SCH_1):PAGE320_I57@PURE_QUANTA.CONN112_10137002101LF(CHIPS)':
 'M1': CDS_PINID='M1';
NET_NAME
'P5E_CPU0_PE4_TX_C_DP<10>'
 '@S9S_MB_2U_LIB.S9S_MB_2U(SCH_1):P5E_CPU0_PE4_TX_C_DP'<10>:
 C_SIGNAL='@s9s_mb_2u_lib.s9s_mb_2u(sch_1):p5e_cpu0_pe4_tx_c_dp(10)';
NODE_NAME     C1559 1
 '@S9S_MB_2U_LIB.S9S_MB_2U(SCH_1):PAGE166_I263@PURE_QUANTA.Q_CAP_DIFFBUS(CHIPS)':
 '1': CDS_PINID='\1\';
NODE_NAME     J107 M3
 '@S9S_MB_2U_LIB.S9S_MB_2U(SCH_1):PAGE317_I58@PURE_QUANTA.CONN112_10137002101LF(CHIPS)':
 'M3': CDS_PINID='M3';
NET_NAME
'P5E_CPU0_PE4_TX_C_DP<11>'
 '@S9S_MB_2U_LIB.S9S_MB_2U(SCH_1):P5E_CPU0_PE4_TX_C_DP'<11>:
 C_SIGNAL='@s9s_mb_2u_lib.s9s_mb_2u(sch_1):p5e_cpu0_pe4_tx_c_dp(11)';
NODE_NAME     C1557 1
 '@S9S_MB_2U_LIB.S9S_MB_2U(SCH_1):PAGE166_I266@PURE_QUANTA.Q_CAP_DIFFBUS(CHIPS)':
 '1': CDS_PINID='\1\';
NODE_NAME     J107 K4
 '@S9S_MB_2U_LIB.S9S_MB_2U(SCH_1):PAGE317_I58@PURE_QUANTA.CONN112_10137002101LF(CHIPS)':
 'K4': CDS_PINID='K4';
NET_NAME
'P5E_CPU0_PE4_TX_C_DP<12>'
 '@S9S_MB_2U_LIB.S9S_MB_2U(SCH_1):P5E_CPU0_PE4_TX_C_DP'<12>:
 C_SIGNAL='@s9s_mb_2u_lib.s9s_mb_2u(sch_1):p5e_cpu0_pe4_tx_c_dp(12)';
NODE_NAME     C1555 1
 '@S9S_MB_2U_LIB.S9S_MB_2U(SCH_1):PAGE166_I267@PURE_QUANTA.Q_CAP_DIFFBUS(CHIPS)':
 '1': CDS_PINID='\1\';
NODE_NAME     J107 M5
 '@S9S_MB_2U_LIB.S9S_MB_2U(SCH_1):PAGE317_I38@PURE_QUANTA.CONN112_10137002101LF(CHIPS)':
 'M5': CDS_PINID='M5';
NET_NAME
'P5E_CPU0_PE4_TX_C_DP<13>'
 '@S9S_MB_2U_LIB.S9S_MB_2U(SCH_1):P5E_CPU0_PE4_TX_C_DP'<13>:
 C_SIGNAL='@s9s_mb_2u_lib.s9s_mb_2u(sch_1):p5e_cpu0_pe4_tx_c_dp(13)';
NODE_NAME     C1553 1
 '@S9S_MB_2U_LIB.S9S_MB_2U(SCH_1):PAGE166_I269@PURE_QUANTA.Q_CAP_DIFFBUS(CHIPS)':
 '1': CDS_PINID='\1\';
NODE_NAME     J107 L6
 '@S9S_MB_2U_LIB.S9S_MB_2U(SCH_1):PAGE317_I38@PURE_QUANTA.CONN112_10137002101LF(CHIPS)':
 'L6': CDS_PINID='L6';
NET_NAME
'P5E_CPU0_PE4_TX_C_DP<14>'
 '@S9S_MB_2U_LIB.S9S_MB_2U(SCH_1):P5E_CPU0_PE4_TX_C_DP'<14>:
 C_SIGNAL='@s9s_mb_2u_lib.s9s_mb_2u(sch_1):p5e_cpu0_pe4_tx_c_dp(14)';
NODE_NAME     C1792 1
 '@S9S_MB_2U_LIB.S9S_MB_2U(SCH_1):PAGE166_I271@PURE_QUANTA.Q_CAP_DIFFBUS(CHIPS)':
 '1': CDS_PINID='\1\';
NODE_NAME     J107 M7
 '@S9S_MB_2U_LIB.S9S_MB_2U(SCH_1):PAGE317_I38@PURE_QUANTA.CONN112_10137002101LF(CHIPS)':
 'M7': CDS_PINID='M7';
NET_NAME
'P5E_CPU0_PE4_TX_C_DP<15>'
 '@S9S_MB_2U_LIB.S9S_MB_2U(SCH_1):P5E_CPU0_PE4_TX_C_DP'<15>:
 C_SIGNAL='@s9s_mb_2u_lib.s9s_mb_2u(sch_1):p5e_cpu0_pe4_tx_c_dp(15)';
NODE_NAME     C1549 1
 '@S9S_MB_2U_LIB.S9S_MB_2U(SCH_1):PAGE166_I274@PURE_QUANTA.Q_CAP_DIFFBUS(CHIPS)':
 '1': CDS_PINID='\1\';
NODE_NAME     J107 L8
 '@S9S_MB_2U_LIB.S9S_MB_2U(SCH_1):PAGE317_I38@PURE_QUANTA.CONN112_10137002101LF(CHIPS)':
 'L8': CDS_PINID='L8';
NET_NAME
'P5E_CPU0_PE4_TX_C_DP<1>'
 '@S9S_MB_2U_LIB.S9S_MB_2U(SCH_1):P5E_CPU0_PE4_TX_C_DP'<1>:
 C_SIGNAL='@s9s_mb_2u_lib.s9s_mb_2u(sch_1):p5e_cpu0_pe4_tx_c_dp(1)';
NODE_NAME     C1577 1
 '@S9S_MB_2U_LIB.S9S_MB_2U(SCH_1):PAGE166_I311@PURE_QUANTA.Q_CAP_DIFFBUS(CHIPS)':
 '1': CDS_PINID='\1\';
NODE_NAME     J108 K2
 '@S9S_MB_2U_LIB.S9S_MB_2U(SCH_1):PAGE320_I57@PURE_QUANTA.CONN112_10137002101LF(CHIPS)':
 'K2': CDS_PINID='K2';
NET_NAME
'P5E_CPU0_PE4_TX_C_DP<2>'
 '@S9S_MB_2U_LIB.S9S_MB_2U(SCH_1):P5E_CPU0_PE4_TX_C_DP'<2>:
 C_SIGNAL='@s9s_mb_2u_lib.s9s_mb_2u(sch_1):p5e_cpu0_pe4_tx_c_dp(2)';
NODE_NAME     C1575 1
 '@S9S_MB_2U_LIB.S9S_MB_2U(SCH_1):PAGE166_I231@PURE_QUANTA.Q_CAP_DIFFBUS(CHIPS)':
 '1': CDS_PINID='\1\';
NODE_NAME     J108 M3
 '@S9S_MB_2U_LIB.S9S_MB_2U(SCH_1):PAGE320_I57@PURE_QUANTA.CONN112_10137002101LF(CHIPS)':
 'M3': CDS_PINID='M3';
NET_NAME
'P5E_CPU0_PE4_TX_C_DP<3>'
 '@S9S_MB_2U_LIB.S9S_MB_2U(SCH_1):P5E_CPU0_PE4_TX_C_DP'<3>:
 C_SIGNAL='@s9s_mb_2u_lib.s9s_mb_2u(sch_1):p5e_cpu0_pe4_tx_c_dp(3)';
NODE_NAME     C1573 1
 '@S9S_MB_2U_LIB.S9S_MB_2U(SCH_1):PAGE166_I233@PURE_QUANTA.Q_CAP_DIFFBUS(CHIPS)':
 '1': CDS_PINID='\1\';
NODE_NAME     J108 L4
 '@S9S_MB_2U_LIB.S9S_MB_2U(SCH_1):PAGE320_I57@PURE_QUANTA.CONN112_10137002101LF(CHIPS)':
 'L4': CDS_PINID='L4';
NET_NAME
'P5E_CPU0_PE4_TX_C_DP<4>'
 '@S9S_MB_2U_LIB.S9S_MB_2U(SCH_1):P5E_CPU0_PE4_TX_C_DP'<4>:
 C_SIGNAL='@s9s_mb_2u_lib.s9s_mb_2u(sch_1):p5e_cpu0_pe4_tx_c_dp(4)';
NODE_NAME     C1571 1
 '@S9S_MB_2U_LIB.S9S_MB_2U(SCH_1):PAGE166_I236@PURE_QUANTA.Q_CAP_DIFFBUS(CHIPS)':
 '1': CDS_PINID='\1\';
NODE_NAME     J108 M5
 '@S9S_MB_2U_LIB.S9S_MB_2U(SCH_1):PAGE320_I76@PURE_QUANTA.CONN112_10137002101LF(CHIPS)':
 'M5': CDS_PINID='M5';
NET_NAME
'P5E_CPU0_PE4_TX_C_DP<5>'
 '@S9S_MB_2U_LIB.S9S_MB_2U(SCH_1):P5E_CPU0_PE4_TX_C_DP'<5>:
 C_SIGNAL='@s9s_mb_2u_lib.s9s_mb_2u(sch_1):p5e_cpu0_pe4_tx_c_dp(5)';
NODE_NAME     C1569 1
 '@S9S_MB_2U_LIB.S9S_MB_2U(SCH_1):PAGE166_I237@PURE_QUANTA.Q_CAP_DIFFBUS(CHIPS)':
 '1': CDS_PINID='\1\';
NODE_NAME     J108 L6
 '@S9S_MB_2U_LIB.S9S_MB_2U(SCH_1):PAGE320_I76@PURE_QUANTA.CONN112_10137002101LF(CHIPS)':
 'L6': CDS_PINID='L6';
NET_NAME
'P5E_CPU0_PE4_TX_C_DP<6>'
 '@S9S_MB_2U_LIB.S9S_MB_2U(SCH_1):P5E_CPU0_PE4_TX_C_DP'<6>:
 C_SIGNAL='@s9s_mb_2u_lib.s9s_mb_2u(sch_1):p5e_cpu0_pe4_tx_c_dp(6)';
NODE_NAME     C1567 1
 '@S9S_MB_2U_LIB.S9S_MB_2U(SCH_1):PAGE166_I239@PURE_QUANTA.Q_CAP_DIFFBUS(CHIPS)':
 '1': CDS_PINID='\1\';
NODE_NAME     J108 M7
 '@S9S_MB_2U_LIB.S9S_MB_2U(SCH_1):PAGE320_I76@PURE_QUANTA.CONN112_10137002101LF(CHIPS)':
 'M7': CDS_PINID='M7';
NET_NAME
'P5E_CPU0_PE4_TX_C_DP<7>'
 '@S9S_MB_2U_LIB.S9S_MB_2U(SCH_1):P5E_CPU0_PE4_TX_C_DP'<7>:
 C_SIGNAL='@s9s_mb_2u_lib.s9s_mb_2u(sch_1):p5e_cpu0_pe4_tx_c_dp(7)';
NODE_NAME     C1565 1
 '@S9S_MB_2U_LIB.S9S_MB_2U(SCH_1):PAGE166_I241@PURE_QUANTA.Q_CAP_DIFFBUS(CHIPS)':
 '1': CDS_PINID='\1\';
NODE_NAME     J108 L8
 '@S9S_MB_2U_LIB.S9S_MB_2U(SCH_1):PAGE320_I76@PURE_QUANTA.CONN112_10137002101LF(CHIPS)':
 'L8': CDS_PINID='L8';
NET_NAME
'P5E_CPU0_PE4_TX_C_DP<8>'
 '@S9S_MB_2U_LIB.S9S_MB_2U(SCH_1):P5E_CPU0_PE4_TX_C_DP'<8>:
 C_SIGNAL='@s9s_mb_2u_lib.s9s_mb_2u(sch_1):p5e_cpu0_pe4_tx_c_dp(8)';
NODE_NAME     C1563 1
 '@S9S_MB_2U_LIB.S9S_MB_2U(SCH_1):PAGE166_I259@PURE_QUANTA.Q_CAP_DIFFBUS(CHIPS)':
 '1': CDS_PINID='\1\';
NODE_NAME     J107 M1
 '@S9S_MB_2U_LIB.S9S_MB_2U(SCH_1):PAGE317_I58@PURE_QUANTA.CONN112_10137002101LF(CHIPS)':
 'M1': CDS_PINID='M1';
NET_NAME
'P5E_CPU0_PE4_TX_C_DP<9>'
 '@S9S_MB_2U_LIB.S9S_MB_2U(SCH_1):P5E_CPU0_PE4_TX_C_DP'<9>:
 C_SIGNAL='@s9s_mb_2u_lib.s9s_mb_2u(sch_1):p5e_cpu0_pe4_tx_c_dp(9)';
NODE_NAME     C1793 1
 '@S9S_MB_2U_LIB.S9S_MB_2U(SCH_1):PAGE166_I261@PURE_QUANTA.Q_CAP_DIFFBUS(CHIPS)':
 '1': CDS_PINID='\1\';
NODE_NAME     J107 L2
 '@S9S_MB_2U_LIB.S9S_MB_2U(SCH_1):PAGE317_I58@PURE_QUANTA.CONN112_10137002101LF(CHIPS)':
 'L2': CDS_PINID='L2';
NET_NAME
'P5E_CPU0_PE4_TX_DN<0>'
 '@S9S_MB_2U_LIB.S9S_MB_2U(SCH_1):P5E_CPU0_PE4_TX_DN'<0>:
 C_SIGNAL='@s9s_mb_2u_lib.s9s_mb_2u(sch_1):p5e_cpu0_pe4_tx_dn(0)';
NODE_NAME     U2 L86
 '@S9S_MB_2U_LIB.S9S_MB_2U(SCH_1):PAGE31_I139@PURE_QUANTA.SOCKET4677_AZIF0045P001C01CS(CHIPS)':
 'PE4_TX_DN0': CDS_PINID='PE4_TX_DN0';
NODE_NAME     C1578 2
 '@S9S_MB_2U_LIB.S9S_MB_2U(SCH_1):PAGE166_I230@PURE_QUANTA.Q_CAP_DIFFBUS(CHIPS)':
 '2': CDS_PINID='\2\';
NET_NAME
'P5E_CPU0_PE4_TX_DN<10>'
 '@S9S_MB_2U_LIB.S9S_MB_2U(SCH_1):P5E_CPU0_PE4_TX_DN'<10>:
 C_SIGNAL='@s9s_mb_2u_lib.s9s_mb_2u(sch_1):p5e_cpu0_pe4_tx_dn(10)';
NODE_NAME     U2 AL86
 '@S9S_MB_2U_LIB.S9S_MB_2U(SCH_1):PAGE31_I139@PURE_QUANTA.SOCKET4677_AZIF0045P001C01CS(CHIPS)':
 'PE4_TX_DN10': CDS_PINID='PE4_TX_DN10';
NODE_NAME     C1558 2
 '@S9S_MB_2U_LIB.S9S_MB_2U(SCH_1):PAGE166_I264@PURE_QUANTA.Q_CAP_DIFFBUS(CHIPS)':
 '2': CDS_PINID='\2\';
NET_NAME
'P5E_CPU0_PE4_TX_DN<11>'
 '@S9S_MB_2U_LIB.S9S_MB_2U(SCH_1):P5E_CPU0_PE4_TX_DN'<11>:
 C_SIGNAL='@s9s_mb_2u_lib.s9s_mb_2u(sch_1):p5e_cpu0_pe4_tx_dn(11)';
NODE_NAME     U2 AP85
 '@S9S_MB_2U_LIB.S9S_MB_2U(SCH_1):PAGE31_I139@PURE_QUANTA.SOCKET4677_AZIF0045P001C01CS(CHIPS)':
 'PE4_TX_DN11': CDS_PINID='PE4_TX_DN11';
NODE_NAME     C1556 2
 '@S9S_MB_2U_LIB.S9S_MB_2U(SCH_1):PAGE166_I265@PURE_QUANTA.Q_CAP_DIFFBUS(CHIPS)':
 '2': CDS_PINID='\2\';
NET_NAME
'P5E_CPU0_PE4_TX_DN<12>'
 '@S9S_MB_2U_LIB.S9S_MB_2U(SCH_1):P5E_CPU0_PE4_TX_DN'<12>:
 C_SIGNAL='@s9s_mb_2u_lib.s9s_mb_2u(sch_1):p5e_cpu0_pe4_tx_dn(12)';
NODE_NAME     U2 AR86
 '@S9S_MB_2U_LIB.S9S_MB_2U(SCH_1):PAGE31_I139@PURE_QUANTA.SOCKET4677_AZIF0045P001C01CS(CHIPS)':
 'PE4_TX_DN12': CDS_PINID='PE4_TX_DN12';
NODE_NAME     C1554 2
 '@S9S_MB_2U_LIB.S9S_MB_2U(SCH_1):PAGE166_I268@PURE_QUANTA.Q_CAP_DIFFBUS(CHIPS)':
 '2': CDS_PINID='\2\';
NET_NAME
'P5E_CPU0_PE4_TX_DN<13>'
 '@S9S_MB_2U_LIB.S9S_MB_2U(SCH_1):P5E_CPU0_PE4_TX_DN'<13>:
 C_SIGNAL='@s9s_mb_2u_lib.s9s_mb_2u(sch_1):p5e_cpu0_pe4_tx_dn(13)';
NODE_NAME     U2 AU86
 '@S9S_MB_2U_LIB.S9S_MB_2U(SCH_1):PAGE31_I139@PURE_QUANTA.SOCKET4677_AZIF0045P001C01CS(CHIPS)':
 'PE4_TX_DN13': CDS_PINID='PE4_TX_DN13';
NODE_NAME     C1552 2
 '@S9S_MB_2U_LIB.S9S_MB_2U(SCH_1):PAGE166_I270@PURE_QUANTA.Q_CAP_DIFFBUS(CHIPS)':
 '2': CDS_PINID='\2\';
NET_NAME
'P5E_CPU0_PE4_TX_DN<14>'
 '@S9S_MB_2U_LIB.S9S_MB_2U(SCH_1):P5E_CPU0_PE4_TX_DN'<14>:
 C_SIGNAL='@s9s_mb_2u_lib.s9s_mb_2u(sch_1):p5e_cpu0_pe4_tx_dn(14)';
NODE_NAME     U2 AW86
 '@S9S_MB_2U_LIB.S9S_MB_2U(SCH_1):PAGE31_I139@PURE_QUANTA.SOCKET4677_AZIF0045P001C01CS(CHIPS)':
 'PE4_TX_DN14': CDS_PINID='PE4_TX_DN14';
NODE_NAME     C1550 2
 '@S9S_MB_2U_LIB.S9S_MB_2U(SCH_1):PAGE166_I272@PURE_QUANTA.Q_CAP_DIFFBUS(CHIPS)':
 '2': CDS_PINID='\2\';
NET_NAME
'P5E_CPU0_PE4_TX_DN<15>'
 '@S9S_MB_2U_LIB.S9S_MB_2U(SCH_1):P5E_CPU0_PE4_TX_DN'<15>:
 C_SIGNAL='@s9s_mb_2u_lib.s9s_mb_2u(sch_1):p5e_cpu0_pe4_tx_dn(15)';
NODE_NAME     U2 BA86
 '@S9S_MB_2U_LIB.S9S_MB_2U(SCH_1):PAGE31_I139@PURE_QUANTA.SOCKET4677_AZIF0045P001C01CS(CHIPS)':
 'PE4_TX_DN15': CDS_PINID='PE4_TX_DN15';
NODE_NAME     C1548 2
 '@S9S_MB_2U_LIB.S9S_MB_2U(SCH_1):PAGE166_I273@PURE_QUANTA.Q_CAP_DIFFBUS(CHIPS)':
 '2': CDS_PINID='\2\';
NET_NAME
'P5E_CPU0_PE4_TX_DN<1>'
 '@S9S_MB_2U_LIB.S9S_MB_2U(SCH_1):P5E_CPU0_PE4_TX_DN'<1>:
 C_SIGNAL='@s9s_mb_2u_lib.s9s_mb_2u(sch_1):p5e_cpu0_pe4_tx_dn(1)';
NODE_NAME     U2 P85
 '@S9S_MB_2U_LIB.S9S_MB_2U(SCH_1):PAGE31_I139@PURE_QUANTA.SOCKET4677_AZIF0045P001C01CS(CHIPS)':
 'PE4_TX_DN1': CDS_PINID='PE4_TX_DN1';
NODE_NAME     C1576 2
 '@S9S_MB_2U_LIB.S9S_MB_2U(SCH_1):PAGE166_I312@PURE_QUANTA.Q_CAP_DIFFBUS(CHIPS)':
 '2': CDS_PINID='\2\';
NET_NAME
'P5E_CPU0_PE4_TX_DN<2>'
 '@S9S_MB_2U_LIB.S9S_MB_2U(SCH_1):P5E_CPU0_PE4_TX_DN'<2>:
 C_SIGNAL='@s9s_mb_2u_lib.s9s_mb_2u(sch_1):p5e_cpu0_pe4_tx_dn(2)';
NODE_NAME     U2 R86
 '@S9S_MB_2U_LIB.S9S_MB_2U(SCH_1):PAGE31_I139@PURE_QUANTA.SOCKET4677_AZIF0045P001C01CS(CHIPS)':
 'PE4_TX_DN2': CDS_PINID='PE4_TX_DN2';
NODE_NAME     C1574 2
 '@S9S_MB_2U_LIB.S9S_MB_2U(SCH_1):PAGE166_I232@PURE_QUANTA.Q_CAP_DIFFBUS(CHIPS)':
 '2': CDS_PINID='\2\';
NET_NAME
'P5E_CPU0_PE4_TX_DN<3>'
 '@S9S_MB_2U_LIB.S9S_MB_2U(SCH_1):P5E_CPU0_PE4_TX_DN'<3>:
 C_SIGNAL='@s9s_mb_2u_lib.s9s_mb_2u(sch_1):p5e_cpu0_pe4_tx_dn(3)';
NODE_NAME     U2 U86
 '@S9S_MB_2U_LIB.S9S_MB_2U(SCH_1):PAGE31_I139@PURE_QUANTA.SOCKET4677_AZIF0045P001C01CS(CHIPS)':
 'PE4_TX_DN3': CDS_PINID='PE4_TX_DN3';
NODE_NAME     C1572 2
 '@S9S_MB_2U_LIB.S9S_MB_2U(SCH_1):PAGE166_I234@PURE_QUANTA.Q_CAP_DIFFBUS(CHIPS)':
 '2': CDS_PINID='\2\';
NET_NAME
'P5E_CPU0_PE4_TX_DN<4>'
 '@S9S_MB_2U_LIB.S9S_MB_2U(SCH_1):P5E_CPU0_PE4_TX_DN'<4>:
 C_SIGNAL='@s9s_mb_2u_lib.s9s_mb_2u(sch_1):p5e_cpu0_pe4_tx_dn(4)';
NODE_NAME     U2 W86
 '@S9S_MB_2U_LIB.S9S_MB_2U(SCH_1):PAGE31_I139@PURE_QUANTA.SOCKET4677_AZIF0045P001C01CS(CHIPS)':
 'PE4_TX_DN4': CDS_PINID='PE4_TX_DN4';
NODE_NAME     C1570 2
 '@S9S_MB_2U_LIB.S9S_MB_2U(SCH_1):PAGE166_I235@PURE_QUANTA.Q_CAP_DIFFBUS(CHIPS)':
 '2': CDS_PINID='\2\';
NET_NAME
'P5E_CPU0_PE4_TX_DN<5>'
 '@S9S_MB_2U_LIB.S9S_MB_2U(SCH_1):P5E_CPU0_PE4_TX_DN'<5>:
 C_SIGNAL='@s9s_mb_2u_lib.s9s_mb_2u(sch_1):p5e_cpu0_pe4_tx_dn(5)';
NODE_NAME     U2 AA86
 '@S9S_MB_2U_LIB.S9S_MB_2U(SCH_1):PAGE31_I139@PURE_QUANTA.SOCKET4677_AZIF0045P001C01CS(CHIPS)':
 'PE4_TX_DN5': CDS_PINID='PE4_TX_DN5';
NODE_NAME     C1568 2
 '@S9S_MB_2U_LIB.S9S_MB_2U(SCH_1):PAGE166_I238@PURE_QUANTA.Q_CAP_DIFFBUS(CHIPS)':
 '2': CDS_PINID='\2\';
NET_NAME
'P5E_CPU0_PE4_TX_DN<6>'
 '@S9S_MB_2U_LIB.S9S_MB_2U(SCH_1):P5E_CPU0_PE4_TX_DN'<6>:
 C_SIGNAL='@s9s_mb_2u_lib.s9s_mb_2u(sch_1):p5e_cpu0_pe4_tx_dn(6)';
NODE_NAME     U2 AC86
 '@S9S_MB_2U_LIB.S9S_MB_2U(SCH_1):PAGE31_I139@PURE_QUANTA.SOCKET4677_AZIF0045P001C01CS(CHIPS)':
 'PE4_TX_DN6': CDS_PINID='PE4_TX_DN6';
NODE_NAME     C1566 2
 '@S9S_MB_2U_LIB.S9S_MB_2U(SCH_1):PAGE166_I240@PURE_QUANTA.Q_CAP_DIFFBUS(CHIPS)':
 '2': CDS_PINID='\2\';
NET_NAME
'P5E_CPU0_PE4_TX_DN<7>'
 '@S9S_MB_2U_LIB.S9S_MB_2U(SCH_1):P5E_CPU0_PE4_TX_DN'<7>:
 C_SIGNAL='@s9s_mb_2u_lib.s9s_mb_2u(sch_1):p5e_cpu0_pe4_tx_dn(7)';
NODE_NAME     U2 AE86
 '@S9S_MB_2U_LIB.S9S_MB_2U(SCH_1):PAGE31_I139@PURE_QUANTA.SOCKET4677_AZIF0045P001C01CS(CHIPS)':
 'PE4_TX_DN7': CDS_PINID='PE4_TX_DN7';
NODE_NAME     C1564 2
 '@S9S_MB_2U_LIB.S9S_MB_2U(SCH_1):PAGE166_I242@PURE_QUANTA.Q_CAP_DIFFBUS(CHIPS)':
 '2': CDS_PINID='\2\';
NET_NAME
'P5E_CPU0_PE4_TX_DN<8>'
 '@S9S_MB_2U_LIB.S9S_MB_2U(SCH_1):P5E_CPU0_PE4_TX_DN'<8>:
 C_SIGNAL='@s9s_mb_2u_lib.s9s_mb_2u(sch_1):p5e_cpu0_pe4_tx_dn(8)';
NODE_NAME     U2 AG86
 '@S9S_MB_2U_LIB.S9S_MB_2U(SCH_1):PAGE31_I139@PURE_QUANTA.SOCKET4677_AZIF0045P001C01CS(CHIPS)':
 'PE4_TX_DN8': CDS_PINID='PE4_TX_DN8';
NODE_NAME     C1794 2
 '@S9S_MB_2U_LIB.S9S_MB_2U(SCH_1):PAGE166_I260@PURE_QUANTA.Q_CAP_DIFFBUS(CHIPS)':
 '2': CDS_PINID='\2\';
NET_NAME
'P5E_CPU0_PE4_TX_DN<9>'
 '@S9S_MB_2U_LIB.S9S_MB_2U(SCH_1):P5E_CPU0_PE4_TX_DN'<9>:
 C_SIGNAL='@s9s_mb_2u_lib.s9s_mb_2u(sch_1):p5e_cpu0_pe4_tx_dn(9)';
NODE_NAME     U2 AJ86
 '@S9S_MB_2U_LIB.S9S_MB_2U(SCH_1):PAGE31_I139@PURE_QUANTA.SOCKET4677_AZIF0045P001C01CS(CHIPS)':
 'PE4_TX_DN9': CDS_PINID='PE4_TX_DN9';
NODE_NAME     C1560 2
 '@S9S_MB_2U_LIB.S9S_MB_2U(SCH_1):PAGE166_I262@PURE_QUANTA.Q_CAP_DIFFBUS(CHIPS)':
 '2': CDS_PINID='\2\';
NET_NAME
'P5E_CPU0_PE4_TX_DP<0>'
 '@S9S_MB_2U_LIB.S9S_MB_2U(SCH_1):P5E_CPU0_PE4_TX_DP'<0>:
 C_SIGNAL='@s9s_mb_2u_lib.s9s_mb_2u(sch_1):p5e_cpu0_pe4_tx_dp(0)';
NODE_NAME     U2 M87
 '@S9S_MB_2U_LIB.S9S_MB_2U(SCH_1):PAGE31_I139@PURE_QUANTA.SOCKET4677_AZIF0045P001C01CS(CHIPS)':
 'PE4_TX_DP0': CDS_PINID='PE4_TX_DP0';
NODE_NAME     C1579 2
 '@S9S_MB_2U_LIB.S9S_MB_2U(SCH_1):PAGE166_I229@PURE_QUANTA.Q_CAP_DIFFBUS(CHIPS)':
 '2': CDS_PINID='\2\';
NET_NAME
'P5E_CPU0_PE4_TX_DP<10>'
 '@S9S_MB_2U_LIB.S9S_MB_2U(SCH_1):P5E_CPU0_PE4_TX_DP'<10>:
 C_SIGNAL='@s9s_mb_2u_lib.s9s_mb_2u(sch_1):p5e_cpu0_pe4_tx_dp(10)';
NODE_NAME     U2 AM87
 '@S9S_MB_2U_LIB.S9S_MB_2U(SCH_1):PAGE31_I139@PURE_QUANTA.SOCKET4677_AZIF0045P001C01CS(CHIPS)':
 'PE4_TX_DP10': CDS_PINID='PE4_TX_DP10';
NODE_NAME     C1559 2
 '@S9S_MB_2U_LIB.S9S_MB_2U(SCH_1):PAGE166_I263@PURE_QUANTA.Q_CAP_DIFFBUS(CHIPS)':
 '2': CDS_PINID='\2\';
NET_NAME
'P5E_CPU0_PE4_TX_DP<11>'
 '@S9S_MB_2U_LIB.S9S_MB_2U(SCH_1):P5E_CPU0_PE4_TX_DP'<11>:
 C_SIGNAL='@s9s_mb_2u_lib.s9s_mb_2u(sch_1):p5e_cpu0_pe4_tx_dp(11)';
NODE_NAME     U2 AN86
 '@S9S_MB_2U_LIB.S9S_MB_2U(SCH_1):PAGE31_I139@PURE_QUANTA.SOCKET4677_AZIF0045P001C01CS(CHIPS)':
 'PE4_TX_DP11': CDS_PINID='PE4_TX_DP11';
NODE_NAME     C1557 2
 '@S9S_MB_2U_LIB.S9S_MB_2U(SCH_1):PAGE166_I266@PURE_QUANTA.Q_CAP_DIFFBUS(CHIPS)':
 '2': CDS_PINID='\2\';
NET_NAME
'P5E_CPU0_PE4_TX_DP<12>'
 '@S9S_MB_2U_LIB.S9S_MB_2U(SCH_1):P5E_CPU0_PE4_TX_DP'<12>:
 C_SIGNAL='@s9s_mb_2u_lib.s9s_mb_2u(sch_1):p5e_cpu0_pe4_tx_dp(12)';
NODE_NAME     U2 AT87
 '@S9S_MB_2U_LIB.S9S_MB_2U(SCH_1):PAGE31_I139@PURE_QUANTA.SOCKET4677_AZIF0045P001C01CS(CHIPS)':
 'PE4_TX_DP12': CDS_PINID='PE4_TX_DP12';
NODE_NAME     C1555 2
 '@S9S_MB_2U_LIB.S9S_MB_2U(SCH_1):PAGE166_I267@PURE_QUANTA.Q_CAP_DIFFBUS(CHIPS)':
 '2': CDS_PINID='\2\';
NET_NAME
'P5E_CPU0_PE4_TX_DP<13>'
 '@S9S_MB_2U_LIB.S9S_MB_2U(SCH_1):P5E_CPU0_PE4_TX_DP'<13>:
 C_SIGNAL='@s9s_mb_2u_lib.s9s_mb_2u(sch_1):p5e_cpu0_pe4_tx_dp(13)';
NODE_NAME     U2 AV85
 '@S9S_MB_2U_LIB.S9S_MB_2U(SCH_1):PAGE31_I139@PURE_QUANTA.SOCKET4677_AZIF0045P001C01CS(CHIPS)':
 'PE4_TX_DP13': CDS_PINID='PE4_TX_DP13';
NODE_NAME     C1553 2
 '@S9S_MB_2U_LIB.S9S_MB_2U(SCH_1):PAGE166_I269@PURE_QUANTA.Q_CAP_DIFFBUS(CHIPS)':
 '2': CDS_PINID='\2\';
NET_NAME
'P5E_CPU0_PE4_TX_DP<14>'
 '@S9S_MB_2U_LIB.S9S_MB_2U(SCH_1):P5E_CPU0_PE4_TX_DP'<14>:
 C_SIGNAL='@s9s_mb_2u_lib.s9s_mb_2u(sch_1):p5e_cpu0_pe4_tx_dp(14)';
NODE_NAME     U2 AY87
 '@S9S_MB_2U_LIB.S9S_MB_2U(SCH_1):PAGE31_I139@PURE_QUANTA.SOCKET4677_AZIF0045P001C01CS(CHIPS)':
 'PE4_TX_DP14': CDS_PINID='PE4_TX_DP14';
NODE_NAME     C1792 2
 '@S9S_MB_2U_LIB.S9S_MB_2U(SCH_1):PAGE166_I271@PURE_QUANTA.Q_CAP_DIFFBUS(CHIPS)':
 '2': CDS_PINID='\2\';
NET_NAME
'P5E_CPU0_PE4_TX_DP<15>'
 '@S9S_MB_2U_LIB.S9S_MB_2U(SCH_1):P5E_CPU0_PE4_TX_DP'<15>:
 C_SIGNAL='@s9s_mb_2u_lib.s9s_mb_2u(sch_1):p5e_cpu0_pe4_tx_dp(15)';
NODE_NAME     U2 BB85
 '@S9S_MB_2U_LIB.S9S_MB_2U(SCH_1):PAGE31_I139@PURE_QUANTA.SOCKET4677_AZIF0045P001C01CS(CHIPS)':
 'PE4_TX_DP15': CDS_PINID='PE4_TX_DP15';
NODE_NAME     C1549 2
 '@S9S_MB_2U_LIB.S9S_MB_2U(SCH_1):PAGE166_I274@PURE_QUANTA.Q_CAP_DIFFBUS(CHIPS)':
 '2': CDS_PINID='\2\';
NET_NAME
'P5E_CPU0_PE4_TX_DP<1>'
 '@S9S_MB_2U_LIB.S9S_MB_2U(SCH_1):P5E_CPU0_PE4_TX_DP'<1>:
 C_SIGNAL='@s9s_mb_2u_lib.s9s_mb_2u(sch_1):p5e_cpu0_pe4_tx_dp(1)';
NODE_NAME     U2 N86
 '@S9S_MB_2U_LIB.S9S_MB_2U(SCH_1):PAGE31_I139@PURE_QUANTA.SOCKET4677_AZIF0045P001C01CS(CHIPS)':
 'PE4_TX_DP1': CDS_PINID='PE4_TX_DP1';
NODE_NAME     C1577 2
 '@S9S_MB_2U_LIB.S9S_MB_2U(SCH_1):PAGE166_I311@PURE_QUANTA.Q_CAP_DIFFBUS(CHIPS)':
 '2': CDS_PINID='\2\';
NET_NAME
'P5E_CPU0_PE4_TX_DP<2>'
 '@S9S_MB_2U_LIB.S9S_MB_2U(SCH_1):P5E_CPU0_PE4_TX_DP'<2>:
 C_SIGNAL='@s9s_mb_2u_lib.s9s_mb_2u(sch_1):p5e_cpu0_pe4_tx_dp(2)';
NODE_NAME     U2 T87
 '@S9S_MB_2U_LIB.S9S_MB_2U(SCH_1):PAGE31_I139@PURE_QUANTA.SOCKET4677_AZIF0045P001C01CS(CHIPS)':
 'PE4_TX_DP2': CDS_PINID='PE4_TX_DP2';
NODE_NAME     C1575 2
 '@S9S_MB_2U_LIB.S9S_MB_2U(SCH_1):PAGE166_I231@PURE_QUANTA.Q_CAP_DIFFBUS(CHIPS)':
 '2': CDS_PINID='\2\';
NET_NAME
'P5E_CPU0_PE4_TX_DP<3>'
 '@S9S_MB_2U_LIB.S9S_MB_2U(SCH_1):P5E_CPU0_PE4_TX_DP'<3>:
 C_SIGNAL='@s9s_mb_2u_lib.s9s_mb_2u(sch_1):p5e_cpu0_pe4_tx_dp(3)';
NODE_NAME     U2 V85
 '@S9S_MB_2U_LIB.S9S_MB_2U(SCH_1):PAGE31_I139@PURE_QUANTA.SOCKET4677_AZIF0045P001C01CS(CHIPS)':
 'PE4_TX_DP3': CDS_PINID='PE4_TX_DP3';
NODE_NAME     C1573 2
 '@S9S_MB_2U_LIB.S9S_MB_2U(SCH_1):PAGE166_I233@PURE_QUANTA.Q_CAP_DIFFBUS(CHIPS)':
 '2': CDS_PINID='\2\';
NET_NAME
'P5E_CPU0_PE4_TX_DP<4>'
 '@S9S_MB_2U_LIB.S9S_MB_2U(SCH_1):P5E_CPU0_PE4_TX_DP'<4>:
 C_SIGNAL='@s9s_mb_2u_lib.s9s_mb_2u(sch_1):p5e_cpu0_pe4_tx_dp(4)';
NODE_NAME     U2 Y87
 '@S9S_MB_2U_LIB.S9S_MB_2U(SCH_1):PAGE31_I139@PURE_QUANTA.SOCKET4677_AZIF0045P001C01CS(CHIPS)':
 'PE4_TX_DP4': CDS_PINID='PE4_TX_DP4';
NODE_NAME     C1571 2
 '@S9S_MB_2U_LIB.S9S_MB_2U(SCH_1):PAGE166_I236@PURE_QUANTA.Q_CAP_DIFFBUS(CHIPS)':
 '2': CDS_PINID='\2\';
NET_NAME
'P5E_CPU0_PE4_TX_DP<5>'
 '@S9S_MB_2U_LIB.S9S_MB_2U(SCH_1):P5E_CPU0_PE4_TX_DP'<5>:
 C_SIGNAL='@s9s_mb_2u_lib.s9s_mb_2u(sch_1):p5e_cpu0_pe4_tx_dp(5)';
NODE_NAME     U2 AB85
 '@S9S_MB_2U_LIB.S9S_MB_2U(SCH_1):PAGE31_I139@PURE_QUANTA.SOCKET4677_AZIF0045P001C01CS(CHIPS)':
 'PE4_TX_DP5': CDS_PINID='PE4_TX_DP5';
NODE_NAME     C1569 2
 '@S9S_MB_2U_LIB.S9S_MB_2U(SCH_1):PAGE166_I237@PURE_QUANTA.Q_CAP_DIFFBUS(CHIPS)':
 '2': CDS_PINID='\2\';
NET_NAME
'P5E_CPU0_PE4_TX_DP<6>'
 '@S9S_MB_2U_LIB.S9S_MB_2U(SCH_1):P5E_CPU0_PE4_TX_DP'<6>:
 C_SIGNAL='@s9s_mb_2u_lib.s9s_mb_2u(sch_1):p5e_cpu0_pe4_tx_dp(6)';
NODE_NAME     U2 AD87
 '@S9S_MB_2U_LIB.S9S_MB_2U(SCH_1):PAGE31_I139@PURE_QUANTA.SOCKET4677_AZIF0045P001C01CS(CHIPS)':
 'PE4_TX_DP6': CDS_PINID='PE4_TX_DP6';
NODE_NAME     C1567 2
 '@S9S_MB_2U_LIB.S9S_MB_2U(SCH_1):PAGE166_I239@PURE_QUANTA.Q_CAP_DIFFBUS(CHIPS)':
 '2': CDS_PINID='\2\';
NET_NAME
'P5E_CPU0_PE4_TX_DP<7>'
 '@S9S_MB_2U_LIB.S9S_MB_2U(SCH_1):P5E_CPU0_PE4_TX_DP'<7>:
 C_SIGNAL='@s9s_mb_2u_lib.s9s_mb_2u(sch_1):p5e_cpu0_pe4_tx_dp(7)';
NODE_NAME     U2 AF85
 '@S9S_MB_2U_LIB.S9S_MB_2U(SCH_1):PAGE31_I139@PURE_QUANTA.SOCKET4677_AZIF0045P001C01CS(CHIPS)':
 'PE4_TX_DP7': CDS_PINID='PE4_TX_DP7';
NODE_NAME     C1565 2
 '@S9S_MB_2U_LIB.S9S_MB_2U(SCH_1):PAGE166_I241@PURE_QUANTA.Q_CAP_DIFFBUS(CHIPS)':
 '2': CDS_PINID='\2\';
NET_NAME
'P5E_CPU0_PE4_TX_DP<8>'
 '@S9S_MB_2U_LIB.S9S_MB_2U(SCH_1):P5E_CPU0_PE4_TX_DP'<8>:
 C_SIGNAL='@s9s_mb_2u_lib.s9s_mb_2u(sch_1):p5e_cpu0_pe4_tx_dp(8)';
NODE_NAME     U2 AH87
 '@S9S_MB_2U_LIB.S9S_MB_2U(SCH_1):PAGE31_I139@PURE_QUANTA.SOCKET4677_AZIF0045P001C01CS(CHIPS)':
 'PE4_TX_DP8': CDS_PINID='PE4_TX_DP8';
NODE_NAME     C1563 2
 '@S9S_MB_2U_LIB.S9S_MB_2U(SCH_1):PAGE166_I259@PURE_QUANTA.Q_CAP_DIFFBUS(CHIPS)':
 '2': CDS_PINID='\2\';
NET_NAME
'P5E_CPU0_PE4_TX_DP<9>'
 '@S9S_MB_2U_LIB.S9S_MB_2U(SCH_1):P5E_CPU0_PE4_TX_DP'<9>:
 C_SIGNAL='@s9s_mb_2u_lib.s9s_mb_2u(sch_1):p5e_cpu0_pe4_tx_dp(9)';
NODE_NAME     U2 AK85
 '@S9S_MB_2U_LIB.S9S_MB_2U(SCH_1):PAGE31_I139@PURE_QUANTA.SOCKET4677_AZIF0045P001C01CS(CHIPS)':
 'PE4_TX_DP9': CDS_PINID='PE4_TX_DP9';
NODE_NAME     C1793 2
 '@S9S_MB_2U_LIB.S9S_MB_2U(SCH_1):PAGE166_I261@PURE_QUANTA.Q_CAP_DIFFBUS(CHIPS)':
 '2': CDS_PINID='\2\';
NET_NAME
'P5E_CPU1_PE0_RX_DN<0>'
 '@S9S_MB_2U_LIB.S9S_MB_2U(SCH_1):P5E_CPU1_PE0_RX_DN'<0>:
 C_SIGNAL='@s9s_mb_2u_lib.s9s_mb_2u(sch_1):p5e_cpu1_pe0_rx_dn(0)';
NODE_NAME     U1 K10
 '@S9S_MB_2U_LIB.S9S_MB_2U(SCH_1):PAGE60_I80@PURE_QUANTA.SOCKET4677_AZIF0045P001C01CS(CHIPS)':
 'PE0_RX_DN0': CDS_PINID='PE0_RX_DN0';
NODE_NAME     J111 B8
 '@S9S_MB_2U_LIB.S9S_MB_2U(SCH_1):PAGE148_I74@PURE_QUANTA.CONN112_10137002101LF(CHIPS)':
 'B8': CDS_PINID='B8';
NET_NAME
'P5E_CPU1_PE0_RX_DN<10>'
 '@S9S_MB_2U_LIB.S9S_MB_2U(SCH_1):P5E_CPU1_PE0_RX_DN'<10>:
 C_SIGNAL='@s9s_mb_2u_lib.s9s_mb_2u(sch_1):p5e_cpu1_pe0_rx_dn(10)';
NODE_NAME     U1 AK10
 '@S9S_MB_2U_LIB.S9S_MB_2U(SCH_1):PAGE60_I80@PURE_QUANTA.SOCKET4677_AZIF0045P001C01CS(CHIPS)':
 'PE0_RX_DN10': CDS_PINID='PE0_RX_DN10';
NODE_NAME     J112 B6
 '@S9S_MB_2U_LIB.S9S_MB_2U(SCH_1):PAGE149_I75@PURE_QUANTA.CONN160_10131762101LF(CHIPS)':
 'B6': CDS_PINID='B6';
NET_NAME
'P5E_CPU1_PE0_RX_DN<11>'
 '@S9S_MB_2U_LIB.S9S_MB_2U(SCH_1):P5E_CPU1_PE0_RX_DN'<11>:
 C_SIGNAL='@s9s_mb_2u_lib.s9s_mb_2u(sch_1):p5e_cpu1_pe0_rx_dn(11)';
NODE_NAME     U1 AM10
 '@S9S_MB_2U_LIB.S9S_MB_2U(SCH_1):PAGE60_I80@PURE_QUANTA.SOCKET4677_AZIF0045P001C01CS(CHIPS)':
 'PE0_RX_DN11': CDS_PINID='PE0_RX_DN11';
NODE_NAME     J112 D5
 '@S9S_MB_2U_LIB.S9S_MB_2U(SCH_1):PAGE149_I75@PURE_QUANTA.CONN160_10131762101LF(CHIPS)':
 'D5': CDS_PINID='D5';
NET_NAME
'P5E_CPU1_PE0_RX_DN<12>'
 '@S9S_MB_2U_LIB.S9S_MB_2U(SCH_1):P5E_CPU1_PE0_RX_DN'<12>:
 C_SIGNAL='@s9s_mb_2u_lib.s9s_mb_2u(sch_1):p5e_cpu1_pe0_rx_dn(12)';
NODE_NAME     U1 AP10
 '@S9S_MB_2U_LIB.S9S_MB_2U(SCH_1):PAGE60_I80@PURE_QUANTA.SOCKET4677_AZIF0045P001C01CS(CHIPS)':
 'PE0_RX_DN12': CDS_PINID='PE0_RX_DN12';
NODE_NAME     J112 B4
 '@S9S_MB_2U_LIB.S9S_MB_2U(SCH_1):PAGE149_I76@PURE_QUANTA.CONN160_10131762101LF(CHIPS)':
 'B4': CDS_PINID='B4';
NET_NAME
'P5E_CPU1_PE0_RX_DN<13>'
 '@S9S_MB_2U_LIB.S9S_MB_2U(SCH_1):P5E_CPU1_PE0_RX_DN'<13>:
 C_SIGNAL='@s9s_mb_2u_lib.s9s_mb_2u(sch_1):p5e_cpu1_pe0_rx_dn(13)';
NODE_NAME     U1 AU9
 '@S9S_MB_2U_LIB.S9S_MB_2U(SCH_1):PAGE60_I80@PURE_QUANTA.SOCKET4677_AZIF0045P001C01CS(CHIPS)':
 'PE0_RX_DN13': CDS_PINID='PE0_RX_DN13';
NODE_NAME     J112 C3
 '@S9S_MB_2U_LIB.S9S_MB_2U(SCH_1):PAGE149_I76@PURE_QUANTA.CONN160_10131762101LF(CHIPS)':
 'C3': CDS_PINID='C3';
NET_NAME
'P5E_CPU1_PE0_RX_DN<14>'
 '@S9S_MB_2U_LIB.S9S_MB_2U(SCH_1):P5E_CPU1_PE0_RX_DN'<14>:
 C_SIGNAL='@s9s_mb_2u_lib.s9s_mb_2u(sch_1):p5e_cpu1_pe0_rx_dn(14)';
NODE_NAME     U1 AV10
 '@S9S_MB_2U_LIB.S9S_MB_2U(SCH_1):PAGE60_I80@PURE_QUANTA.SOCKET4677_AZIF0045P001C01CS(CHIPS)':
 'PE0_RX_DN14': CDS_PINID='PE0_RX_DN14';
NODE_NAME     J112 B2
 '@S9S_MB_2U_LIB.S9S_MB_2U(SCH_1):PAGE149_I76@PURE_QUANTA.CONN160_10131762101LF(CHIPS)':
 'B2': CDS_PINID='B2';
NET_NAME
'P5E_CPU1_PE0_RX_DN<15>'
 '@S9S_MB_2U_LIB.S9S_MB_2U(SCH_1):P5E_CPU1_PE0_RX_DN'<15>:
 C_SIGNAL='@s9s_mb_2u_lib.s9s_mb_2u(sch_1):p5e_cpu1_pe0_rx_dn(15)';
NODE_NAME     U1 BA9
 '@S9S_MB_2U_LIB.S9S_MB_2U(SCH_1):PAGE60_I80@PURE_QUANTA.SOCKET4677_AZIF0045P001C01CS(CHIPS)':
 'PE0_RX_DN15': CDS_PINID='PE0_RX_DN15';
NODE_NAME     J112 C1
 '@S9S_MB_2U_LIB.S9S_MB_2U(SCH_1):PAGE149_I76@PURE_QUANTA.CONN160_10131762101LF(CHIPS)':
 'C1': CDS_PINID='C1';
NET_NAME
'P5E_CPU1_PE0_RX_DN<1>'
 '@S9S_MB_2U_LIB.S9S_MB_2U(SCH_1):P5E_CPU1_PE0_RX_DN'<1>:
 C_SIGNAL='@s9s_mb_2u_lib.s9s_mb_2u(sch_1):p5e_cpu1_pe0_rx_dn(1)';
NODE_NAME     U1 M10
 '@S9S_MB_2U_LIB.S9S_MB_2U(SCH_1):PAGE60_I80@PURE_QUANTA.SOCKET4677_AZIF0045P001C01CS(CHIPS)':
 'PE0_RX_DN1': CDS_PINID='PE0_RX_DN1';
NODE_NAME     J111 D7
 '@S9S_MB_2U_LIB.S9S_MB_2U(SCH_1):PAGE148_I74@PURE_QUANTA.CONN112_10137002101LF(CHIPS)':
 'D7': CDS_PINID='D7';
NET_NAME
'P5E_CPU1_PE0_RX_DN<2>'
 '@S9S_MB_2U_LIB.S9S_MB_2U(SCH_1):P5E_CPU1_PE0_RX_DN'<2>:
 C_SIGNAL='@s9s_mb_2u_lib.s9s_mb_2u(sch_1):p5e_cpu1_pe0_rx_dn(2)';
NODE_NAME     U1 P10
 '@S9S_MB_2U_LIB.S9S_MB_2U(SCH_1):PAGE60_I80@PURE_QUANTA.SOCKET4677_AZIF0045P001C01CS(CHIPS)':
 'PE0_RX_DN2': CDS_PINID='PE0_RX_DN2';
NODE_NAME     J111 B6
 '@S9S_MB_2U_LIB.S9S_MB_2U(SCH_1):PAGE148_I74@PURE_QUANTA.CONN112_10137002101LF(CHIPS)':
 'B6': CDS_PINID='B6';
NET_NAME
'P5E_CPU1_PE0_RX_DN<3>'
 '@S9S_MB_2U_LIB.S9S_MB_2U(SCH_1):P5E_CPU1_PE0_RX_DN'<3>:
 C_SIGNAL='@s9s_mb_2u_lib.s9s_mb_2u(sch_1):p5e_cpu1_pe0_rx_dn(3)';
NODE_NAME     U1 T10
 '@S9S_MB_2U_LIB.S9S_MB_2U(SCH_1):PAGE60_I80@PURE_QUANTA.SOCKET4677_AZIF0045P001C01CS(CHIPS)':
 'PE0_RX_DN3': CDS_PINID='PE0_RX_DN3';
NODE_NAME     J111 D5
 '@S9S_MB_2U_LIB.S9S_MB_2U(SCH_1):PAGE148_I74@PURE_QUANTA.CONN112_10137002101LF(CHIPS)':
 'D5': CDS_PINID='D5';
NET_NAME
'P5E_CPU1_PE0_RX_DN<4>'
 '@S9S_MB_2U_LIB.S9S_MB_2U(SCH_1):P5E_CPU1_PE0_RX_DN'<4>:
 C_SIGNAL='@s9s_mb_2u_lib.s9s_mb_2u(sch_1):p5e_cpu1_pe0_rx_dn(4)';
NODE_NAME     U1 V10
 '@S9S_MB_2U_LIB.S9S_MB_2U(SCH_1):PAGE60_I80@PURE_QUANTA.SOCKET4677_AZIF0045P001C01CS(CHIPS)':
 'PE0_RX_DN4': CDS_PINID='PE0_RX_DN4';
NODE_NAME     J111 B4
 '@S9S_MB_2U_LIB.S9S_MB_2U(SCH_1):PAGE148_I75@PURE_QUANTA.CONN112_10137002101LF(CHIPS)':
 'B4': CDS_PINID='B4';
NET_NAME
'P5E_CPU1_PE0_RX_DN<5>'
 '@S9S_MB_2U_LIB.S9S_MB_2U(SCH_1):P5E_CPU1_PE0_RX_DN'<5>:
 C_SIGNAL='@s9s_mb_2u_lib.s9s_mb_2u(sch_1):p5e_cpu1_pe0_rx_dn(5)';
NODE_NAME     U1 AA9
 '@S9S_MB_2U_LIB.S9S_MB_2U(SCH_1):PAGE60_I80@PURE_QUANTA.SOCKET4677_AZIF0045P001C01CS(CHIPS)':
 'PE0_RX_DN5': CDS_PINID='PE0_RX_DN5';
NODE_NAME     J111 C3
 '@S9S_MB_2U_LIB.S9S_MB_2U(SCH_1):PAGE148_I75@PURE_QUANTA.CONN112_10137002101LF(CHIPS)':
 'C3': CDS_PINID='C3';
NET_NAME
'P5E_CPU1_PE0_RX_DN<6>'
 '@S9S_MB_2U_LIB.S9S_MB_2U(SCH_1):P5E_CPU1_PE0_RX_DN'<6>:
 C_SIGNAL='@s9s_mb_2u_lib.s9s_mb_2u(sch_1):p5e_cpu1_pe0_rx_dn(6)';
NODE_NAME     U1 AB10
 '@S9S_MB_2U_LIB.S9S_MB_2U(SCH_1):PAGE60_I80@PURE_QUANTA.SOCKET4677_AZIF0045P001C01CS(CHIPS)':
 'PE0_RX_DN6': CDS_PINID='PE0_RX_DN6';
NODE_NAME     J111 B2
 '@S9S_MB_2U_LIB.S9S_MB_2U(SCH_1):PAGE148_I75@PURE_QUANTA.CONN112_10137002101LF(CHIPS)':
 'B2': CDS_PINID='B2';
NET_NAME
'P5E_CPU1_PE0_RX_DN<7>'
 '@S9S_MB_2U_LIB.S9S_MB_2U(SCH_1):P5E_CPU1_PE0_RX_DN'<7>:
 C_SIGNAL='@s9s_mb_2u_lib.s9s_mb_2u(sch_1):p5e_cpu1_pe0_rx_dn(7)';
NODE_NAME     U1 AE9
 '@S9S_MB_2U_LIB.S9S_MB_2U(SCH_1):PAGE60_I80@PURE_QUANTA.SOCKET4677_AZIF0045P001C01CS(CHIPS)':
 'PE0_RX_DN7': CDS_PINID='PE0_RX_DN7';
NODE_NAME     J111 C1
 '@S9S_MB_2U_LIB.S9S_MB_2U(SCH_1):PAGE148_I75@PURE_QUANTA.CONN112_10137002101LF(CHIPS)':
 'C1': CDS_PINID='C1';
NET_NAME
'P5E_CPU1_PE0_RX_DN<8>'
 '@S9S_MB_2U_LIB.S9S_MB_2U(SCH_1):P5E_CPU1_PE0_RX_DN'<8>:
 C_SIGNAL='@s9s_mb_2u_lib.s9s_mb_2u(sch_1):p5e_cpu1_pe0_rx_dn(8)';
NODE_NAME     U1 AF10
 '@S9S_MB_2U_LIB.S9S_MB_2U(SCH_1):PAGE60_I80@PURE_QUANTA.SOCKET4677_AZIF0045P001C01CS(CHIPS)':
 'PE0_RX_DN8': CDS_PINID='PE0_RX_DN8';
NODE_NAME     J112 B8
 '@S9S_MB_2U_LIB.S9S_MB_2U(SCH_1):PAGE149_I75@PURE_QUANTA.CONN160_10131762101LF(CHIPS)':
 'B8': CDS_PINID='B8';
NET_NAME
'P5E_CPU1_PE0_RX_DN<9>'
 '@S9S_MB_2U_LIB.S9S_MB_2U(SCH_1):P5E_CPU1_PE0_RX_DN'<9>:
 C_SIGNAL='@s9s_mb_2u_lib.s9s_mb_2u(sch_1):p5e_cpu1_pe0_rx_dn(9)';
NODE_NAME     U1 AJ9
 '@S9S_MB_2U_LIB.S9S_MB_2U(SCH_1):PAGE60_I80@PURE_QUANTA.SOCKET4677_AZIF0045P001C01CS(CHIPS)':
 'PE0_RX_DN9': CDS_PINID='PE0_RX_DN9';
NODE_NAME     J112 C7
 '@S9S_MB_2U_LIB.S9S_MB_2U(SCH_1):PAGE149_I75@PURE_QUANTA.CONN160_10131762101LF(CHIPS)':
 'C7': CDS_PINID='C7';
NET_NAME
'P5E_CPU1_PE0_RX_DP<0>'
 '@S9S_MB_2U_LIB.S9S_MB_2U(SCH_1):P5E_CPU1_PE0_RX_DP'<0>:
 C_SIGNAL='@s9s_mb_2u_lib.s9s_mb_2u(sch_1):p5e_cpu1_pe0_rx_dp(0)';
NODE_NAME     U1 L11
 '@S9S_MB_2U_LIB.S9S_MB_2U(SCH_1):PAGE60_I80@PURE_QUANTA.SOCKET4677_AZIF0045P001C01CS(CHIPS)':
 'PE0_RX_DP0': CDS_PINID='PE0_RX_DP0';
NODE_NAME     J111 C8
 '@S9S_MB_2U_LIB.S9S_MB_2U(SCH_1):PAGE148_I74@PURE_QUANTA.CONN112_10137002101LF(CHIPS)':
 'C8': CDS_PINID='C8';
NET_NAME
'P5E_CPU1_PE0_RX_DP<10>'
 '@S9S_MB_2U_LIB.S9S_MB_2U(SCH_1):P5E_CPU1_PE0_RX_DP'<10>:
 C_SIGNAL='@s9s_mb_2u_lib.s9s_mb_2u(sch_1):p5e_cpu1_pe0_rx_dp(10)';
NODE_NAME     U1 AL11
 '@S9S_MB_2U_LIB.S9S_MB_2U(SCH_1):PAGE60_I80@PURE_QUANTA.SOCKET4677_AZIF0045P001C01CS(CHIPS)':
 'PE0_RX_DP10': CDS_PINID='PE0_RX_DP10';
NODE_NAME     J112 C6
 '@S9S_MB_2U_LIB.S9S_MB_2U(SCH_1):PAGE149_I75@PURE_QUANTA.CONN160_10131762101LF(CHIPS)':
 'C6': CDS_PINID='C6';
NET_NAME
'P5E_CPU1_PE0_RX_DP<11>'
 '@S9S_MB_2U_LIB.S9S_MB_2U(SCH_1):P5E_CPU1_PE0_RX_DP'<11>:
 C_SIGNAL='@s9s_mb_2u_lib.s9s_mb_2u(sch_1):p5e_cpu1_pe0_rx_dp(11)';
NODE_NAME     U1 AN9
 '@S9S_MB_2U_LIB.S9S_MB_2U(SCH_1):PAGE60_I80@PURE_QUANTA.SOCKET4677_AZIF0045P001C01CS(CHIPS)':
 'PE0_RX_DP11': CDS_PINID='PE0_RX_DP11';
NODE_NAME     J112 C5
 '@S9S_MB_2U_LIB.S9S_MB_2U(SCH_1):PAGE149_I75@PURE_QUANTA.CONN160_10131762101LF(CHIPS)':
 'C5': CDS_PINID='C5';
NET_NAME
'P5E_CPU1_PE0_RX_DP<12>'
 '@S9S_MB_2U_LIB.S9S_MB_2U(SCH_1):P5E_CPU1_PE0_RX_DP'<12>:
 C_SIGNAL='@s9s_mb_2u_lib.s9s_mb_2u(sch_1):p5e_cpu1_pe0_rx_dp(12)';
NODE_NAME     U1 AR11
 '@S9S_MB_2U_LIB.S9S_MB_2U(SCH_1):PAGE60_I80@PURE_QUANTA.SOCKET4677_AZIF0045P001C01CS(CHIPS)':
 'PE0_RX_DP12': CDS_PINID='PE0_RX_DP12';
NODE_NAME     J112 C4
 '@S9S_MB_2U_LIB.S9S_MB_2U(SCH_1):PAGE149_I76@PURE_QUANTA.CONN160_10131762101LF(CHIPS)':
 'C4': CDS_PINID='C4';
NET_NAME
'P5E_CPU1_PE0_RX_DP<13>'
 '@S9S_MB_2U_LIB.S9S_MB_2U(SCH_1):P5E_CPU1_PE0_RX_DP'<13>:
 C_SIGNAL='@s9s_mb_2u_lib.s9s_mb_2u(sch_1):p5e_cpu1_pe0_rx_dp(13)';
NODE_NAME     U1 AT10
 '@S9S_MB_2U_LIB.S9S_MB_2U(SCH_1):PAGE60_I80@PURE_QUANTA.SOCKET4677_AZIF0045P001C01CS(CHIPS)':
 'PE0_RX_DP13': CDS_PINID='PE0_RX_DP13';
NODE_NAME     J112 D3
 '@S9S_MB_2U_LIB.S9S_MB_2U(SCH_1):PAGE149_I76@PURE_QUANTA.CONN160_10131762101LF(CHIPS)':
 'D3': CDS_PINID='D3';
NET_NAME
'P5E_CPU1_PE0_RX_DP<14>'
 '@S9S_MB_2U_LIB.S9S_MB_2U(SCH_1):P5E_CPU1_PE0_RX_DP'<14>:
 C_SIGNAL='@s9s_mb_2u_lib.s9s_mb_2u(sch_1):p5e_cpu1_pe0_rx_dp(14)';
NODE_NAME     U1 AW11
 '@S9S_MB_2U_LIB.S9S_MB_2U(SCH_1):PAGE60_I80@PURE_QUANTA.SOCKET4677_AZIF0045P001C01CS(CHIPS)':
 'PE0_RX_DP14': CDS_PINID='PE0_RX_DP14';
NODE_NAME     J112 C2
 '@S9S_MB_2U_LIB.S9S_MB_2U(SCH_1):PAGE149_I76@PURE_QUANTA.CONN160_10131762101LF(CHIPS)':
 'C2': CDS_PINID='C2';
NET_NAME
'P5E_CPU1_PE0_RX_DP<15>'
 '@S9S_MB_2U_LIB.S9S_MB_2U(SCH_1):P5E_CPU1_PE0_RX_DP'<15>:
 C_SIGNAL='@s9s_mb_2u_lib.s9s_mb_2u(sch_1):p5e_cpu1_pe0_rx_dp(15)';
NODE_NAME     U1 AY10
 '@S9S_MB_2U_LIB.S9S_MB_2U(SCH_1):PAGE60_I80@PURE_QUANTA.SOCKET4677_AZIF0045P001C01CS(CHIPS)':
 'PE0_RX_DP15': CDS_PINID='PE0_RX_DP15';
NODE_NAME     J112 D1
 '@S9S_MB_2U_LIB.S9S_MB_2U(SCH_1):PAGE149_I76@PURE_QUANTA.CONN160_10131762101LF(CHIPS)':
 'D1': CDS_PINID='D1';
NET_NAME
'P5E_CPU1_PE0_RX_DP<1>'
 '@S9S_MB_2U_LIB.S9S_MB_2U(SCH_1):P5E_CPU1_PE0_RX_DP'<1>:
 C_SIGNAL='@s9s_mb_2u_lib.s9s_mb_2u(sch_1):p5e_cpu1_pe0_rx_dp(1)';
NODE_NAME     U1 N9
 '@S9S_MB_2U_LIB.S9S_MB_2U(SCH_1):PAGE60_I80@PURE_QUANTA.SOCKET4677_AZIF0045P001C01CS(CHIPS)':
 'PE0_RX_DP1': CDS_PINID='PE0_RX_DP1';
NODE_NAME     J111 C7
 '@S9S_MB_2U_LIB.S9S_MB_2U(SCH_1):PAGE148_I74@PURE_QUANTA.CONN112_10137002101LF(CHIPS)':
 'C7': CDS_PINID='C7';
NET_NAME
'P5E_CPU1_PE0_RX_DP<2>'
 '@S9S_MB_2U_LIB.S9S_MB_2U(SCH_1):P5E_CPU1_PE0_RX_DP'<2>:
 C_SIGNAL='@s9s_mb_2u_lib.s9s_mb_2u(sch_1):p5e_cpu1_pe0_rx_dp(2)';
NODE_NAME     U1 R11
 '@S9S_MB_2U_LIB.S9S_MB_2U(SCH_1):PAGE60_I80@PURE_QUANTA.SOCKET4677_AZIF0045P001C01CS(CHIPS)':
 'PE0_RX_DP2': CDS_PINID='PE0_RX_DP2';
NODE_NAME     J111 C6
 '@S9S_MB_2U_LIB.S9S_MB_2U(SCH_1):PAGE148_I74@PURE_QUANTA.CONN112_10137002101LF(CHIPS)':
 'C6': CDS_PINID='C6';
NET_NAME
'P5E_CPU1_PE0_RX_DP<3>'
 '@S9S_MB_2U_LIB.S9S_MB_2U(SCH_1):P5E_CPU1_PE0_RX_DP'<3>:
 C_SIGNAL='@s9s_mb_2u_lib.s9s_mb_2u(sch_1):p5e_cpu1_pe0_rx_dp(3)';
NODE_NAME     U1 U9
 '@S9S_MB_2U_LIB.S9S_MB_2U(SCH_1):PAGE60_I80@PURE_QUANTA.SOCKET4677_AZIF0045P001C01CS(CHIPS)':
 'PE0_RX_DP3': CDS_PINID='PE0_RX_DP3';
NODE_NAME     J111 C5
 '@S9S_MB_2U_LIB.S9S_MB_2U(SCH_1):PAGE148_I74@PURE_QUANTA.CONN112_10137002101LF(CHIPS)':
 'C5': CDS_PINID='C5';
NET_NAME
'P5E_CPU1_PE0_RX_DP<4>'
 '@S9S_MB_2U_LIB.S9S_MB_2U(SCH_1):P5E_CPU1_PE0_RX_DP'<4>:
 C_SIGNAL='@s9s_mb_2u_lib.s9s_mb_2u(sch_1):p5e_cpu1_pe0_rx_dp(4)';
NODE_NAME     U1 W11
 '@S9S_MB_2U_LIB.S9S_MB_2U(SCH_1):PAGE60_I80@PURE_QUANTA.SOCKET4677_AZIF0045P001C01CS(CHIPS)':
 'PE0_RX_DP4': CDS_PINID='PE0_RX_DP4';
NODE_NAME     J111 C4
 '@S9S_MB_2U_LIB.S9S_MB_2U(SCH_1):PAGE148_I75@PURE_QUANTA.CONN112_10137002101LF(CHIPS)':
 'C4': CDS_PINID='C4';
NET_NAME
'P5E_CPU1_PE0_RX_DP<5>'
 '@S9S_MB_2U_LIB.S9S_MB_2U(SCH_1):P5E_CPU1_PE0_RX_DP'<5>:
 C_SIGNAL='@s9s_mb_2u_lib.s9s_mb_2u(sch_1):p5e_cpu1_pe0_rx_dp(5)';
NODE_NAME     U1 Y10
 '@S9S_MB_2U_LIB.S9S_MB_2U(SCH_1):PAGE60_I80@PURE_QUANTA.SOCKET4677_AZIF0045P001C01CS(CHIPS)':
 'PE0_RX_DP5': CDS_PINID='PE0_RX_DP5';
NODE_NAME     J111 D3
 '@S9S_MB_2U_LIB.S9S_MB_2U(SCH_1):PAGE148_I75@PURE_QUANTA.CONN112_10137002101LF(CHIPS)':
 'D3': CDS_PINID='D3';
NET_NAME
'P5E_CPU1_PE0_RX_DP<6>'
 '@S9S_MB_2U_LIB.S9S_MB_2U(SCH_1):P5E_CPU1_PE0_RX_DP'<6>:
 C_SIGNAL='@s9s_mb_2u_lib.s9s_mb_2u(sch_1):p5e_cpu1_pe0_rx_dp(6)';
NODE_NAME     U1 AC11
 '@S9S_MB_2U_LIB.S9S_MB_2U(SCH_1):PAGE60_I80@PURE_QUANTA.SOCKET4677_AZIF0045P001C01CS(CHIPS)':
 'PE0_RX_DP6': CDS_PINID='PE0_RX_DP6';
NODE_NAME     J111 C2
 '@S9S_MB_2U_LIB.S9S_MB_2U(SCH_1):PAGE148_I75@PURE_QUANTA.CONN112_10137002101LF(CHIPS)':
 'C2': CDS_PINID='C2';
NET_NAME
'P5E_CPU1_PE0_RX_DP<7>'
 '@S9S_MB_2U_LIB.S9S_MB_2U(SCH_1):P5E_CPU1_PE0_RX_DP'<7>:
 C_SIGNAL='@s9s_mb_2u_lib.s9s_mb_2u(sch_1):p5e_cpu1_pe0_rx_dp(7)';
NODE_NAME     U1 AD10
 '@S9S_MB_2U_LIB.S9S_MB_2U(SCH_1):PAGE60_I80@PURE_QUANTA.SOCKET4677_AZIF0045P001C01CS(CHIPS)':
 'PE0_RX_DP7': CDS_PINID='PE0_RX_DP7';
NODE_NAME     J111 D1
 '@S9S_MB_2U_LIB.S9S_MB_2U(SCH_1):PAGE148_I75@PURE_QUANTA.CONN112_10137002101LF(CHIPS)':
 'D1': CDS_PINID='D1';
NET_NAME
'P5E_CPU1_PE0_RX_DP<8>'
 '@S9S_MB_2U_LIB.S9S_MB_2U(SCH_1):P5E_CPU1_PE0_RX_DP'<8>:
 C_SIGNAL='@s9s_mb_2u_lib.s9s_mb_2u(sch_1):p5e_cpu1_pe0_rx_dp(8)';
NODE_NAME     U1 AG11
 '@S9S_MB_2U_LIB.S9S_MB_2U(SCH_1):PAGE60_I80@PURE_QUANTA.SOCKET4677_AZIF0045P001C01CS(CHIPS)':
 'PE0_RX_DP8': CDS_PINID='PE0_RX_DP8';
NODE_NAME     J112 C8
 '@S9S_MB_2U_LIB.S9S_MB_2U(SCH_1):PAGE149_I75@PURE_QUANTA.CONN160_10131762101LF(CHIPS)':
 'C8': CDS_PINID='C8';
NET_NAME
'P5E_CPU1_PE0_RX_DP<9>'
 '@S9S_MB_2U_LIB.S9S_MB_2U(SCH_1):P5E_CPU1_PE0_RX_DP'<9>:
 C_SIGNAL='@s9s_mb_2u_lib.s9s_mb_2u(sch_1):p5e_cpu1_pe0_rx_dp(9)';
NODE_NAME     U1 AH10
 '@S9S_MB_2U_LIB.S9S_MB_2U(SCH_1):PAGE60_I80@PURE_QUANTA.SOCKET4677_AZIF0045P001C01CS(CHIPS)':
 'PE0_RX_DP9': CDS_PINID='PE0_RX_DP9';
NODE_NAME     J112 D7
 '@S9S_MB_2U_LIB.S9S_MB_2U(SCH_1):PAGE149_I75@PURE_QUANTA.CONN160_10131762101LF(CHIPS)':
 'D7': CDS_PINID='D7';
NET_NAME
'P5E_CPU1_PE0_TX_C_DN<0>'
 '@S9S_MB_2U_LIB.S9S_MB_2U(SCH_1):P5E_CPU1_PE0_TX_C_DN'<0>:
 C_SIGNAL='@s9s_mb_2u_lib.s9s_mb_2u(sch_1):p5e_cpu1_pe0_tx_c_dn(0)';
NODE_NAME     J111 H8
 '@S9S_MB_2U_LIB.S9S_MB_2U(SCH_1):PAGE148_I74@PURE_QUANTA.CONN112_10137002101LF(CHIPS)':
 'H8': CDS_PINID='H8';
NODE_NAME     C740 1
 '@S9S_MB_2U_LIB.S9S_MB_2U(SCH_1):PAGE167_I229@PURE_QUANTA.Q_CAP_DIFFBUS(CHIPS)':
 '1': CDS_PINID='\1\';
NET_NAME
'P5E_CPU1_PE0_TX_C_DN<10>'
 '@S9S_MB_2U_LIB.S9S_MB_2U(SCH_1):P5E_CPU1_PE0_TX_C_DN'<10>:
 C_SIGNAL='@s9s_mb_2u_lib.s9s_mb_2u(sch_1):p5e_cpu1_pe0_tx_c_dn(10)';
NODE_NAME     C720 1
 '@S9S_MB_2U_LIB.S9S_MB_2U(SCH_1):PAGE167_I279@PURE_QUANTA.Q_CAP_DIFFBUS(CHIPS)':
 '1': CDS_PINID='\1\';
NODE_NAME     J112 H6
 '@S9S_MB_2U_LIB.S9S_MB_2U(SCH_1):PAGE149_I75@PURE_QUANTA.CONN160_10131762101LF(CHIPS)':
 'H6': CDS_PINID='H6';
NET_NAME
'P5E_CPU1_PE0_TX_C_DN<11>'
 '@S9S_MB_2U_LIB.S9S_MB_2U(SCH_1):P5E_CPU1_PE0_TX_C_DN'<11>:
 C_SIGNAL='@s9s_mb_2u_lib.s9s_mb_2u(sch_1):p5e_cpu1_pe0_tx_c_dn(11)';
NODE_NAME     C718 1
 '@S9S_MB_2U_LIB.S9S_MB_2U(SCH_1):PAGE167_I281@PURE_QUANTA.Q_CAP_DIFFBUS(CHIPS)':
 '1': CDS_PINID='\1\';
NODE_NAME     J112 I5
 '@S9S_MB_2U_LIB.S9S_MB_2U(SCH_1):PAGE149_I75@PURE_QUANTA.CONN160_10131762101LF(CHIPS)':
 'I5': CDS_PINID='I5';
NET_NAME
'P5E_CPU1_PE0_TX_C_DN<12>'
 '@S9S_MB_2U_LIB.S9S_MB_2U(SCH_1):P5E_CPU1_PE0_TX_C_DN'<12>:
 C_SIGNAL='@s9s_mb_2u_lib.s9s_mb_2u(sch_1):p5e_cpu1_pe0_tx_c_dn(12)';
NODE_NAME     C716 1
 '@S9S_MB_2U_LIB.S9S_MB_2U(SCH_1):PAGE167_I283@PURE_QUANTA.Q_CAP_DIFFBUS(CHIPS)':
 '1': CDS_PINID='\1\';
NODE_NAME     J112 H4
 '@S9S_MB_2U_LIB.S9S_MB_2U(SCH_1):PAGE149_I76@PURE_QUANTA.CONN160_10131762101LF(CHIPS)':
 'H4': CDS_PINID='H4';
NET_NAME
'P5E_CPU1_PE0_TX_C_DN<13>'
 '@S9S_MB_2U_LIB.S9S_MB_2U(SCH_1):P5E_CPU1_PE0_TX_C_DN'<13>:
 C_SIGNAL='@s9s_mb_2u_lib.s9s_mb_2u(sch_1):p5e_cpu1_pe0_tx_c_dn(13)';
NODE_NAME     C714 1
 '@S9S_MB_2U_LIB.S9S_MB_2U(SCH_1):PAGE167_I295@PURE_QUANTA.Q_CAP_DIFFBUS(CHIPS)':
 '1': CDS_PINID='\1\';
NODE_NAME     J112 I3
 '@S9S_MB_2U_LIB.S9S_MB_2U(SCH_1):PAGE149_I76@PURE_QUANTA.CONN160_10131762101LF(CHIPS)':
 'I3': CDS_PINID='I3';
NET_NAME
'P5E_CPU1_PE0_TX_C_DN<14>'
 '@S9S_MB_2U_LIB.S9S_MB_2U(SCH_1):P5E_CPU1_PE0_TX_C_DN'<14>:
 C_SIGNAL='@s9s_mb_2u_lib.s9s_mb_2u(sch_1):p5e_cpu1_pe0_tx_c_dn(14)';
NODE_NAME     C712 1
 '@S9S_MB_2U_LIB.S9S_MB_2U(SCH_1):PAGE167_I296@PURE_QUANTA.Q_CAP_DIFFBUS(CHIPS)':
 '1': CDS_PINID='\1\';
NODE_NAME     J112 H2
 '@S9S_MB_2U_LIB.S9S_MB_2U(SCH_1):PAGE149_I76@PURE_QUANTA.CONN160_10131762101LF(CHIPS)':
 'H2': CDS_PINID='H2';
NET_NAME
'P5E_CPU1_PE0_TX_C_DN<15>'
 '@S9S_MB_2U_LIB.S9S_MB_2U(SCH_1):P5E_CPU1_PE0_TX_C_DN'<15>:
 C_SIGNAL='@s9s_mb_2u_lib.s9s_mb_2u(sch_1):p5e_cpu1_pe0_tx_c_dn(15)';
NODE_NAME     C710 1
 '@S9S_MB_2U_LIB.S9S_MB_2U(SCH_1):PAGE167_I299@PURE_QUANTA.Q_CAP_DIFFBUS(CHIPS)':
 '1': CDS_PINID='\1\';
NODE_NAME     J112 I1
 '@S9S_MB_2U_LIB.S9S_MB_2U(SCH_1):PAGE149_I76@PURE_QUANTA.CONN160_10131762101LF(CHIPS)':
 'I1': CDS_PINID='I1';
NET_NAME
'P5E_CPU1_PE0_TX_C_DN<1>'
 '@S9S_MB_2U_LIB.S9S_MB_2U(SCH_1):P5E_CPU1_PE0_TX_C_DN'<1>:
 C_SIGNAL='@s9s_mb_2u_lib.s9s_mb_2u(sch_1):p5e_cpu1_pe0_tx_c_dn(1)';
NODE_NAME     J111 I7
 '@S9S_MB_2U_LIB.S9S_MB_2U(SCH_1):PAGE148_I74@PURE_QUANTA.CONN112_10137002101LF(CHIPS)':
 'I7': CDS_PINID='I7';
NODE_NAME     C738 1
 '@S9S_MB_2U_LIB.S9S_MB_2U(SCH_1):PAGE167_I232@PURE_QUANTA.Q_CAP_DIFFBUS(CHIPS)':
 '1': CDS_PINID='\1\';
NET_NAME
'P5E_CPU1_PE0_TX_C_DN<2>'
 '@S9S_MB_2U_LIB.S9S_MB_2U(SCH_1):P5E_CPU1_PE0_TX_C_DN'<2>:
 C_SIGNAL='@s9s_mb_2u_lib.s9s_mb_2u(sch_1):p5e_cpu1_pe0_tx_c_dn(2)';
NODE_NAME     J111 H6
 '@S9S_MB_2U_LIB.S9S_MB_2U(SCH_1):PAGE148_I74@PURE_QUANTA.CONN112_10137002101LF(CHIPS)':
 'H6': CDS_PINID='H6';
NODE_NAME     C736 1
 '@S9S_MB_2U_LIB.S9S_MB_2U(SCH_1):PAGE167_I234@PURE_QUANTA.Q_CAP_DIFFBUS(CHIPS)':
 '1': CDS_PINID='\1\';
NET_NAME
'P5E_CPU1_PE0_TX_C_DN<3>'
 '@S9S_MB_2U_LIB.S9S_MB_2U(SCH_1):P5E_CPU1_PE0_TX_C_DN'<3>:
 C_SIGNAL='@s9s_mb_2u_lib.s9s_mb_2u(sch_1):p5e_cpu1_pe0_tx_c_dn(3)';
NODE_NAME     J111 I5
 '@S9S_MB_2U_LIB.S9S_MB_2U(SCH_1):PAGE148_I74@PURE_QUANTA.CONN112_10137002101LF(CHIPS)':
 'I5': CDS_PINID='I5';
NODE_NAME     C734 1
 '@S9S_MB_2U_LIB.S9S_MB_2U(SCH_1):PAGE167_I235@PURE_QUANTA.Q_CAP_DIFFBUS(CHIPS)':
 '1': CDS_PINID='\1\';
NET_NAME
'P5E_CPU1_PE0_TX_C_DN<4>'
 '@S9S_MB_2U_LIB.S9S_MB_2U(SCH_1):P5E_CPU1_PE0_TX_C_DN'<4>:
 C_SIGNAL='@s9s_mb_2u_lib.s9s_mb_2u(sch_1):p5e_cpu1_pe0_tx_c_dn(4)';
NODE_NAME     C732 1
 '@S9S_MB_2U_LIB.S9S_MB_2U(SCH_1):PAGE167_I246@PURE_QUANTA.Q_CAP_DIFFBUS(CHIPS)':
 '1': CDS_PINID='\1\';
NODE_NAME     J111 H4
 '@S9S_MB_2U_LIB.S9S_MB_2U(SCH_1):PAGE148_I75@PURE_QUANTA.CONN112_10137002101LF(CHIPS)':
 'H4': CDS_PINID='H4';
NET_NAME
'P5E_CPU1_PE0_TX_C_DN<5>'
 '@S9S_MB_2U_LIB.S9S_MB_2U(SCH_1):P5E_CPU1_PE0_TX_C_DN'<5>:
 C_SIGNAL='@s9s_mb_2u_lib.s9s_mb_2u(sch_1):p5e_cpu1_pe0_tx_c_dn(5)';
NODE_NAME     C730 1
 '@S9S_MB_2U_LIB.S9S_MB_2U(SCH_1):PAGE167_I248@PURE_QUANTA.Q_CAP_DIFFBUS(CHIPS)':
 '1': CDS_PINID='\1\';
NODE_NAME     J111 I3
 '@S9S_MB_2U_LIB.S9S_MB_2U(SCH_1):PAGE148_I75@PURE_QUANTA.CONN112_10137002101LF(CHIPS)':
 'I3': CDS_PINID='I3';
NET_NAME
'P5E_CPU1_PE0_TX_C_DN<6>'
 '@S9S_MB_2U_LIB.S9S_MB_2U(SCH_1):P5E_CPU1_PE0_TX_C_DN'<6>:
 C_SIGNAL='@s9s_mb_2u_lib.s9s_mb_2u(sch_1):p5e_cpu1_pe0_tx_c_dn(6)';
NODE_NAME     C728 1
 '@S9S_MB_2U_LIB.S9S_MB_2U(SCH_1):PAGE167_I250@PURE_QUANTA.Q_CAP_DIFFBUS(CHIPS)':
 '1': CDS_PINID='\1\';
NODE_NAME     J111 H2
 '@S9S_MB_2U_LIB.S9S_MB_2U(SCH_1):PAGE148_I75@PURE_QUANTA.CONN112_10137002101LF(CHIPS)':
 'H2': CDS_PINID='H2';
NET_NAME
'P5E_CPU1_PE0_TX_C_DN<7>'
 '@S9S_MB_2U_LIB.S9S_MB_2U(SCH_1):P5E_CPU1_PE0_TX_C_DN'<7>:
 C_SIGNAL='@s9s_mb_2u_lib.s9s_mb_2u(sch_1):p5e_cpu1_pe0_tx_c_dn(7)';
NODE_NAME     C726 1
 '@S9S_MB_2U_LIB.S9S_MB_2U(SCH_1):PAGE167_I312@PURE_QUANTA.Q_CAP_DIFFBUS(CHIPS)':
 '1': CDS_PINID='\1\';
NODE_NAME     J111 I1
 '@S9S_MB_2U_LIB.S9S_MB_2U(SCH_1):PAGE148_I75@PURE_QUANTA.CONN112_10137002101LF(CHIPS)':
 'I1': CDS_PINID='I1';
NET_NAME
'P5E_CPU1_PE0_TX_C_DN<8>'
 '@S9S_MB_2U_LIB.S9S_MB_2U(SCH_1):P5E_CPU1_PE0_TX_C_DN'<8>:
 C_SIGNAL='@s9s_mb_2u_lib.s9s_mb_2u(sch_1):p5e_cpu1_pe0_tx_c_dn(8)';
NODE_NAME     C724 1
 '@S9S_MB_2U_LIB.S9S_MB_2U(SCH_1):PAGE167_I275@PURE_QUANTA.Q_CAP_DIFFBUS(CHIPS)':
 '1': CDS_PINID='\1\';
NODE_NAME     J112 H8
 '@S9S_MB_2U_LIB.S9S_MB_2U(SCH_1):PAGE149_I75@PURE_QUANTA.CONN160_10131762101LF(CHIPS)':
 'H8': CDS_PINID='H8';
NET_NAME
'P5E_CPU1_PE0_TX_C_DN<9>'
 '@S9S_MB_2U_LIB.S9S_MB_2U(SCH_1):P5E_CPU1_PE0_TX_C_DN'<9>:
 C_SIGNAL='@s9s_mb_2u_lib.s9s_mb_2u(sch_1):p5e_cpu1_pe0_tx_c_dn(9)';
NODE_NAME     C722 1
 '@S9S_MB_2U_LIB.S9S_MB_2U(SCH_1):PAGE167_I276@PURE_QUANTA.Q_CAP_DIFFBUS(CHIPS)':
 '1': CDS_PINID='\1\';
NODE_NAME     J112 I7
 '@S9S_MB_2U_LIB.S9S_MB_2U(SCH_1):PAGE149_I75@PURE_QUANTA.CONN160_10131762101LF(CHIPS)':
 'I7': CDS_PINID='I7';
NET_NAME
'P5E_CPU1_PE0_TX_C_DP<0>'
 '@S9S_MB_2U_LIB.S9S_MB_2U(SCH_1):P5E_CPU1_PE0_TX_C_DP'<0>:
 C_SIGNAL='@s9s_mb_2u_lib.s9s_mb_2u(sch_1):p5e_cpu1_pe0_tx_c_dp(0)';
NODE_NAME     J111 I8
 '@S9S_MB_2U_LIB.S9S_MB_2U(SCH_1):PAGE148_I74@PURE_QUANTA.CONN112_10137002101LF(CHIPS)':
 'I8': CDS_PINID='I8';
NODE_NAME     C741 1
 '@S9S_MB_2U_LIB.S9S_MB_2U(SCH_1):PAGE167_I230@PURE_QUANTA.Q_CAP_DIFFBUS(CHIPS)':
 '1': CDS_PINID='\1\';
NET_NAME
'P5E_CPU1_PE0_TX_C_DP<10>'
 '@S9S_MB_2U_LIB.S9S_MB_2U(SCH_1):P5E_CPU1_PE0_TX_C_DP'<10>:
 C_SIGNAL='@s9s_mb_2u_lib.s9s_mb_2u(sch_1):p5e_cpu1_pe0_tx_c_dp(10)';
NODE_NAME     C721 1
 '@S9S_MB_2U_LIB.S9S_MB_2U(SCH_1):PAGE167_I278@PURE_QUANTA.Q_CAP_DIFFBUS(CHIPS)':
 '1': CDS_PINID='\1\';
NODE_NAME     J112 I6
 '@S9S_MB_2U_LIB.S9S_MB_2U(SCH_1):PAGE149_I75@PURE_QUANTA.CONN160_10131762101LF(CHIPS)':
 'I6': CDS_PINID='I6';
NET_NAME
'P5E_CPU1_PE0_TX_C_DP<11>'
 '@S9S_MB_2U_LIB.S9S_MB_2U(SCH_1):P5E_CPU1_PE0_TX_C_DP'<11>:
 C_SIGNAL='@s9s_mb_2u_lib.s9s_mb_2u(sch_1):p5e_cpu1_pe0_tx_c_dp(11)';
NODE_NAME     C719 1
 '@S9S_MB_2U_LIB.S9S_MB_2U(SCH_1):PAGE167_I280@PURE_QUANTA.Q_CAP_DIFFBUS(CHIPS)':
 '1': CDS_PINID='\1\';
NODE_NAME     J112 J5
 '@S9S_MB_2U_LIB.S9S_MB_2U(SCH_1):PAGE149_I75@PURE_QUANTA.CONN160_10131762101LF(CHIPS)':
 'J5': CDS_PINID='J5';
NET_NAME
'P5E_CPU1_PE0_TX_C_DP<12>'
 '@S9S_MB_2U_LIB.S9S_MB_2U(SCH_1):P5E_CPU1_PE0_TX_C_DP'<12>:
 C_SIGNAL='@s9s_mb_2u_lib.s9s_mb_2u(sch_1):p5e_cpu1_pe0_tx_c_dp(12)';
NODE_NAME     C717 1
 '@S9S_MB_2U_LIB.S9S_MB_2U(SCH_1):PAGE167_I282@PURE_QUANTA.Q_CAP_DIFFBUS(CHIPS)':
 '1': CDS_PINID='\1\';
NODE_NAME     J112 I4
 '@S9S_MB_2U_LIB.S9S_MB_2U(SCH_1):PAGE149_I76@PURE_QUANTA.CONN160_10131762101LF(CHIPS)':
 'I4': CDS_PINID='I4';
NET_NAME
'P5E_CPU1_PE0_TX_C_DP<13>'
 '@S9S_MB_2U_LIB.S9S_MB_2U(SCH_1):P5E_CPU1_PE0_TX_C_DP'<13>:
 C_SIGNAL='@s9s_mb_2u_lib.s9s_mb_2u(sch_1):p5e_cpu1_pe0_tx_c_dp(13)';
NODE_NAME     C715 1
 '@S9S_MB_2U_LIB.S9S_MB_2U(SCH_1):PAGE167_I294@PURE_QUANTA.Q_CAP_DIFFBUS(CHIPS)':
 '1': CDS_PINID='\1\';
NODE_NAME     J112 J3
 '@S9S_MB_2U_LIB.S9S_MB_2U(SCH_1):PAGE149_I76@PURE_QUANTA.CONN160_10131762101LF(CHIPS)':
 'J3': CDS_PINID='J3';
NET_NAME
'P5E_CPU1_PE0_TX_C_DP<14>'
 '@S9S_MB_2U_LIB.S9S_MB_2U(SCH_1):P5E_CPU1_PE0_TX_C_DP'<14>:
 C_SIGNAL='@s9s_mb_2u_lib.s9s_mb_2u(sch_1):p5e_cpu1_pe0_tx_c_dp(14)';
NODE_NAME     C713 1
 '@S9S_MB_2U_LIB.S9S_MB_2U(SCH_1):PAGE167_I297@PURE_QUANTA.Q_CAP_DIFFBUS(CHIPS)':
 '1': CDS_PINID='\1\';
NODE_NAME     J112 I2
 '@S9S_MB_2U_LIB.S9S_MB_2U(SCH_1):PAGE149_I76@PURE_QUANTA.CONN160_10131762101LF(CHIPS)':
 'I2': CDS_PINID='I2';
NET_NAME
'P5E_CPU1_PE0_TX_C_DP<15>'
 '@S9S_MB_2U_LIB.S9S_MB_2U(SCH_1):P5E_CPU1_PE0_TX_C_DP'<15>:
 C_SIGNAL='@s9s_mb_2u_lib.s9s_mb_2u(sch_1):p5e_cpu1_pe0_tx_c_dp(15)';
NODE_NAME     C711 1
 '@S9S_MB_2U_LIB.S9S_MB_2U(SCH_1):PAGE167_I298@PURE_QUANTA.Q_CAP_DIFFBUS(CHIPS)':
 '1': CDS_PINID='\1\';
NODE_NAME     J112 J1
 '@S9S_MB_2U_LIB.S9S_MB_2U(SCH_1):PAGE149_I76@PURE_QUANTA.CONN160_10131762101LF(CHIPS)':
 'J1': CDS_PINID='J1';
NET_NAME
'P5E_CPU1_PE0_TX_C_DP<1>'
 '@S9S_MB_2U_LIB.S9S_MB_2U(SCH_1):P5E_CPU1_PE0_TX_C_DP'<1>:
 C_SIGNAL='@s9s_mb_2u_lib.s9s_mb_2u(sch_1):p5e_cpu1_pe0_tx_c_dp(1)';
NODE_NAME     J111 J7
 '@S9S_MB_2U_LIB.S9S_MB_2U(SCH_1):PAGE148_I74@PURE_QUANTA.CONN112_10137002101LF(CHIPS)':
 'J7': CDS_PINID='J7';
NODE_NAME     C739 1
 '@S9S_MB_2U_LIB.S9S_MB_2U(SCH_1):PAGE167_I231@PURE_QUANTA.Q_CAP_DIFFBUS(CHIPS)':
 '1': CDS_PINID='\1\';
NET_NAME
'P5E_CPU1_PE0_TX_C_DP<2>'
 '@S9S_MB_2U_LIB.S9S_MB_2U(SCH_1):P5E_CPU1_PE0_TX_C_DP'<2>:
 C_SIGNAL='@s9s_mb_2u_lib.s9s_mb_2u(sch_1):p5e_cpu1_pe0_tx_c_dp(2)';
NODE_NAME     J111 I6
 '@S9S_MB_2U_LIB.S9S_MB_2U(SCH_1):PAGE148_I74@PURE_QUANTA.CONN112_10137002101LF(CHIPS)':
 'I6': CDS_PINID='I6';
NODE_NAME     C737 1
 '@S9S_MB_2U_LIB.S9S_MB_2U(SCH_1):PAGE167_I233@PURE_QUANTA.Q_CAP_DIFFBUS(CHIPS)':
 '1': CDS_PINID='\1\';
NET_NAME
'P5E_CPU1_PE0_TX_C_DP<3>'
 '@S9S_MB_2U_LIB.S9S_MB_2U(SCH_1):P5E_CPU1_PE0_TX_C_DP'<3>:
 C_SIGNAL='@s9s_mb_2u_lib.s9s_mb_2u(sch_1):p5e_cpu1_pe0_tx_c_dp(3)';
NODE_NAME     J111 J5
 '@S9S_MB_2U_LIB.S9S_MB_2U(SCH_1):PAGE148_I74@PURE_QUANTA.CONN112_10137002101LF(CHIPS)':
 'J5': CDS_PINID='J5';
NODE_NAME     C735 1
 '@S9S_MB_2U_LIB.S9S_MB_2U(SCH_1):PAGE167_I236@PURE_QUANTA.Q_CAP_DIFFBUS(CHIPS)':
 '1': CDS_PINID='\1\';
NET_NAME
'P5E_CPU1_PE0_TX_C_DP<4>'
 '@S9S_MB_2U_LIB.S9S_MB_2U(SCH_1):P5E_CPU1_PE0_TX_C_DP'<4>:
 C_SIGNAL='@s9s_mb_2u_lib.s9s_mb_2u(sch_1):p5e_cpu1_pe0_tx_c_dp(4)';
NODE_NAME     C733 1
 '@S9S_MB_2U_LIB.S9S_MB_2U(SCH_1):PAGE167_I237@PURE_QUANTA.Q_CAP_DIFFBUS(CHIPS)':
 '1': CDS_PINID='\1\';
NODE_NAME     J111 I4
 '@S9S_MB_2U_LIB.S9S_MB_2U(SCH_1):PAGE148_I75@PURE_QUANTA.CONN112_10137002101LF(CHIPS)':
 'I4': CDS_PINID='I4';
NET_NAME
'P5E_CPU1_PE0_TX_C_DP<5>'
 '@S9S_MB_2U_LIB.S9S_MB_2U(SCH_1):P5E_CPU1_PE0_TX_C_DP'<5>:
 C_SIGNAL='@s9s_mb_2u_lib.s9s_mb_2u(sch_1):p5e_cpu1_pe0_tx_c_dp(5)';
NODE_NAME     C731 1
 '@S9S_MB_2U_LIB.S9S_MB_2U(SCH_1):PAGE167_I247@PURE_QUANTA.Q_CAP_DIFFBUS(CHIPS)':
 '1': CDS_PINID='\1\';
NODE_NAME     J111 J3
 '@S9S_MB_2U_LIB.S9S_MB_2U(SCH_1):PAGE148_I75@PURE_QUANTA.CONN112_10137002101LF(CHIPS)':
 'J3': CDS_PINID='J3';
NET_NAME
'P5E_CPU1_PE0_TX_C_DP<6>'
 '@S9S_MB_2U_LIB.S9S_MB_2U(SCH_1):P5E_CPU1_PE0_TX_C_DP'<6>:
 C_SIGNAL='@s9s_mb_2u_lib.s9s_mb_2u(sch_1):p5e_cpu1_pe0_tx_c_dp(6)';
NODE_NAME     C729 1
 '@S9S_MB_2U_LIB.S9S_MB_2U(SCH_1):PAGE167_I249@PURE_QUANTA.Q_CAP_DIFFBUS(CHIPS)':
 '1': CDS_PINID='\1\';
NODE_NAME     J111 I2
 '@S9S_MB_2U_LIB.S9S_MB_2U(SCH_1):PAGE148_I75@PURE_QUANTA.CONN112_10137002101LF(CHIPS)':
 'I2': CDS_PINID='I2';
NET_NAME
'P5E_CPU1_PE0_TX_C_DP<7>'
 '@S9S_MB_2U_LIB.S9S_MB_2U(SCH_1):P5E_CPU1_PE0_TX_C_DP'<7>:
 C_SIGNAL='@s9s_mb_2u_lib.s9s_mb_2u(sch_1):p5e_cpu1_pe0_tx_c_dp(7)';
NODE_NAME     C727 1
 '@S9S_MB_2U_LIB.S9S_MB_2U(SCH_1):PAGE167_I251@PURE_QUANTA.Q_CAP_DIFFBUS(CHIPS)':
 '1': CDS_PINID='\1\';
NODE_NAME     J111 J1
 '@S9S_MB_2U_LIB.S9S_MB_2U(SCH_1):PAGE148_I75@PURE_QUANTA.CONN112_10137002101LF(CHIPS)':
 'J1': CDS_PINID='J1';
NET_NAME
'P5E_CPU1_PE0_TX_C_DP<8>'
 '@S9S_MB_2U_LIB.S9S_MB_2U(SCH_1):P5E_CPU1_PE0_TX_C_DP'<8>:
 C_SIGNAL='@s9s_mb_2u_lib.s9s_mb_2u(sch_1):p5e_cpu1_pe0_tx_c_dp(8)';
NODE_NAME     C725 1
 '@S9S_MB_2U_LIB.S9S_MB_2U(SCH_1):PAGE167_I274@PURE_QUANTA.Q_CAP_DIFFBUS(CHIPS)':
 '1': CDS_PINID='\1\';
NODE_NAME     J112 I8
 '@S9S_MB_2U_LIB.S9S_MB_2U(SCH_1):PAGE149_I75@PURE_QUANTA.CONN160_10131762101LF(CHIPS)':
 'I8': CDS_PINID='I8';
NET_NAME
'P5E_CPU1_PE0_TX_C_DP<9>'
 '@S9S_MB_2U_LIB.S9S_MB_2U(SCH_1):P5E_CPU1_PE0_TX_C_DP'<9>:
 C_SIGNAL='@s9s_mb_2u_lib.s9s_mb_2u(sch_1):p5e_cpu1_pe0_tx_c_dp(9)';
NODE_NAME     C723 1
 '@S9S_MB_2U_LIB.S9S_MB_2U(SCH_1):PAGE167_I277@PURE_QUANTA.Q_CAP_DIFFBUS(CHIPS)':
 '1': CDS_PINID='\1\';
NODE_NAME     J112 J7
 '@S9S_MB_2U_LIB.S9S_MB_2U(SCH_1):PAGE149_I75@PURE_QUANTA.CONN160_10131762101LF(CHIPS)':
 'J7': CDS_PINID='J7';
NET_NAME
'P5E_CPU1_PE0_TX_DN<0>'
 '@S9S_MB_2U_LIB.S9S_MB_2U(SCH_1):P5E_CPU1_PE0_TX_DN'<0>:
 C_SIGNAL='@s9s_mb_2u_lib.s9s_mb_2u(sch_1):p5e_cpu1_pe0_tx_dn(0)';
NODE_NAME     U1 N13
 '@S9S_MB_2U_LIB.S9S_MB_2U(SCH_1):PAGE60_I80@PURE_QUANTA.SOCKET4677_AZIF0045P001C01CS(CHIPS)':
 'PE0_TX_DN0': CDS_PINID='PE0_TX_DN0';
NODE_NAME     C740 2
 '@S9S_MB_2U_LIB.S9S_MB_2U(SCH_1):PAGE167_I229@PURE_QUANTA.Q_CAP_DIFFBUS(CHIPS)':
 '2': CDS_PINID='\2\';
NET_NAME
'P5E_CPU1_PE0_TX_DN<10>'
 '@S9S_MB_2U_LIB.S9S_MB_2U(SCH_1):P5E_CPU1_PE0_TX_DN'<10>:
 C_SIGNAL='@s9s_mb_2u_lib.s9s_mb_2u(sch_1):p5e_cpu1_pe0_tx_dn(10)';
NODE_NAME     U1 AN13
 '@S9S_MB_2U_LIB.S9S_MB_2U(SCH_1):PAGE60_I80@PURE_QUANTA.SOCKET4677_AZIF0045P001C01CS(CHIPS)':
 'PE0_TX_DN10': CDS_PINID='PE0_TX_DN10';
NODE_NAME     C720 2
 '@S9S_MB_2U_LIB.S9S_MB_2U(SCH_1):PAGE167_I279@PURE_QUANTA.Q_CAP_DIFFBUS(CHIPS)':
 '2': CDS_PINID='\2\';
NET_NAME
'P5E_CPU1_PE0_TX_DN<11>'
 '@S9S_MB_2U_LIB.S9S_MB_2U(SCH_1):P5E_CPU1_PE0_TX_DN'<11>:
 C_SIGNAL='@s9s_mb_2u_lib.s9s_mb_2u(sch_1):p5e_cpu1_pe0_tx_dn(11)';
NODE_NAME     U1 AP14
 '@S9S_MB_2U_LIB.S9S_MB_2U(SCH_1):PAGE60_I80@PURE_QUANTA.SOCKET4677_AZIF0045P001C01CS(CHIPS)':
 'PE0_TX_DN11': CDS_PINID='PE0_TX_DN11';
NODE_NAME     C718 2
 '@S9S_MB_2U_LIB.S9S_MB_2U(SCH_1):PAGE167_I281@PURE_QUANTA.Q_CAP_DIFFBUS(CHIPS)':
 '2': CDS_PINID='\2\';
NET_NAME
'P5E_CPU1_PE0_TX_DN<12>'
 '@S9S_MB_2U_LIB.S9S_MB_2U(SCH_1):P5E_CPU1_PE0_TX_DN'<12>:
 C_SIGNAL='@s9s_mb_2u_lib.s9s_mb_2u(sch_1):p5e_cpu1_pe0_tx_dn(12)';
NODE_NAME     U1 AU13
 '@S9S_MB_2U_LIB.S9S_MB_2U(SCH_1):PAGE60_I80@PURE_QUANTA.SOCKET4677_AZIF0045P001C01CS(CHIPS)':
 'PE0_TX_DN12': CDS_PINID='PE0_TX_DN12';
NODE_NAME     C716 2
 '@S9S_MB_2U_LIB.S9S_MB_2U(SCH_1):PAGE167_I283@PURE_QUANTA.Q_CAP_DIFFBUS(CHIPS)':
 '2': CDS_PINID='\2\';
NET_NAME
'P5E_CPU1_PE0_TX_DN<13>'
 '@S9S_MB_2U_LIB.S9S_MB_2U(SCH_1):P5E_CPU1_PE0_TX_DN'<13>:
 C_SIGNAL='@s9s_mb_2u_lib.s9s_mb_2u(sch_1):p5e_cpu1_pe0_tx_dn(13)';
NODE_NAME     U1 AV14
 '@S9S_MB_2U_LIB.S9S_MB_2U(SCH_1):PAGE60_I80@PURE_QUANTA.SOCKET4677_AZIF0045P001C01CS(CHIPS)':
 'PE0_TX_DN13': CDS_PINID='PE0_TX_DN13';
NODE_NAME     C714 2
 '@S9S_MB_2U_LIB.S9S_MB_2U(SCH_1):PAGE167_I295@PURE_QUANTA.Q_CAP_DIFFBUS(CHIPS)':
 '2': CDS_PINID='\2\';
NET_NAME
'P5E_CPU1_PE0_TX_DN<14>'
 '@S9S_MB_2U_LIB.S9S_MB_2U(SCH_1):P5E_CPU1_PE0_TX_DN'<14>:
 C_SIGNAL='@s9s_mb_2u_lib.s9s_mb_2u(sch_1):p5e_cpu1_pe0_tx_dn(14)';
NODE_NAME     U1 BA13
 '@S9S_MB_2U_LIB.S9S_MB_2U(SCH_1):PAGE60_I80@PURE_QUANTA.SOCKET4677_AZIF0045P001C01CS(CHIPS)':
 'PE0_TX_DN14': CDS_PINID='PE0_TX_DN14';
NODE_NAME     C712 2
 '@S9S_MB_2U_LIB.S9S_MB_2U(SCH_1):PAGE167_I296@PURE_QUANTA.Q_CAP_DIFFBUS(CHIPS)':
 '2': CDS_PINID='\2\';
NET_NAME
'P5E_CPU1_PE0_TX_DN<15>'
 '@S9S_MB_2U_LIB.S9S_MB_2U(SCH_1):P5E_CPU1_PE0_TX_DN'<15>:
 C_SIGNAL='@s9s_mb_2u_lib.s9s_mb_2u(sch_1):p5e_cpu1_pe0_tx_dn(15)';
NODE_NAME     U1 BB14
 '@S9S_MB_2U_LIB.S9S_MB_2U(SCH_1):PAGE60_I80@PURE_QUANTA.SOCKET4677_AZIF0045P001C01CS(CHIPS)':
 'PE0_TX_DN15': CDS_PINID='PE0_TX_DN15';
NODE_NAME     C710 2
 '@S9S_MB_2U_LIB.S9S_MB_2U(SCH_1):PAGE167_I299@PURE_QUANTA.Q_CAP_DIFFBUS(CHIPS)':
 '2': CDS_PINID='\2\';
NET_NAME
'P5E_CPU1_PE0_TX_DN<1>'
 '@S9S_MB_2U_LIB.S9S_MB_2U(SCH_1):P5E_CPU1_PE0_TX_DN'<1>:
 C_SIGNAL='@s9s_mb_2u_lib.s9s_mb_2u(sch_1):p5e_cpu1_pe0_tx_dn(1)';
NODE_NAME     U1 P14
 '@S9S_MB_2U_LIB.S9S_MB_2U(SCH_1):PAGE60_I80@PURE_QUANTA.SOCKET4677_AZIF0045P001C01CS(CHIPS)':
 'PE0_TX_DN1': CDS_PINID='PE0_TX_DN1';
NODE_NAME     C738 2
 '@S9S_MB_2U_LIB.S9S_MB_2U(SCH_1):PAGE167_I232@PURE_QUANTA.Q_CAP_DIFFBUS(CHIPS)':
 '2': CDS_PINID='\2\';
NET_NAME
'P5E_CPU1_PE0_TX_DN<2>'
 '@S9S_MB_2U_LIB.S9S_MB_2U(SCH_1):P5E_CPU1_PE0_TX_DN'<2>:
 C_SIGNAL='@s9s_mb_2u_lib.s9s_mb_2u(sch_1):p5e_cpu1_pe0_tx_dn(2)';
NODE_NAME     U1 U13
 '@S9S_MB_2U_LIB.S9S_MB_2U(SCH_1):PAGE60_I80@PURE_QUANTA.SOCKET4677_AZIF0045P001C01CS(CHIPS)':
 'PE0_TX_DN2': CDS_PINID='PE0_TX_DN2';
NODE_NAME     C736 2
 '@S9S_MB_2U_LIB.S9S_MB_2U(SCH_1):PAGE167_I234@PURE_QUANTA.Q_CAP_DIFFBUS(CHIPS)':
 '2': CDS_PINID='\2\';
NET_NAME
'P5E_CPU1_PE0_TX_DN<3>'
 '@S9S_MB_2U_LIB.S9S_MB_2U(SCH_1):P5E_CPU1_PE0_TX_DN'<3>:
 C_SIGNAL='@s9s_mb_2u_lib.s9s_mb_2u(sch_1):p5e_cpu1_pe0_tx_dn(3)';
NODE_NAME     U1 V14
 '@S9S_MB_2U_LIB.S9S_MB_2U(SCH_1):PAGE60_I80@PURE_QUANTA.SOCKET4677_AZIF0045P001C01CS(CHIPS)':
 'PE0_TX_DN3': CDS_PINID='PE0_TX_DN3';
NODE_NAME     C734 2
 '@S9S_MB_2U_LIB.S9S_MB_2U(SCH_1):PAGE167_I235@PURE_QUANTA.Q_CAP_DIFFBUS(CHIPS)':
 '2': CDS_PINID='\2\';
NET_NAME
'P5E_CPU1_PE0_TX_DN<4>'
 '@S9S_MB_2U_LIB.S9S_MB_2U(SCH_1):P5E_CPU1_PE0_TX_DN'<4>:
 C_SIGNAL='@s9s_mb_2u_lib.s9s_mb_2u(sch_1):p5e_cpu1_pe0_tx_dn(4)';
NODE_NAME     U1 AA13
 '@S9S_MB_2U_LIB.S9S_MB_2U(SCH_1):PAGE60_I80@PURE_QUANTA.SOCKET4677_AZIF0045P001C01CS(CHIPS)':
 'PE0_TX_DN4': CDS_PINID='PE0_TX_DN4';
NODE_NAME     C732 2
 '@S9S_MB_2U_LIB.S9S_MB_2U(SCH_1):PAGE167_I246@PURE_QUANTA.Q_CAP_DIFFBUS(CHIPS)':
 '2': CDS_PINID='\2\';
NET_NAME
'P5E_CPU1_PE0_TX_DN<5>'
 '@S9S_MB_2U_LIB.S9S_MB_2U(SCH_1):P5E_CPU1_PE0_TX_DN'<5>:
 C_SIGNAL='@s9s_mb_2u_lib.s9s_mb_2u(sch_1):p5e_cpu1_pe0_tx_dn(5)';
NODE_NAME     U1 AB14
 '@S9S_MB_2U_LIB.S9S_MB_2U(SCH_1):PAGE60_I80@PURE_QUANTA.SOCKET4677_AZIF0045P001C01CS(CHIPS)':
 'PE0_TX_DN5': CDS_PINID='PE0_TX_DN5';
NODE_NAME     C730 2
 '@S9S_MB_2U_LIB.S9S_MB_2U(SCH_1):PAGE167_I248@PURE_QUANTA.Q_CAP_DIFFBUS(CHIPS)':
 '2': CDS_PINID='\2\';
NET_NAME
'P5E_CPU1_PE0_TX_DN<6>'
 '@S9S_MB_2U_LIB.S9S_MB_2U(SCH_1):P5E_CPU1_PE0_TX_DN'<6>:
 C_SIGNAL='@s9s_mb_2u_lib.s9s_mb_2u(sch_1):p5e_cpu1_pe0_tx_dn(6)';
NODE_NAME     U1 AE13
 '@S9S_MB_2U_LIB.S9S_MB_2U(SCH_1):PAGE60_I80@PURE_QUANTA.SOCKET4677_AZIF0045P001C01CS(CHIPS)':
 'PE0_TX_DN6': CDS_PINID='PE0_TX_DN6';
NODE_NAME     C728 2
 '@S9S_MB_2U_LIB.S9S_MB_2U(SCH_1):PAGE167_I250@PURE_QUANTA.Q_CAP_DIFFBUS(CHIPS)':
 '2': CDS_PINID='\2\';
NET_NAME
'P5E_CPU1_PE0_TX_DN<7>'
 '@S9S_MB_2U_LIB.S9S_MB_2U(SCH_1):P5E_CPU1_PE0_TX_DN'<7>:
 C_SIGNAL='@s9s_mb_2u_lib.s9s_mb_2u(sch_1):p5e_cpu1_pe0_tx_dn(7)';
NODE_NAME     U1 AF14
 '@S9S_MB_2U_LIB.S9S_MB_2U(SCH_1):PAGE60_I80@PURE_QUANTA.SOCKET4677_AZIF0045P001C01CS(CHIPS)':
 'PE0_TX_DN7': CDS_PINID='PE0_TX_DN7';
NODE_NAME     C726 2
 '@S9S_MB_2U_LIB.S9S_MB_2U(SCH_1):PAGE167_I312@PURE_QUANTA.Q_CAP_DIFFBUS(CHIPS)':
 '2': CDS_PINID='\2\';
NET_NAME
'P5E_CPU1_PE0_TX_DN<8>'
 '@S9S_MB_2U_LIB.S9S_MB_2U(SCH_1):P5E_CPU1_PE0_TX_DN'<8>:
 C_SIGNAL='@s9s_mb_2u_lib.s9s_mb_2u(sch_1):p5e_cpu1_pe0_tx_dn(8)';
NODE_NAME     U1 AJ13
 '@S9S_MB_2U_LIB.S9S_MB_2U(SCH_1):PAGE60_I80@PURE_QUANTA.SOCKET4677_AZIF0045P001C01CS(CHIPS)':
 'PE0_TX_DN8': CDS_PINID='PE0_TX_DN8';
NODE_NAME     C724 2
 '@S9S_MB_2U_LIB.S9S_MB_2U(SCH_1):PAGE167_I275@PURE_QUANTA.Q_CAP_DIFFBUS(CHIPS)':
 '2': CDS_PINID='\2\';
NET_NAME
'P5E_CPU1_PE0_TX_DN<9>'
 '@S9S_MB_2U_LIB.S9S_MB_2U(SCH_1):P5E_CPU1_PE0_TX_DN'<9>:
 C_SIGNAL='@s9s_mb_2u_lib.s9s_mb_2u(sch_1):p5e_cpu1_pe0_tx_dn(9)';
NODE_NAME     U1 AK14
 '@S9S_MB_2U_LIB.S9S_MB_2U(SCH_1):PAGE60_I80@PURE_QUANTA.SOCKET4677_AZIF0045P001C01CS(CHIPS)':
 'PE0_TX_DN9': CDS_PINID='PE0_TX_DN9';
NODE_NAME     C722 2
 '@S9S_MB_2U_LIB.S9S_MB_2U(SCH_1):PAGE167_I276@PURE_QUANTA.Q_CAP_DIFFBUS(CHIPS)':
 '2': CDS_PINID='\2\';
NET_NAME
'P5E_CPU1_PE0_TX_DP<0>'
 '@S9S_MB_2U_LIB.S9S_MB_2U(SCH_1):P5E_CPU1_PE0_TX_DP'<0>:
 C_SIGNAL='@s9s_mb_2u_lib.s9s_mb_2u(sch_1):p5e_cpu1_pe0_tx_dp(0)';
NODE_NAME     U1 M14
 '@S9S_MB_2U_LIB.S9S_MB_2U(SCH_1):PAGE60_I80@PURE_QUANTA.SOCKET4677_AZIF0045P001C01CS(CHIPS)':
 'PE0_TX_DP0': CDS_PINID='PE0_TX_DP0';
NODE_NAME     C741 2
 '@S9S_MB_2U_LIB.S9S_MB_2U(SCH_1):PAGE167_I230@PURE_QUANTA.Q_CAP_DIFFBUS(CHIPS)':
 '2': CDS_PINID='\2\';
NET_NAME
'P5E_CPU1_PE0_TX_DP<10>'
 '@S9S_MB_2U_LIB.S9S_MB_2U(SCH_1):P5E_CPU1_PE0_TX_DP'<10>:
 C_SIGNAL='@s9s_mb_2u_lib.s9s_mb_2u(sch_1):p5e_cpu1_pe0_tx_dp(10)';
NODE_NAME     U1 AM14
 '@S9S_MB_2U_LIB.S9S_MB_2U(SCH_1):PAGE60_I80@PURE_QUANTA.SOCKET4677_AZIF0045P001C01CS(CHIPS)':
 'PE0_TX_DP10': CDS_PINID='PE0_TX_DP10';
NODE_NAME     C721 2
 '@S9S_MB_2U_LIB.S9S_MB_2U(SCH_1):PAGE167_I278@PURE_QUANTA.Q_CAP_DIFFBUS(CHIPS)':
 '2': CDS_PINID='\2\';
NET_NAME
'P5E_CPU1_PE0_TX_DP<11>'
 '@S9S_MB_2U_LIB.S9S_MB_2U(SCH_1):P5E_CPU1_PE0_TX_DP'<11>:
 C_SIGNAL='@s9s_mb_2u_lib.s9s_mb_2u(sch_1):p5e_cpu1_pe0_tx_dp(11)';
NODE_NAME     U1 AR15
 '@S9S_MB_2U_LIB.S9S_MB_2U(SCH_1):PAGE60_I80@PURE_QUANTA.SOCKET4677_AZIF0045P001C01CS(CHIPS)':
 'PE0_TX_DP11': CDS_PINID='PE0_TX_DP11';
NODE_NAME     C719 2
 '@S9S_MB_2U_LIB.S9S_MB_2U(SCH_1):PAGE167_I280@PURE_QUANTA.Q_CAP_DIFFBUS(CHIPS)':
 '2': CDS_PINID='\2\';
NET_NAME
'P5E_CPU1_PE0_TX_DP<12>'
 '@S9S_MB_2U_LIB.S9S_MB_2U(SCH_1):P5E_CPU1_PE0_TX_DP'<12>:
 C_SIGNAL='@s9s_mb_2u_lib.s9s_mb_2u(sch_1):p5e_cpu1_pe0_tx_dp(12)';
NODE_NAME     U1 AT14
 '@S9S_MB_2U_LIB.S9S_MB_2U(SCH_1):PAGE60_I80@PURE_QUANTA.SOCKET4677_AZIF0045P001C01CS(CHIPS)':
 'PE0_TX_DP12': CDS_PINID='PE0_TX_DP12';
NODE_NAME     C717 2
 '@S9S_MB_2U_LIB.S9S_MB_2U(SCH_1):PAGE167_I282@PURE_QUANTA.Q_CAP_DIFFBUS(CHIPS)':
 '2': CDS_PINID='\2\';
NET_NAME
'P5E_CPU1_PE0_TX_DP<13>'
 '@S9S_MB_2U_LIB.S9S_MB_2U(SCH_1):P5E_CPU1_PE0_TX_DP'<13>:
 C_SIGNAL='@s9s_mb_2u_lib.s9s_mb_2u(sch_1):p5e_cpu1_pe0_tx_dp(13)';
NODE_NAME     U1 AW15
 '@S9S_MB_2U_LIB.S9S_MB_2U(SCH_1):PAGE60_I80@PURE_QUANTA.SOCKET4677_AZIF0045P001C01CS(CHIPS)':
 'PE0_TX_DP13': CDS_PINID='PE0_TX_DP13';
NODE_NAME     C715 2
 '@S9S_MB_2U_LIB.S9S_MB_2U(SCH_1):PAGE167_I294@PURE_QUANTA.Q_CAP_DIFFBUS(CHIPS)':
 '2': CDS_PINID='\2\';
NET_NAME
'P5E_CPU1_PE0_TX_DP<14>'
 '@S9S_MB_2U_LIB.S9S_MB_2U(SCH_1):P5E_CPU1_PE0_TX_DP'<14>:
 C_SIGNAL='@s9s_mb_2u_lib.s9s_mb_2u(sch_1):p5e_cpu1_pe0_tx_dp(14)';
NODE_NAME     U1 AY14
 '@S9S_MB_2U_LIB.S9S_MB_2U(SCH_1):PAGE60_I80@PURE_QUANTA.SOCKET4677_AZIF0045P001C01CS(CHIPS)':
 'PE0_TX_DP14': CDS_PINID='PE0_TX_DP14';
NODE_NAME     C713 2
 '@S9S_MB_2U_LIB.S9S_MB_2U(SCH_1):PAGE167_I297@PURE_QUANTA.Q_CAP_DIFFBUS(CHIPS)':
 '2': CDS_PINID='\2\';
NET_NAME
'P5E_CPU1_PE0_TX_DP<15>'
 '@S9S_MB_2U_LIB.S9S_MB_2U(SCH_1):P5E_CPU1_PE0_TX_DP'<15>:
 C_SIGNAL='@s9s_mb_2u_lib.s9s_mb_2u(sch_1):p5e_cpu1_pe0_tx_dp(15)';
NODE_NAME     U1 BC15
 '@S9S_MB_2U_LIB.S9S_MB_2U(SCH_1):PAGE60_I80@PURE_QUANTA.SOCKET4677_AZIF0045P001C01CS(CHIPS)':
 'PE0_TX_DP15': CDS_PINID='PE0_TX_DP15';
NODE_NAME     C711 2
 '@S9S_MB_2U_LIB.S9S_MB_2U(SCH_1):PAGE167_I298@PURE_QUANTA.Q_CAP_DIFFBUS(CHIPS)':
 '2': CDS_PINID='\2\';
NET_NAME
'P5E_CPU1_PE0_TX_DP<1>'
 '@S9S_MB_2U_LIB.S9S_MB_2U(SCH_1):P5E_CPU1_PE0_TX_DP'<1>:
 C_SIGNAL='@s9s_mb_2u_lib.s9s_mb_2u(sch_1):p5e_cpu1_pe0_tx_dp(1)';
NODE_NAME     U1 R15
 '@S9S_MB_2U_LIB.S9S_MB_2U(SCH_1):PAGE60_I80@PURE_QUANTA.SOCKET4677_AZIF0045P001C01CS(CHIPS)':
 'PE0_TX_DP1': CDS_PINID='PE0_TX_DP1';
NODE_NAME     C739 2
 '@S9S_MB_2U_LIB.S9S_MB_2U(SCH_1):PAGE167_I231@PURE_QUANTA.Q_CAP_DIFFBUS(CHIPS)':
 '2': CDS_PINID='\2\';
NET_NAME
'P5E_CPU1_PE0_TX_DP<2>'
 '@S9S_MB_2U_LIB.S9S_MB_2U(SCH_1):P5E_CPU1_PE0_TX_DP'<2>:
 C_SIGNAL='@s9s_mb_2u_lib.s9s_mb_2u(sch_1):p5e_cpu1_pe0_tx_dp(2)';
NODE_NAME     U1 T14
 '@S9S_MB_2U_LIB.S9S_MB_2U(SCH_1):PAGE60_I80@PURE_QUANTA.SOCKET4677_AZIF0045P001C01CS(CHIPS)':
 'PE0_TX_DP2': CDS_PINID='PE0_TX_DP2';
NODE_NAME     C737 2
 '@S9S_MB_2U_LIB.S9S_MB_2U(SCH_1):PAGE167_I233@PURE_QUANTA.Q_CAP_DIFFBUS(CHIPS)':
 '2': CDS_PINID='\2\';
NET_NAME
'P5E_CPU1_PE0_TX_DP<3>'
 '@S9S_MB_2U_LIB.S9S_MB_2U(SCH_1):P5E_CPU1_PE0_TX_DP'<3>:
 C_SIGNAL='@s9s_mb_2u_lib.s9s_mb_2u(sch_1):p5e_cpu1_pe0_tx_dp(3)';
NODE_NAME     U1 W15
 '@S9S_MB_2U_LIB.S9S_MB_2U(SCH_1):PAGE60_I80@PURE_QUANTA.SOCKET4677_AZIF0045P001C01CS(CHIPS)':
 'PE0_TX_DP3': CDS_PINID='PE0_TX_DP3';
NODE_NAME     C735 2
 '@S9S_MB_2U_LIB.S9S_MB_2U(SCH_1):PAGE167_I236@PURE_QUANTA.Q_CAP_DIFFBUS(CHIPS)':
 '2': CDS_PINID='\2\';
NET_NAME
'P5E_CPU1_PE0_TX_DP<4>'
 '@S9S_MB_2U_LIB.S9S_MB_2U(SCH_1):P5E_CPU1_PE0_TX_DP'<4>:
 C_SIGNAL='@s9s_mb_2u_lib.s9s_mb_2u(sch_1):p5e_cpu1_pe0_tx_dp(4)';
NODE_NAME     U1 Y14
 '@S9S_MB_2U_LIB.S9S_MB_2U(SCH_1):PAGE60_I80@PURE_QUANTA.SOCKET4677_AZIF0045P001C01CS(CHIPS)':
 'PE0_TX_DP4': CDS_PINID='PE0_TX_DP4';
NODE_NAME     C733 2
 '@S9S_MB_2U_LIB.S9S_MB_2U(SCH_1):PAGE167_I237@PURE_QUANTA.Q_CAP_DIFFBUS(CHIPS)':
 '2': CDS_PINID='\2\';
NET_NAME
'P5E_CPU1_PE0_TX_DP<5>'
 '@S9S_MB_2U_LIB.S9S_MB_2U(SCH_1):P5E_CPU1_PE0_TX_DP'<5>:
 C_SIGNAL='@s9s_mb_2u_lib.s9s_mb_2u(sch_1):p5e_cpu1_pe0_tx_dp(5)';
NODE_NAME     U1 AC15
 '@S9S_MB_2U_LIB.S9S_MB_2U(SCH_1):PAGE60_I80@PURE_QUANTA.SOCKET4677_AZIF0045P001C01CS(CHIPS)':
 'PE0_TX_DP5': CDS_PINID='PE0_TX_DP5';
NODE_NAME     C731 2
 '@S9S_MB_2U_LIB.S9S_MB_2U(SCH_1):PAGE167_I247@PURE_QUANTA.Q_CAP_DIFFBUS(CHIPS)':
 '2': CDS_PINID='\2\';
NET_NAME
'P5E_CPU1_PE0_TX_DP<6>'
 '@S9S_MB_2U_LIB.S9S_MB_2U(SCH_1):P5E_CPU1_PE0_TX_DP'<6>:
 C_SIGNAL='@s9s_mb_2u_lib.s9s_mb_2u(sch_1):p5e_cpu1_pe0_tx_dp(6)';
NODE_NAME     U1 AD14
 '@S9S_MB_2U_LIB.S9S_MB_2U(SCH_1):PAGE60_I80@PURE_QUANTA.SOCKET4677_AZIF0045P001C01CS(CHIPS)':
 'PE0_TX_DP6': CDS_PINID='PE0_TX_DP6';
NODE_NAME     C729 2
 '@S9S_MB_2U_LIB.S9S_MB_2U(SCH_1):PAGE167_I249@PURE_QUANTA.Q_CAP_DIFFBUS(CHIPS)':
 '2': CDS_PINID='\2\';
NET_NAME
'P5E_CPU1_PE0_TX_DP<7>'
 '@S9S_MB_2U_LIB.S9S_MB_2U(SCH_1):P5E_CPU1_PE0_TX_DP'<7>:
 C_SIGNAL='@s9s_mb_2u_lib.s9s_mb_2u(sch_1):p5e_cpu1_pe0_tx_dp(7)';
NODE_NAME     U1 AG15
 '@S9S_MB_2U_LIB.S9S_MB_2U(SCH_1):PAGE60_I80@PURE_QUANTA.SOCKET4677_AZIF0045P001C01CS(CHIPS)':
 'PE0_TX_DP7': CDS_PINID='PE0_TX_DP7';
NODE_NAME     C727 2
 '@S9S_MB_2U_LIB.S9S_MB_2U(SCH_1):PAGE167_I251@PURE_QUANTA.Q_CAP_DIFFBUS(CHIPS)':
 '2': CDS_PINID='\2\';
NET_NAME
'P5E_CPU1_PE0_TX_DP<8>'
 '@S9S_MB_2U_LIB.S9S_MB_2U(SCH_1):P5E_CPU1_PE0_TX_DP'<8>:
 C_SIGNAL='@s9s_mb_2u_lib.s9s_mb_2u(sch_1):p5e_cpu1_pe0_tx_dp(8)';
NODE_NAME     U1 AH14
 '@S9S_MB_2U_LIB.S9S_MB_2U(SCH_1):PAGE60_I80@PURE_QUANTA.SOCKET4677_AZIF0045P001C01CS(CHIPS)':
 'PE0_TX_DP8': CDS_PINID='PE0_TX_DP8';
NODE_NAME     C725 2
 '@S9S_MB_2U_LIB.S9S_MB_2U(SCH_1):PAGE167_I274@PURE_QUANTA.Q_CAP_DIFFBUS(CHIPS)':
 '2': CDS_PINID='\2\';
NET_NAME
'P5E_CPU1_PE0_TX_DP<9>'
 '@S9S_MB_2U_LIB.S9S_MB_2U(SCH_1):P5E_CPU1_PE0_TX_DP'<9>:
 C_SIGNAL='@s9s_mb_2u_lib.s9s_mb_2u(sch_1):p5e_cpu1_pe0_tx_dp(9)';
NODE_NAME     U1 AL15
 '@S9S_MB_2U_LIB.S9S_MB_2U(SCH_1):PAGE60_I80@PURE_QUANTA.SOCKET4677_AZIF0045P001C01CS(CHIPS)':
 'PE0_TX_DP9': CDS_PINID='PE0_TX_DP9';
NODE_NAME     C723 2
 '@S9S_MB_2U_LIB.S9S_MB_2U(SCH_1):PAGE167_I277@PURE_QUANTA.Q_CAP_DIFFBUS(CHIPS)':
 '2': CDS_PINID='\2\';
NET_NAME
'P5E_CPU1_PE1_RX_DN<0>'
 '@S9S_MB_2U_LIB.S9S_MB_2U(SCH_1):P5E_CPU1_PE1_RX_DN'<0>:
 C_SIGNAL='@s9s_mb_2u_lib.s9s_mb_2u(sch_1):p5e_cpu1_pe1_rx_dn(0)';
NODE_NAME     U1 CP10
 '@S9S_MB_2U_LIB.S9S_MB_2U(SCH_1):PAGE60_I69@PURE_QUANTA.SOCKET4677_AZIF0045P001C01CS(CHIPS)':
 'PE1_RX_DN0': CDS_PINID='PE1_RX_DN0';
NODE_NAME     J35 A17
 '@S9S_MB_2U_LIB.S9S_MB_2U(SCH_1):PAGE146_I303@PURE_QUANTA.SCONN168_ME1016810202011(CHIPS)':
 'PERN0': CDS_PINID='PERN0';
NET_NAME
'P5E_CPU1_PE1_RX_DN<10>'
 '@S9S_MB_2U_LIB.S9S_MB_2U(SCH_1):P5E_CPU1_PE1_RX_DN'<10>:
 C_SIGNAL='@s9s_mb_2u_lib.s9s_mb_2u(sch_1):p5e_cpu1_pe1_rx_dn(10)';
NODE_NAME     U1 BP10
 '@S9S_MB_2U_LIB.S9S_MB_2U(SCH_1):PAGE60_I69@PURE_QUANTA.SOCKET4677_AZIF0045P001C01CS(CHIPS)':
 'PE1_RX_DN10': CDS_PINID='PE1_RX_DN10';
NODE_NAME     J35 A50
 '@S9S_MB_2U_LIB.S9S_MB_2U(SCH_1):PAGE146_I303@PURE_QUANTA.SCONN168_ME1016810202011(CHIPS)':
 'PERN10': CDS_PINID='PERN10';
NET_NAME
'P5E_CPU1_PE1_RX_DN<11>'
 '@S9S_MB_2U_LIB.S9S_MB_2U(SCH_1):P5E_CPU1_PE1_RX_DN'<11>:
 C_SIGNAL='@s9s_mb_2u_lib.s9s_mb_2u(sch_1):p5e_cpu1_pe1_rx_dn(11)';
NODE_NAME     U1 BL11
 '@S9S_MB_2U_LIB.S9S_MB_2U(SCH_1):PAGE60_I69@PURE_QUANTA.SOCKET4677_AZIF0045P001C01CS(CHIPS)':
 'PE1_RX_DN11': CDS_PINID='PE1_RX_DN11';
NODE_NAME     J35 A53
 '@S9S_MB_2U_LIB.S9S_MB_2U(SCH_1):PAGE146_I303@PURE_QUANTA.SCONN168_ME1016810202011(CHIPS)':
 'PERN11': CDS_PINID='PERN11';
NET_NAME
'P5E_CPU1_PE1_RX_DN<12>'
 '@S9S_MB_2U_LIB.S9S_MB_2U(SCH_1):P5E_CPU1_PE1_RX_DN'<12>:
 C_SIGNAL='@s9s_mb_2u_lib.s9s_mb_2u(sch_1):p5e_cpu1_pe1_rx_dn(12)';
NODE_NAME     U1 BK10
 '@S9S_MB_2U_LIB.S9S_MB_2U(SCH_1):PAGE60_I69@PURE_QUANTA.SOCKET4677_AZIF0045P001C01CS(CHIPS)':
 'PE1_RX_DN12': CDS_PINID='PE1_RX_DN12';
NODE_NAME     J35 A56
 '@S9S_MB_2U_LIB.S9S_MB_2U(SCH_1):PAGE146_I303@PURE_QUANTA.SCONN168_ME1016810202011(CHIPS)':
 'PERN12': CDS_PINID='PERN12';
NET_NAME
'P5E_CPU1_PE1_RX_DN<13>'
 '@S9S_MB_2U_LIB.S9S_MB_2U(SCH_1):P5E_CPU1_PE1_RX_DN'<13>:
 C_SIGNAL='@s9s_mb_2u_lib.s9s_mb_2u(sch_1):p5e_cpu1_pe1_rx_dn(13)';
NODE_NAME     U1 BG11
 '@S9S_MB_2U_LIB.S9S_MB_2U(SCH_1):PAGE60_I69@PURE_QUANTA.SOCKET4677_AZIF0045P001C01CS(CHIPS)':
 'PE1_RX_DN13': CDS_PINID='PE1_RX_DN13';
NODE_NAME     J35 A59
 '@S9S_MB_2U_LIB.S9S_MB_2U(SCH_1):PAGE146_I303@PURE_QUANTA.SCONN168_ME1016810202011(CHIPS)':
 'PERN13': CDS_PINID='PERN13';
NET_NAME
'P5E_CPU1_PE1_RX_DN<14>'
 '@S9S_MB_2U_LIB.S9S_MB_2U(SCH_1):P5E_CPU1_PE1_RX_DN'<14>:
 C_SIGNAL='@s9s_mb_2u_lib.s9s_mb_2u(sch_1):p5e_cpu1_pe1_rx_dn(14)';
NODE_NAME     U1 BF10
 '@S9S_MB_2U_LIB.S9S_MB_2U(SCH_1):PAGE60_I69@PURE_QUANTA.SOCKET4677_AZIF0045P001C01CS(CHIPS)':
 'PE1_RX_DN14': CDS_PINID='PE1_RX_DN14';
NODE_NAME     J35 A62
 '@S9S_MB_2U_LIB.S9S_MB_2U(SCH_1):PAGE146_I303@PURE_QUANTA.SCONN168_ME1016810202011(CHIPS)':
 'PERN14': CDS_PINID='PERN14';
NET_NAME
'P5E_CPU1_PE1_RX_DN<15>'
 '@S9S_MB_2U_LIB.S9S_MB_2U(SCH_1):P5E_CPU1_PE1_RX_DN'<15>:
 C_SIGNAL='@s9s_mb_2u_lib.s9s_mb_2u(sch_1):p5e_cpu1_pe1_rx_dn(15)';
NODE_NAME     U1 BC11
 '@S9S_MB_2U_LIB.S9S_MB_2U(SCH_1):PAGE60_I69@PURE_QUANTA.SOCKET4677_AZIF0045P001C01CS(CHIPS)':
 'PE1_RX_DN15': CDS_PINID='PE1_RX_DN15';
NODE_NAME     J35 A65
 '@S9S_MB_2U_LIB.S9S_MB_2U(SCH_1):PAGE146_I303@PURE_QUANTA.SCONN168_ME1016810202011(CHIPS)':
 'PERN15': CDS_PINID='PERN15';
NET_NAME
'P5E_CPU1_PE1_RX_DN<1>'
 '@S9S_MB_2U_LIB.S9S_MB_2U(SCH_1):P5E_CPU1_PE1_RX_DN'<1>:
 C_SIGNAL='@s9s_mb_2u_lib.s9s_mb_2u(sch_1):p5e_cpu1_pe1_rx_dn(1)';
NODE_NAME     U1 CL11
 '@S9S_MB_2U_LIB.S9S_MB_2U(SCH_1):PAGE60_I69@PURE_QUANTA.SOCKET4677_AZIF0045P001C01CS(CHIPS)':
 'PE1_RX_DN1': CDS_PINID='PE1_RX_DN1';
NODE_NAME     J35 A20
 '@S9S_MB_2U_LIB.S9S_MB_2U(SCH_1):PAGE146_I303@PURE_QUANTA.SCONN168_ME1016810202011(CHIPS)':
 'PERN1': CDS_PINID='PERN1';
NET_NAME
'P5E_CPU1_PE1_RX_DN<2>'
 '@S9S_MB_2U_LIB.S9S_MB_2U(SCH_1):P5E_CPU1_PE1_RX_DN'<2>:
 C_SIGNAL='@s9s_mb_2u_lib.s9s_mb_2u(sch_1):p5e_cpu1_pe1_rx_dn(2)';
NODE_NAME     U1 CK10
 '@S9S_MB_2U_LIB.S9S_MB_2U(SCH_1):PAGE60_I69@PURE_QUANTA.SOCKET4677_AZIF0045P001C01CS(CHIPS)':
 'PE1_RX_DN2': CDS_PINID='PE1_RX_DN2';
NODE_NAME     J35 A23
 '@S9S_MB_2U_LIB.S9S_MB_2U(SCH_1):PAGE146_I303@PURE_QUANTA.SCONN168_ME1016810202011(CHIPS)':
 'PERN2': CDS_PINID='PERN2';
NET_NAME
'P5E_CPU1_PE1_RX_DN<3>'
 '@S9S_MB_2U_LIB.S9S_MB_2U(SCH_1):P5E_CPU1_PE1_RX_DN'<3>:
 C_SIGNAL='@s9s_mb_2u_lib.s9s_mb_2u(sch_1):p5e_cpu1_pe1_rx_dn(3)';
NODE_NAME     U1 CG11
 '@S9S_MB_2U_LIB.S9S_MB_2U(SCH_1):PAGE60_I69@PURE_QUANTA.SOCKET4677_AZIF0045P001C01CS(CHIPS)':
 'PE1_RX_DN3': CDS_PINID='PE1_RX_DN3';
NODE_NAME     J35 A26
 '@S9S_MB_2U_LIB.S9S_MB_2U(SCH_1):PAGE146_I303@PURE_QUANTA.SCONN168_ME1016810202011(CHIPS)':
 'PERN3': CDS_PINID='PERN3';
NET_NAME
'P5E_CPU1_PE1_RX_DN<4>'
 '@S9S_MB_2U_LIB.S9S_MB_2U(SCH_1):P5E_CPU1_PE1_RX_DN'<4>:
 C_SIGNAL='@s9s_mb_2u_lib.s9s_mb_2u(sch_1):p5e_cpu1_pe1_rx_dn(4)';
NODE_NAME     U1 CF10
 '@S9S_MB_2U_LIB.S9S_MB_2U(SCH_1):PAGE60_I69@PURE_QUANTA.SOCKET4677_AZIF0045P001C01CS(CHIPS)':
 'PE1_RX_DN4': CDS_PINID='PE1_RX_DN4';
NODE_NAME     J35 A30
 '@S9S_MB_2U_LIB.S9S_MB_2U(SCH_1):PAGE146_I303@PURE_QUANTA.SCONN168_ME1016810202011(CHIPS)':
 'PERN4': CDS_PINID='PERN4';
NET_NAME
'P5E_CPU1_PE1_RX_DN<5>'
 '@S9S_MB_2U_LIB.S9S_MB_2U(SCH_1):P5E_CPU1_PE1_RX_DN'<5>:
 C_SIGNAL='@s9s_mb_2u_lib.s9s_mb_2u(sch_1):p5e_cpu1_pe1_rx_dn(5)';
NODE_NAME     U1 CC11
 '@S9S_MB_2U_LIB.S9S_MB_2U(SCH_1):PAGE60_I69@PURE_QUANTA.SOCKET4677_AZIF0045P001C01CS(CHIPS)':
 'PE1_RX_DN5': CDS_PINID='PE1_RX_DN5';
NODE_NAME     J35 A33
 '@S9S_MB_2U_LIB.S9S_MB_2U(SCH_1):PAGE146_I303@PURE_QUANTA.SCONN168_ME1016810202011(CHIPS)':
 'PERN5': CDS_PINID='PERN5';
NET_NAME
'P5E_CPU1_PE1_RX_DN<6>'
 '@S9S_MB_2U_LIB.S9S_MB_2U(SCH_1):P5E_CPU1_PE1_RX_DN'<6>:
 C_SIGNAL='@s9s_mb_2u_lib.s9s_mb_2u(sch_1):p5e_cpu1_pe1_rx_dn(6)';
NODE_NAME     U1 CB10
 '@S9S_MB_2U_LIB.S9S_MB_2U(SCH_1):PAGE60_I69@PURE_QUANTA.SOCKET4677_AZIF0045P001C01CS(CHIPS)':
 'PE1_RX_DN6': CDS_PINID='PE1_RX_DN6';
NODE_NAME     J35 A36
 '@S9S_MB_2U_LIB.S9S_MB_2U(SCH_1):PAGE146_I303@PURE_QUANTA.SCONN168_ME1016810202011(CHIPS)':
 'PERN6': CDS_PINID='PERN6';
NET_NAME
'P5E_CPU1_PE1_RX_DN<7>'
 '@S9S_MB_2U_LIB.S9S_MB_2U(SCH_1):P5E_CPU1_PE1_RX_DN'<7>:
 C_SIGNAL='@s9s_mb_2u_lib.s9s_mb_2u(sch_1):p5e_cpu1_pe1_rx_dn(7)';
NODE_NAME     U1 BW11
 '@S9S_MB_2U_LIB.S9S_MB_2U(SCH_1):PAGE60_I69@PURE_QUANTA.SOCKET4677_AZIF0045P001C01CS(CHIPS)':
 'PE1_RX_DN7': CDS_PINID='PE1_RX_DN7';
NODE_NAME     J35 A39
 '@S9S_MB_2U_LIB.S9S_MB_2U(SCH_1):PAGE146_I303@PURE_QUANTA.SCONN168_ME1016810202011(CHIPS)':
 'PERN7': CDS_PINID='PERN7';
NET_NAME
'P5E_CPU1_PE1_RX_DN<8>'
 '@S9S_MB_2U_LIB.S9S_MB_2U(SCH_1):P5E_CPU1_PE1_RX_DN'<8>:
 C_SIGNAL='@s9s_mb_2u_lib.s9s_mb_2u(sch_1):p5e_cpu1_pe1_rx_dn(8)';
NODE_NAME     U1 BV10
 '@S9S_MB_2U_LIB.S9S_MB_2U(SCH_1):PAGE60_I69@PURE_QUANTA.SOCKET4677_AZIF0045P001C01CS(CHIPS)':
 'PE1_RX_DN8': CDS_PINID='PE1_RX_DN8';
NODE_NAME     J35 A44
 '@S9S_MB_2U_LIB.S9S_MB_2U(SCH_1):PAGE146_I303@PURE_QUANTA.SCONN168_ME1016810202011(CHIPS)':
 'PERN8': CDS_PINID='PERN8';
NET_NAME
'P5E_CPU1_PE1_RX_DN<9>'
 '@S9S_MB_2U_LIB.S9S_MB_2U(SCH_1):P5E_CPU1_PE1_RX_DN'<9>:
 C_SIGNAL='@s9s_mb_2u_lib.s9s_mb_2u(sch_1):p5e_cpu1_pe1_rx_dn(9)';
NODE_NAME     U1 BR11
 '@S9S_MB_2U_LIB.S9S_MB_2U(SCH_1):PAGE60_I69@PURE_QUANTA.SOCKET4677_AZIF0045P001C01CS(CHIPS)':
 'PE1_RX_DN9': CDS_PINID='PE1_RX_DN9';
NODE_NAME     J35 A47
 '@S9S_MB_2U_LIB.S9S_MB_2U(SCH_1):PAGE146_I303@PURE_QUANTA.SCONN168_ME1016810202011(CHIPS)':
 'PERN9': CDS_PINID='PERN9';
NET_NAME
'P5E_CPU1_PE1_RX_DP<0>'
 '@S9S_MB_2U_LIB.S9S_MB_2U(SCH_1):P5E_CPU1_PE1_RX_DP'<0>:
 C_SIGNAL='@s9s_mb_2u_lib.s9s_mb_2u(sch_1):p5e_cpu1_pe1_rx_dp(0)';
NODE_NAME     U1 CN9
 '@S9S_MB_2U_LIB.S9S_MB_2U(SCH_1):PAGE60_I69@PURE_QUANTA.SOCKET4677_AZIF0045P001C01CS(CHIPS)':
 'PE1_RX_DP0': CDS_PINID='PE1_RX_DP0';
NODE_NAME     J35 A18
 '@S9S_MB_2U_LIB.S9S_MB_2U(SCH_1):PAGE146_I303@PURE_QUANTA.SCONN168_ME1016810202011(CHIPS)':
 'PERP0': CDS_PINID='PERP0';
NET_NAME
'P5E_CPU1_PE1_RX_DP<10>'
 '@S9S_MB_2U_LIB.S9S_MB_2U(SCH_1):P5E_CPU1_PE1_RX_DP'<10>:
 C_SIGNAL='@s9s_mb_2u_lib.s9s_mb_2u(sch_1):p5e_cpu1_pe1_rx_dp(10)';
NODE_NAME     U1 BN9
 '@S9S_MB_2U_LIB.S9S_MB_2U(SCH_1):PAGE60_I69@PURE_QUANTA.SOCKET4677_AZIF0045P001C01CS(CHIPS)':
 'PE1_RX_DP10': CDS_PINID='PE1_RX_DP10';
NODE_NAME     J35 A51
 '@S9S_MB_2U_LIB.S9S_MB_2U(SCH_1):PAGE146_I303@PURE_QUANTA.SCONN168_ME1016810202011(CHIPS)':
 'PERP10': CDS_PINID='PERP10';
NET_NAME
'P5E_CPU1_PE1_RX_DP<11>'
 '@S9S_MB_2U_LIB.S9S_MB_2U(SCH_1):P5E_CPU1_PE1_RX_DP'<11>:
 C_SIGNAL='@s9s_mb_2u_lib.s9s_mb_2u(sch_1):p5e_cpu1_pe1_rx_dp(11)';
NODE_NAME     U1 BM10
 '@S9S_MB_2U_LIB.S9S_MB_2U(SCH_1):PAGE60_I69@PURE_QUANTA.SOCKET4677_AZIF0045P001C01CS(CHIPS)':
 'PE1_RX_DP11': CDS_PINID='PE1_RX_DP11';
NODE_NAME     J35 A54
 '@S9S_MB_2U_LIB.S9S_MB_2U(SCH_1):PAGE146_I303@PURE_QUANTA.SCONN168_ME1016810202011(CHIPS)':
 'PERP11': CDS_PINID='PERP11';
NET_NAME
'P5E_CPU1_PE1_RX_DP<12>'
 '@S9S_MB_2U_LIB.S9S_MB_2U(SCH_1):P5E_CPU1_PE1_RX_DP'<12>:
 C_SIGNAL='@s9s_mb_2u_lib.s9s_mb_2u(sch_1):p5e_cpu1_pe1_rx_dp(12)';
NODE_NAME     U1 BJ9
 '@S9S_MB_2U_LIB.S9S_MB_2U(SCH_1):PAGE60_I69@PURE_QUANTA.SOCKET4677_AZIF0045P001C01CS(CHIPS)':
 'PE1_RX_DP12': CDS_PINID='PE1_RX_DP12';
NODE_NAME     J35 A57
 '@S9S_MB_2U_LIB.S9S_MB_2U(SCH_1):PAGE146_I303@PURE_QUANTA.SCONN168_ME1016810202011(CHIPS)':
 'PERP12': CDS_PINID='PERP12';
NET_NAME
'P5E_CPU1_PE1_RX_DP<13>'
 '@S9S_MB_2U_LIB.S9S_MB_2U(SCH_1):P5E_CPU1_PE1_RX_DP'<13>:
 C_SIGNAL='@s9s_mb_2u_lib.s9s_mb_2u(sch_1):p5e_cpu1_pe1_rx_dp(13)';
NODE_NAME     U1 BH10
 '@S9S_MB_2U_LIB.S9S_MB_2U(SCH_1):PAGE60_I69@PURE_QUANTA.SOCKET4677_AZIF0045P001C01CS(CHIPS)':
 'PE1_RX_DP13': CDS_PINID='PE1_RX_DP13';
NODE_NAME     J35 A60
 '@S9S_MB_2U_LIB.S9S_MB_2U(SCH_1):PAGE146_I303@PURE_QUANTA.SCONN168_ME1016810202011(CHIPS)':
 'PERP13': CDS_PINID='PERP13';
NET_NAME
'P5E_CPU1_PE1_RX_DP<14>'
 '@S9S_MB_2U_LIB.S9S_MB_2U(SCH_1):P5E_CPU1_PE1_RX_DP'<14>:
 C_SIGNAL='@s9s_mb_2u_lib.s9s_mb_2u(sch_1):p5e_cpu1_pe1_rx_dp(14)';
NODE_NAME     U1 BE9
 '@S9S_MB_2U_LIB.S9S_MB_2U(SCH_1):PAGE60_I69@PURE_QUANTA.SOCKET4677_AZIF0045P001C01CS(CHIPS)':
 'PE1_RX_DP14': CDS_PINID='PE1_RX_DP14';
NODE_NAME     J35 A63
 '@S9S_MB_2U_LIB.S9S_MB_2U(SCH_1):PAGE146_I303@PURE_QUANTA.SCONN168_ME1016810202011(CHIPS)':
 'PERP14': CDS_PINID='PERP14';
NET_NAME
'P5E_CPU1_PE1_RX_DP<15>'
 '@S9S_MB_2U_LIB.S9S_MB_2U(SCH_1):P5E_CPU1_PE1_RX_DP'<15>:
 C_SIGNAL='@s9s_mb_2u_lib.s9s_mb_2u(sch_1):p5e_cpu1_pe1_rx_dp(15)';
NODE_NAME     U1 BD10
 '@S9S_MB_2U_LIB.S9S_MB_2U(SCH_1):PAGE60_I69@PURE_QUANTA.SOCKET4677_AZIF0045P001C01CS(CHIPS)':
 'PE1_RX_DP15': CDS_PINID='PE1_RX_DP15';
NODE_NAME     J35 A66
 '@S9S_MB_2U_LIB.S9S_MB_2U(SCH_1):PAGE146_I303@PURE_QUANTA.SCONN168_ME1016810202011(CHIPS)':
 'PERP15': CDS_PINID='PERP15';
NET_NAME
'P5E_CPU1_PE1_RX_DP<1>'
 '@S9S_MB_2U_LIB.S9S_MB_2U(SCH_1):P5E_CPU1_PE1_RX_DP'<1>:
 C_SIGNAL='@s9s_mb_2u_lib.s9s_mb_2u(sch_1):p5e_cpu1_pe1_rx_dp(1)';
NODE_NAME     U1 CM10
 '@S9S_MB_2U_LIB.S9S_MB_2U(SCH_1):PAGE60_I69@PURE_QUANTA.SOCKET4677_AZIF0045P001C01CS(CHIPS)':
 'PE1_RX_DP1': CDS_PINID='PE1_RX_DP1';
NODE_NAME     J35 A21
 '@S9S_MB_2U_LIB.S9S_MB_2U(SCH_1):PAGE146_I303@PURE_QUANTA.SCONN168_ME1016810202011(CHIPS)':
 'PERP1': CDS_PINID='PERP1';
NET_NAME
'P5E_CPU1_PE1_RX_DP<2>'
 '@S9S_MB_2U_LIB.S9S_MB_2U(SCH_1):P5E_CPU1_PE1_RX_DP'<2>:
 C_SIGNAL='@s9s_mb_2u_lib.s9s_mb_2u(sch_1):p5e_cpu1_pe1_rx_dp(2)';
NODE_NAME     U1 CJ9
 '@S9S_MB_2U_LIB.S9S_MB_2U(SCH_1):PAGE60_I69@PURE_QUANTA.SOCKET4677_AZIF0045P001C01CS(CHIPS)':
 'PE1_RX_DP2': CDS_PINID='PE1_RX_DP2';
NODE_NAME     J35 A24
 '@S9S_MB_2U_LIB.S9S_MB_2U(SCH_1):PAGE146_I303@PURE_QUANTA.SCONN168_ME1016810202011(CHIPS)':
 'PERP2': CDS_PINID='PERP2';
NET_NAME
'P5E_CPU1_PE1_RX_DP<3>'
 '@S9S_MB_2U_LIB.S9S_MB_2U(SCH_1):P5E_CPU1_PE1_RX_DP'<3>:
 C_SIGNAL='@s9s_mb_2u_lib.s9s_mb_2u(sch_1):p5e_cpu1_pe1_rx_dp(3)';
NODE_NAME     U1 CH10
 '@S9S_MB_2U_LIB.S9S_MB_2U(SCH_1):PAGE60_I69@PURE_QUANTA.SOCKET4677_AZIF0045P001C01CS(CHIPS)':
 'PE1_RX_DP3': CDS_PINID='PE1_RX_DP3';
NODE_NAME     J35 A27
 '@S9S_MB_2U_LIB.S9S_MB_2U(SCH_1):PAGE146_I303@PURE_QUANTA.SCONN168_ME1016810202011(CHIPS)':
 'PERP3': CDS_PINID='PERP3';
NET_NAME
'P5E_CPU1_PE1_RX_DP<4>'
 '@S9S_MB_2U_LIB.S9S_MB_2U(SCH_1):P5E_CPU1_PE1_RX_DP'<4>:
 C_SIGNAL='@s9s_mb_2u_lib.s9s_mb_2u(sch_1):p5e_cpu1_pe1_rx_dp(4)';
NODE_NAME     U1 CE9
 '@S9S_MB_2U_LIB.S9S_MB_2U(SCH_1):PAGE60_I69@PURE_QUANTA.SOCKET4677_AZIF0045P001C01CS(CHIPS)':
 'PE1_RX_DP4': CDS_PINID='PE1_RX_DP4';
NODE_NAME     J35 A31
 '@S9S_MB_2U_LIB.S9S_MB_2U(SCH_1):PAGE146_I303@PURE_QUANTA.SCONN168_ME1016810202011(CHIPS)':
 'PERP4': CDS_PINID='PERP4';
NET_NAME
'P5E_CPU1_PE1_RX_DP<5>'
 '@S9S_MB_2U_LIB.S9S_MB_2U(SCH_1):P5E_CPU1_PE1_RX_DP'<5>:
 C_SIGNAL='@s9s_mb_2u_lib.s9s_mb_2u(sch_1):p5e_cpu1_pe1_rx_dp(5)';
NODE_NAME     U1 CD10
 '@S9S_MB_2U_LIB.S9S_MB_2U(SCH_1):PAGE60_I69@PURE_QUANTA.SOCKET4677_AZIF0045P001C01CS(CHIPS)':
 'PE1_RX_DP5': CDS_PINID='PE1_RX_DP5';
NODE_NAME     J35 A34
 '@S9S_MB_2U_LIB.S9S_MB_2U(SCH_1):PAGE146_I303@PURE_QUANTA.SCONN168_ME1016810202011(CHIPS)':
 'PERP5': CDS_PINID='PERP5';
NET_NAME
'P5E_CPU1_PE1_RX_DP<6>'
 '@S9S_MB_2U_LIB.S9S_MB_2U(SCH_1):P5E_CPU1_PE1_RX_DP'<6>:
 C_SIGNAL='@s9s_mb_2u_lib.s9s_mb_2u(sch_1):p5e_cpu1_pe1_rx_dp(6)';
NODE_NAME     U1 CA9
 '@S9S_MB_2U_LIB.S9S_MB_2U(SCH_1):PAGE60_I69@PURE_QUANTA.SOCKET4677_AZIF0045P001C01CS(CHIPS)':
 'PE1_RX_DP6': CDS_PINID='PE1_RX_DP6';
NODE_NAME     J35 A37
 '@S9S_MB_2U_LIB.S9S_MB_2U(SCH_1):PAGE146_I303@PURE_QUANTA.SCONN168_ME1016810202011(CHIPS)':
 'PERP6': CDS_PINID='PERP6';
NET_NAME
'P5E_CPU1_PE1_RX_DP<7>'
 '@S9S_MB_2U_LIB.S9S_MB_2U(SCH_1):P5E_CPU1_PE1_RX_DP'<7>:
 C_SIGNAL='@s9s_mb_2u_lib.s9s_mb_2u(sch_1):p5e_cpu1_pe1_rx_dp(7)';
NODE_NAME     U1 BY10
 '@S9S_MB_2U_LIB.S9S_MB_2U(SCH_1):PAGE60_I69@PURE_QUANTA.SOCKET4677_AZIF0045P001C01CS(CHIPS)':
 'PE1_RX_DP7': CDS_PINID='PE1_RX_DP7';
NODE_NAME     J35 A40
 '@S9S_MB_2U_LIB.S9S_MB_2U(SCH_1):PAGE146_I303@PURE_QUANTA.SCONN168_ME1016810202011(CHIPS)':
 'PERP7': CDS_PINID='PERP7';
NET_NAME
'P5E_CPU1_PE1_RX_DP<8>'
 '@S9S_MB_2U_LIB.S9S_MB_2U(SCH_1):P5E_CPU1_PE1_RX_DP'<8>:
 C_SIGNAL='@s9s_mb_2u_lib.s9s_mb_2u(sch_1):p5e_cpu1_pe1_rx_dp(8)';
NODE_NAME     U1 BU9
 '@S9S_MB_2U_LIB.S9S_MB_2U(SCH_1):PAGE60_I69@PURE_QUANTA.SOCKET4677_AZIF0045P001C01CS(CHIPS)':
 'PE1_RX_DP8': CDS_PINID='PE1_RX_DP8';
NODE_NAME     J35 A45
 '@S9S_MB_2U_LIB.S9S_MB_2U(SCH_1):PAGE146_I303@PURE_QUANTA.SCONN168_ME1016810202011(CHIPS)':
 'PERP8': CDS_PINID='PERP8';
NET_NAME
'P5E_CPU1_PE1_RX_DP<9>'
 '@S9S_MB_2U_LIB.S9S_MB_2U(SCH_1):P5E_CPU1_PE1_RX_DP'<9>:
 C_SIGNAL='@s9s_mb_2u_lib.s9s_mb_2u(sch_1):p5e_cpu1_pe1_rx_dp(9)';
NODE_NAME     U1 BT10
 '@S9S_MB_2U_LIB.S9S_MB_2U(SCH_1):PAGE60_I69@PURE_QUANTA.SOCKET4677_AZIF0045P001C01CS(CHIPS)':
 'PE1_RX_DP9': CDS_PINID='PE1_RX_DP9';
NODE_NAME     J35 A48
 '@S9S_MB_2U_LIB.S9S_MB_2U(SCH_1):PAGE146_I303@PURE_QUANTA.SCONN168_ME1016810202011(CHIPS)':
 'PERP9': CDS_PINID='PERP9';
NET_NAME
'P5E_CPU1_PE1_TX_C_DN<0>'
 '@S9S_MB_2U_LIB.S9S_MB_2U(SCH_1):P5E_CPU1_PE1_TX_C_DN'<0>:
 C_SIGNAL='@s9s_mb_2u_lib.s9s_mb_2u(sch_1):p5e_cpu1_pe1_tx_c_dn(0)';
NODE_NAME     C836 1
 '@S9S_MB_2U_LIB.S9S_MB_2U(SCH_1):PAGE166_I333@PURE_QUANTA.Q_CAP_DIFFBUS(CHIPS)':
 '1': CDS_PINID='\1\';
NODE_NAME     J35 B18
 '@S9S_MB_2U_LIB.S9S_MB_2U(SCH_1):PAGE146_I303@PURE_QUANTA.SCONN168_ME1016810202011(CHIPS)':
 'PETP0': CDS_PINID='PETP0';
NET_NAME
'P5E_CPU1_PE1_TX_C_DN<10>'
 '@S9S_MB_2U_LIB.S9S_MB_2U(SCH_1):P5E_CPU1_PE1_TX_C_DN'<10>:
 C_SIGNAL='@s9s_mb_2u_lib.s9s_mb_2u(sch_1):p5e_cpu1_pe1_tx_c_dn(10)';
NODE_NAME     C816 1
 '@S9S_MB_2U_LIB.S9S_MB_2U(SCH_1):PAGE166_I368@PURE_QUANTA.Q_CAP_DIFFBUS(CHIPS)':
 '1': CDS_PINID='\1\';
NODE_NAME     J35 B51
 '@S9S_MB_2U_LIB.S9S_MB_2U(SCH_1):PAGE146_I303@PURE_QUANTA.SCONN168_ME1016810202011(CHIPS)':
 'PETP10': CDS_PINID='PETP10';
NET_NAME
'P5E_CPU1_PE1_TX_C_DN<11>'
 '@S9S_MB_2U_LIB.S9S_MB_2U(SCH_1):P5E_CPU1_PE1_TX_C_DN'<11>:
 C_SIGNAL='@s9s_mb_2u_lib.s9s_mb_2u(sch_1):p5e_cpu1_pe1_tx_c_dn(11)';
NODE_NAME     C814 1
 '@S9S_MB_2U_LIB.S9S_MB_2U(SCH_1):PAGE166_I370@PURE_QUANTA.Q_CAP_DIFFBUS(CHIPS)':
 '1': CDS_PINID='\1\';
NODE_NAME     J35 B53
 '@S9S_MB_2U_LIB.S9S_MB_2U(SCH_1):PAGE146_I303@PURE_QUANTA.SCONN168_ME1016810202011(CHIPS)':
 'PETN11': CDS_PINID='PETN11';
NET_NAME
'P5E_CPU1_PE1_TX_C_DN<12>'
 '@S9S_MB_2U_LIB.S9S_MB_2U(SCH_1):P5E_CPU1_PE1_TX_C_DN'<12>:
 C_SIGNAL='@s9s_mb_2u_lib.s9s_mb_2u(sch_1):p5e_cpu1_pe1_tx_c_dn(12)';
NODE_NAME     C812 1
 '@S9S_MB_2U_LIB.S9S_MB_2U(SCH_1):PAGE166_I371@PURE_QUANTA.Q_CAP_DIFFBUS(CHIPS)':
 '1': CDS_PINID='\1\';
NODE_NAME     J35 B57
 '@S9S_MB_2U_LIB.S9S_MB_2U(SCH_1):PAGE146_I303@PURE_QUANTA.SCONN168_ME1016810202011(CHIPS)':
 'PETP12': CDS_PINID='PETP12';
NET_NAME
'P5E_CPU1_PE1_TX_C_DN<13>'
 '@S9S_MB_2U_LIB.S9S_MB_2U(SCH_1):P5E_CPU1_PE1_TX_C_DN'<13>:
 C_SIGNAL='@s9s_mb_2u_lib.s9s_mb_2u(sch_1):p5e_cpu1_pe1_tx_c_dn(13)';
NODE_NAME     C810 1
 '@S9S_MB_2U_LIB.S9S_MB_2U(SCH_1):PAGE166_I374@PURE_QUANTA.Q_CAP_DIFFBUS(CHIPS)':
 '1': CDS_PINID='\1\';
NODE_NAME     J35 B59
 '@S9S_MB_2U_LIB.S9S_MB_2U(SCH_1):PAGE146_I303@PURE_QUANTA.SCONN168_ME1016810202011(CHIPS)':
 'PETN13': CDS_PINID='PETN13';
NET_NAME
'P5E_CPU1_PE1_TX_C_DN<14>'
 '@S9S_MB_2U_LIB.S9S_MB_2U(SCH_1):P5E_CPU1_PE1_TX_C_DN'<14>:
 C_SIGNAL='@s9s_mb_2u_lib.s9s_mb_2u(sch_1):p5e_cpu1_pe1_tx_c_dn(14)';
NODE_NAME     C808 1
 '@S9S_MB_2U_LIB.S9S_MB_2U(SCH_1):PAGE166_I376@PURE_QUANTA.Q_CAP_DIFFBUS(CHIPS)':
 '1': CDS_PINID='\1\';
NODE_NAME     J35 B63
 '@S9S_MB_2U_LIB.S9S_MB_2U(SCH_1):PAGE146_I303@PURE_QUANTA.SCONN168_ME1016810202011(CHIPS)':
 'PETP14': CDS_PINID='PETP14';
NET_NAME
'P5E_CPU1_PE1_TX_C_DN<15>'
 '@S9S_MB_2U_LIB.S9S_MB_2U(SCH_1):P5E_CPU1_PE1_TX_C_DN'<15>:
 C_SIGNAL='@s9s_mb_2u_lib.s9s_mb_2u(sch_1):p5e_cpu1_pe1_tx_c_dn(15)';
NODE_NAME     C806 1
 '@S9S_MB_2U_LIB.S9S_MB_2U(SCH_1):PAGE166_I377@PURE_QUANTA.Q_CAP_DIFFBUS(CHIPS)':
 '1': CDS_PINID='\1\';
NODE_NAME     J35 B65
 '@S9S_MB_2U_LIB.S9S_MB_2U(SCH_1):PAGE146_I303@PURE_QUANTA.SCONN168_ME1016810202011(CHIPS)':
 'PETN15': CDS_PINID='PETN15';
NET_NAME
'P5E_CPU1_PE1_TX_C_DN<1>'
 '@S9S_MB_2U_LIB.S9S_MB_2U(SCH_1):P5E_CPU1_PE1_TX_C_DN'<1>:
 C_SIGNAL='@s9s_mb_2u_lib.s9s_mb_2u(sch_1):p5e_cpu1_pe1_tx_c_dn(1)';
NODE_NAME     C834 1
 '@S9S_MB_2U_LIB.S9S_MB_2U(SCH_1):PAGE166_I335@PURE_QUANTA.Q_CAP_DIFFBUS(CHIPS)':
 '1': CDS_PINID='\1\';
NODE_NAME     J35 B20
 '@S9S_MB_2U_LIB.S9S_MB_2U(SCH_1):PAGE146_I303@PURE_QUANTA.SCONN168_ME1016810202011(CHIPS)':
 'PETN1': CDS_PINID='PETN1';
NET_NAME
'P5E_CPU1_PE1_TX_C_DN<2>'
 '@S9S_MB_2U_LIB.S9S_MB_2U(SCH_1):P5E_CPU1_PE1_TX_C_DN'<2>:
 C_SIGNAL='@s9s_mb_2u_lib.s9s_mb_2u(sch_1):p5e_cpu1_pe1_tx_c_dn(2)';
NODE_NAME     C832 1
 '@S9S_MB_2U_LIB.S9S_MB_2U(SCH_1):PAGE166_I338@PURE_QUANTA.Q_CAP_DIFFBUS(CHIPS)':
 '1': CDS_PINID='\1\';
NODE_NAME     J35 B24
 '@S9S_MB_2U_LIB.S9S_MB_2U(SCH_1):PAGE146_I303@PURE_QUANTA.SCONN168_ME1016810202011(CHIPS)':
 'PETP2': CDS_PINID='PETP2';
NET_NAME
'P5E_CPU1_PE1_TX_C_DN<3>'
 '@S9S_MB_2U_LIB.S9S_MB_2U(SCH_1):P5E_CPU1_PE1_TX_C_DN'<3>:
 C_SIGNAL='@s9s_mb_2u_lib.s9s_mb_2u(sch_1):p5e_cpu1_pe1_tx_c_dn(3)';
NODE_NAME     C830 1
 '@S9S_MB_2U_LIB.S9S_MB_2U(SCH_1):PAGE166_I341@PURE_QUANTA.Q_CAP_DIFFBUS(CHIPS)':
 '1': CDS_PINID='\1\';
NODE_NAME     J35 B26
 '@S9S_MB_2U_LIB.S9S_MB_2U(SCH_1):PAGE146_I303@PURE_QUANTA.SCONN168_ME1016810202011(CHIPS)':
 'PETN3': CDS_PINID='PETN3';
NET_NAME
'P5E_CPU1_PE1_TX_C_DN<4>'
 '@S9S_MB_2U_LIB.S9S_MB_2U(SCH_1):P5E_CPU1_PE1_TX_C_DN'<4>:
 C_SIGNAL='@s9s_mb_2u_lib.s9s_mb_2u(sch_1):p5e_cpu1_pe1_tx_c_dn(4)';
NODE_NAME     C828 1
 '@S9S_MB_2U_LIB.S9S_MB_2U(SCH_1):PAGE166_I340@PURE_QUANTA.Q_CAP_DIFFBUS(CHIPS)':
 '1': CDS_PINID='\1\';
NODE_NAME     J35 B31
 '@S9S_MB_2U_LIB.S9S_MB_2U(SCH_1):PAGE146_I303@PURE_QUANTA.SCONN168_ME1016810202011(CHIPS)':
 'PETP4': CDS_PINID='PETP4';
NET_NAME
'P5E_CPU1_PE1_TX_C_DN<5>'
 '@S9S_MB_2U_LIB.S9S_MB_2U(SCH_1):P5E_CPU1_PE1_TX_C_DN'<5>:
 C_SIGNAL='@s9s_mb_2u_lib.s9s_mb_2u(sch_1):p5e_cpu1_pe1_tx_c_dn(5)';
NODE_NAME     C826 1
 '@S9S_MB_2U_LIB.S9S_MB_2U(SCH_1):PAGE166_I344@PURE_QUANTA.Q_CAP_DIFFBUS(CHIPS)':
 '1': CDS_PINID='\1\';
NODE_NAME     J35 B33
 '@S9S_MB_2U_LIB.S9S_MB_2U(SCH_1):PAGE146_I303@PURE_QUANTA.SCONN168_ME1016810202011(CHIPS)':
 'PETN5': CDS_PINID='PETN5';
NET_NAME
'P5E_CPU1_PE1_TX_C_DN<6>'
 '@S9S_MB_2U_LIB.S9S_MB_2U(SCH_1):P5E_CPU1_PE1_TX_C_DN'<6>:
 C_SIGNAL='@s9s_mb_2u_lib.s9s_mb_2u(sch_1):p5e_cpu1_pe1_tx_c_dn(6)';
NODE_NAME     C824 1
 '@S9S_MB_2U_LIB.S9S_MB_2U(SCH_1):PAGE166_I416@PURE_QUANTA.Q_CAP_DIFFBUS(CHIPS)':
 '1': CDS_PINID='\1\';
NODE_NAME     J35 B37
 '@S9S_MB_2U_LIB.S9S_MB_2U(SCH_1):PAGE146_I303@PURE_QUANTA.SCONN168_ME1016810202011(CHIPS)':
 'PETP6': CDS_PINID='PETP6';
NET_NAME
'P5E_CPU1_PE1_TX_C_DN<7>'
 '@S9S_MB_2U_LIB.S9S_MB_2U(SCH_1):P5E_CPU1_PE1_TX_C_DN'<7>:
 C_SIGNAL='@s9s_mb_2u_lib.s9s_mb_2u(sch_1):p5e_cpu1_pe1_tx_c_dn(7)';
NODE_NAME     C822 1
 '@S9S_MB_2U_LIB.S9S_MB_2U(SCH_1):PAGE166_I345@PURE_QUANTA.Q_CAP_DIFFBUS(CHIPS)':
 '1': CDS_PINID='\1\';
NODE_NAME     J35 B39
 '@S9S_MB_2U_LIB.S9S_MB_2U(SCH_1):PAGE146_I303@PURE_QUANTA.SCONN168_ME1016810202011(CHIPS)':
 'PETN7': CDS_PINID='PETN7';
NET_NAME
'P5E_CPU1_PE1_TX_C_DN<8>'
 '@S9S_MB_2U_LIB.S9S_MB_2U(SCH_1):P5E_CPU1_PE1_TX_C_DN'<8>:
 C_SIGNAL='@s9s_mb_2u_lib.s9s_mb_2u(sch_1):p5e_cpu1_pe1_tx_c_dn(8)';
NODE_NAME     C820 1
 '@S9S_MB_2U_LIB.S9S_MB_2U(SCH_1):PAGE166_I363@PURE_QUANTA.Q_CAP_DIFFBUS(CHIPS)':
 '1': CDS_PINID='\1\';
NODE_NAME     J35 B45
 '@S9S_MB_2U_LIB.S9S_MB_2U(SCH_1):PAGE146_I303@PURE_QUANTA.SCONN168_ME1016810202011(CHIPS)':
 'PETP8': CDS_PINID='PETP8';
NET_NAME
'P5E_CPU1_PE1_TX_C_DN<9>'
 '@S9S_MB_2U_LIB.S9S_MB_2U(SCH_1):P5E_CPU1_PE1_TX_C_DN'<9>:
 C_SIGNAL='@s9s_mb_2u_lib.s9s_mb_2u(sch_1):p5e_cpu1_pe1_tx_c_dn(9)';
NODE_NAME     C818 1
 '@S9S_MB_2U_LIB.S9S_MB_2U(SCH_1):PAGE166_I365@PURE_QUANTA.Q_CAP_DIFFBUS(CHIPS)':
 '1': CDS_PINID='\1\';
NODE_NAME     J35 B47
 '@S9S_MB_2U_LIB.S9S_MB_2U(SCH_1):PAGE146_I303@PURE_QUANTA.SCONN168_ME1016810202011(CHIPS)':
 'PETN9': CDS_PINID='PETN9';
NET_NAME
'P5E_CPU1_PE1_TX_C_DP<0>'
 '@S9S_MB_2U_LIB.S9S_MB_2U(SCH_1):P5E_CPU1_PE1_TX_C_DP'<0>:
 C_SIGNAL='@s9s_mb_2u_lib.s9s_mb_2u(sch_1):p5e_cpu1_pe1_tx_c_dp(0)';
NODE_NAME     C837 1
 '@S9S_MB_2U_LIB.S9S_MB_2U(SCH_1):PAGE166_I334@PURE_QUANTA.Q_CAP_DIFFBUS(CHIPS)':
 '1': CDS_PINID='\1\';
NODE_NAME     J35 B17
 '@S9S_MB_2U_LIB.S9S_MB_2U(SCH_1):PAGE146_I303@PURE_QUANTA.SCONN168_ME1016810202011(CHIPS)':
 'PETN0': CDS_PINID='PETN0';
NET_NAME
'P5E_CPU1_PE1_TX_C_DP<10>'
 '@S9S_MB_2U_LIB.S9S_MB_2U(SCH_1):P5E_CPU1_PE1_TX_C_DP'<10>:
 C_SIGNAL='@s9s_mb_2u_lib.s9s_mb_2u(sch_1):p5e_cpu1_pe1_tx_c_dp(10)';
NODE_NAME     C817 1
 '@S9S_MB_2U_LIB.S9S_MB_2U(SCH_1):PAGE166_I367@PURE_QUANTA.Q_CAP_DIFFBUS(CHIPS)':
 '1': CDS_PINID='\1\';
NODE_NAME     J35 B50
 '@S9S_MB_2U_LIB.S9S_MB_2U(SCH_1):PAGE146_I303@PURE_QUANTA.SCONN168_ME1016810202011(CHIPS)':
 'PETN10': CDS_PINID='PETN10';
NET_NAME
'P5E_CPU1_PE1_TX_C_DP<11>'
 '@S9S_MB_2U_LIB.S9S_MB_2U(SCH_1):P5E_CPU1_PE1_TX_C_DP'<11>:
 C_SIGNAL='@s9s_mb_2u_lib.s9s_mb_2u(sch_1):p5e_cpu1_pe1_tx_c_dp(11)';
NODE_NAME     C815 1
 '@S9S_MB_2U_LIB.S9S_MB_2U(SCH_1):PAGE166_I369@PURE_QUANTA.Q_CAP_DIFFBUS(CHIPS)':
 '1': CDS_PINID='\1\';
NODE_NAME     J35 B54
 '@S9S_MB_2U_LIB.S9S_MB_2U(SCH_1):PAGE146_I303@PURE_QUANTA.SCONN168_ME1016810202011(CHIPS)':
 'PETP11': CDS_PINID='PETP11';
NET_NAME
'P5E_CPU1_PE1_TX_C_DP<12>'
 '@S9S_MB_2U_LIB.S9S_MB_2U(SCH_1):P5E_CPU1_PE1_TX_C_DP'<12>:
 C_SIGNAL='@s9s_mb_2u_lib.s9s_mb_2u(sch_1):p5e_cpu1_pe1_tx_c_dp(12)';
NODE_NAME     C813 1
 '@S9S_MB_2U_LIB.S9S_MB_2U(SCH_1):PAGE166_I372@PURE_QUANTA.Q_CAP_DIFFBUS(CHIPS)':
 '1': CDS_PINID='\1\';
NODE_NAME     J35 B56
 '@S9S_MB_2U_LIB.S9S_MB_2U(SCH_1):PAGE146_I303@PURE_QUANTA.SCONN168_ME1016810202011(CHIPS)':
 'PETN12': CDS_PINID='PETN12';
NET_NAME
'P5E_CPU1_PE1_TX_C_DP<13>'
 '@S9S_MB_2U_LIB.S9S_MB_2U(SCH_1):P5E_CPU1_PE1_TX_C_DP'<13>:
 C_SIGNAL='@s9s_mb_2u_lib.s9s_mb_2u(sch_1):p5e_cpu1_pe1_tx_c_dp(13)';
NODE_NAME     C811 1
 '@S9S_MB_2U_LIB.S9S_MB_2U(SCH_1):PAGE166_I373@PURE_QUANTA.Q_CAP_DIFFBUS(CHIPS)':
 '1': CDS_PINID='\1\';
NODE_NAME     J35 B60
 '@S9S_MB_2U_LIB.S9S_MB_2U(SCH_1):PAGE146_I303@PURE_QUANTA.SCONN168_ME1016810202011(CHIPS)':
 'PETP13': CDS_PINID='PETP13';
NET_NAME
'P5E_CPU1_PE1_TX_C_DP<14>'
 '@S9S_MB_2U_LIB.S9S_MB_2U(SCH_1):P5E_CPU1_PE1_TX_C_DP'<14>:
 C_SIGNAL='@s9s_mb_2u_lib.s9s_mb_2u(sch_1):p5e_cpu1_pe1_tx_c_dp(14)';
NODE_NAME     C809 1
 '@S9S_MB_2U_LIB.S9S_MB_2U(SCH_1):PAGE166_I375@PURE_QUANTA.Q_CAP_DIFFBUS(CHIPS)':
 '1': CDS_PINID='\1\';
NODE_NAME     J35 B62
 '@S9S_MB_2U_LIB.S9S_MB_2U(SCH_1):PAGE146_I303@PURE_QUANTA.SCONN168_ME1016810202011(CHIPS)':
 'PETN14': CDS_PINID='PETN14';
NET_NAME
'P5E_CPU1_PE1_TX_C_DP<15>'
 '@S9S_MB_2U_LIB.S9S_MB_2U(SCH_1):P5E_CPU1_PE1_TX_C_DP'<15>:
 C_SIGNAL='@s9s_mb_2u_lib.s9s_mb_2u(sch_1):p5e_cpu1_pe1_tx_c_dp(15)';
NODE_NAME     C807 1
 '@S9S_MB_2U_LIB.S9S_MB_2U(SCH_1):PAGE166_I378@PURE_QUANTA.Q_CAP_DIFFBUS(CHIPS)':
 '1': CDS_PINID='\1\';
NODE_NAME     J35 B66
 '@S9S_MB_2U_LIB.S9S_MB_2U(SCH_1):PAGE146_I303@PURE_QUANTA.SCONN168_ME1016810202011(CHIPS)':
 'PETP15': CDS_PINID='PETP15';
NET_NAME
'P5E_CPU1_PE1_TX_C_DP<1>'
 '@S9S_MB_2U_LIB.S9S_MB_2U(SCH_1):P5E_CPU1_PE1_TX_C_DP'<1>:
 C_SIGNAL='@s9s_mb_2u_lib.s9s_mb_2u(sch_1):p5e_cpu1_pe1_tx_c_dp(1)';
NODE_NAME     C835 1
 '@S9S_MB_2U_LIB.S9S_MB_2U(SCH_1):PAGE166_I336@PURE_QUANTA.Q_CAP_DIFFBUS(CHIPS)':
 '1': CDS_PINID='\1\';
NODE_NAME     J35 B21
 '@S9S_MB_2U_LIB.S9S_MB_2U(SCH_1):PAGE146_I303@PURE_QUANTA.SCONN168_ME1016810202011(CHIPS)':
 'PETP1': CDS_PINID='PETP1';
NET_NAME
'P5E_CPU1_PE1_TX_C_DP<2>'
 '@S9S_MB_2U_LIB.S9S_MB_2U(SCH_1):P5E_CPU1_PE1_TX_C_DP'<2>:
 C_SIGNAL='@s9s_mb_2u_lib.s9s_mb_2u(sch_1):p5e_cpu1_pe1_tx_c_dp(2)';
NODE_NAME     C833 1
 '@S9S_MB_2U_LIB.S9S_MB_2U(SCH_1):PAGE166_I339@PURE_QUANTA.Q_CAP_DIFFBUS(CHIPS)':
 '1': CDS_PINID='\1\';
NODE_NAME     J35 B23
 '@S9S_MB_2U_LIB.S9S_MB_2U(SCH_1):PAGE146_I303@PURE_QUANTA.SCONN168_ME1016810202011(CHIPS)':
 'PETN2': CDS_PINID='PETN2';
NET_NAME
'P5E_CPU1_PE1_TX_C_DP<3>'
 '@S9S_MB_2U_LIB.S9S_MB_2U(SCH_1):P5E_CPU1_PE1_TX_C_DP'<3>:
 C_SIGNAL='@s9s_mb_2u_lib.s9s_mb_2u(sch_1):p5e_cpu1_pe1_tx_c_dp(3)';
NODE_NAME     C831 1
 '@S9S_MB_2U_LIB.S9S_MB_2U(SCH_1):PAGE166_I337@PURE_QUANTA.Q_CAP_DIFFBUS(CHIPS)':
 '1': CDS_PINID='\1\';
NODE_NAME     J35 B27
 '@S9S_MB_2U_LIB.S9S_MB_2U(SCH_1):PAGE146_I303@PURE_QUANTA.SCONN168_ME1016810202011(CHIPS)':
 'PETP3': CDS_PINID='PETP3';
NET_NAME
'P5E_CPU1_PE1_TX_C_DP<4>'
 '@S9S_MB_2U_LIB.S9S_MB_2U(SCH_1):P5E_CPU1_PE1_TX_C_DP'<4>:
 C_SIGNAL='@s9s_mb_2u_lib.s9s_mb_2u(sch_1):p5e_cpu1_pe1_tx_c_dp(4)';
NODE_NAME     C829 1
 '@S9S_MB_2U_LIB.S9S_MB_2U(SCH_1):PAGE166_I342@PURE_QUANTA.Q_CAP_DIFFBUS(CHIPS)':
 '1': CDS_PINID='\1\';
NODE_NAME     J35 B30
 '@S9S_MB_2U_LIB.S9S_MB_2U(SCH_1):PAGE146_I303@PURE_QUANTA.SCONN168_ME1016810202011(CHIPS)':
 'PETN4': CDS_PINID='PETN4';
NET_NAME
'P5E_CPU1_PE1_TX_C_DP<5>'
 '@S9S_MB_2U_LIB.S9S_MB_2U(SCH_1):P5E_CPU1_PE1_TX_C_DP'<5>:
 C_SIGNAL='@s9s_mb_2u_lib.s9s_mb_2u(sch_1):p5e_cpu1_pe1_tx_c_dp(5)';
NODE_NAME     C827 1
 '@S9S_MB_2U_LIB.S9S_MB_2U(SCH_1):PAGE166_I343@PURE_QUANTA.Q_CAP_DIFFBUS(CHIPS)':
 '1': CDS_PINID='\1\';
NODE_NAME     J35 B34
 '@S9S_MB_2U_LIB.S9S_MB_2U(SCH_1):PAGE146_I303@PURE_QUANTA.SCONN168_ME1016810202011(CHIPS)':
 'PETP5': CDS_PINID='PETP5';
NET_NAME
'P5E_CPU1_PE1_TX_C_DP<6>'
 '@S9S_MB_2U_LIB.S9S_MB_2U(SCH_1):P5E_CPU1_PE1_TX_C_DP'<6>:
 C_SIGNAL='@s9s_mb_2u_lib.s9s_mb_2u(sch_1):p5e_cpu1_pe1_tx_c_dp(6)';
NODE_NAME     C825 1
 '@S9S_MB_2U_LIB.S9S_MB_2U(SCH_1):PAGE166_I415@PURE_QUANTA.Q_CAP_DIFFBUS(CHIPS)':
 '1': CDS_PINID='\1\';
NODE_NAME     J35 B36
 '@S9S_MB_2U_LIB.S9S_MB_2U(SCH_1):PAGE146_I303@PURE_QUANTA.SCONN168_ME1016810202011(CHIPS)':
 'PETN6': CDS_PINID='PETN6';
NET_NAME
'P5E_CPU1_PE1_TX_C_DP<7>'
 '@S9S_MB_2U_LIB.S9S_MB_2U(SCH_1):P5E_CPU1_PE1_TX_C_DP'<7>:
 C_SIGNAL='@s9s_mb_2u_lib.s9s_mb_2u(sch_1):p5e_cpu1_pe1_tx_c_dp(7)';
NODE_NAME     C823 1
 '@S9S_MB_2U_LIB.S9S_MB_2U(SCH_1):PAGE166_I346@PURE_QUANTA.Q_CAP_DIFFBUS(CHIPS)':
 '1': CDS_PINID='\1\';
NODE_NAME     J35 B40
 '@S9S_MB_2U_LIB.S9S_MB_2U(SCH_1):PAGE146_I303@PURE_QUANTA.SCONN168_ME1016810202011(CHIPS)':
 'PETP7': CDS_PINID='PETP7';
NET_NAME
'P5E_CPU1_PE1_TX_C_DP<8>'
 '@S9S_MB_2U_LIB.S9S_MB_2U(SCH_1):P5E_CPU1_PE1_TX_C_DP'<8>:
 C_SIGNAL='@s9s_mb_2u_lib.s9s_mb_2u(sch_1):p5e_cpu1_pe1_tx_c_dp(8)';
NODE_NAME     C821 1
 '@S9S_MB_2U_LIB.S9S_MB_2U(SCH_1):PAGE166_I364@PURE_QUANTA.Q_CAP_DIFFBUS(CHIPS)':
 '1': CDS_PINID='\1\';
NODE_NAME     J35 B44
 '@S9S_MB_2U_LIB.S9S_MB_2U(SCH_1):PAGE146_I303@PURE_QUANTA.SCONN168_ME1016810202011(CHIPS)':
 'PETN8': CDS_PINID='PETN8';
NET_NAME
'P5E_CPU1_PE1_TX_C_DP<9>'
 '@S9S_MB_2U_LIB.S9S_MB_2U(SCH_1):P5E_CPU1_PE1_TX_C_DP'<9>:
 C_SIGNAL='@s9s_mb_2u_lib.s9s_mb_2u(sch_1):p5e_cpu1_pe1_tx_c_dp(9)';
NODE_NAME     C819 1
 '@S9S_MB_2U_LIB.S9S_MB_2U(SCH_1):PAGE166_I366@PURE_QUANTA.Q_CAP_DIFFBUS(CHIPS)':
 '1': CDS_PINID='\1\';
NODE_NAME     J35 B48
 '@S9S_MB_2U_LIB.S9S_MB_2U(SCH_1):PAGE146_I303@PURE_QUANTA.SCONN168_ME1016810202011(CHIPS)':
 'PETP9': CDS_PINID='PETP9';
NET_NAME
'P5E_CPU1_PE1_TX_DN<0>'
 '@S9S_MB_2U_LIB.S9S_MB_2U(SCH_1):P5E_CPU1_PE1_TX_DN'<0>:
 C_SIGNAL='@s9s_mb_2u_lib.s9s_mb_2u(sch_1):p5e_cpu1_pe1_tx_dn(0)';
NODE_NAME     U1 CP14
 '@S9S_MB_2U_LIB.S9S_MB_2U(SCH_1):PAGE60_I69@PURE_QUANTA.SOCKET4677_AZIF0045P001C01CS(CHIPS)':
 'PE1_TX_DN0': CDS_PINID='PE1_TX_DN0';
NODE_NAME     C836 2
 '@S9S_MB_2U_LIB.S9S_MB_2U(SCH_1):PAGE166_I333@PURE_QUANTA.Q_CAP_DIFFBUS(CHIPS)':
 '2': CDS_PINID='\2\';
NET_NAME
'P5E_CPU1_PE1_TX_DN<10>'
 '@S9S_MB_2U_LIB.S9S_MB_2U(SCH_1):P5E_CPU1_PE1_TX_DN'<10>:
 C_SIGNAL='@s9s_mb_2u_lib.s9s_mb_2u(sch_1):p5e_cpu1_pe1_tx_dn(10)';
NODE_NAME     U1 BP14
 '@S9S_MB_2U_LIB.S9S_MB_2U(SCH_1):PAGE60_I69@PURE_QUANTA.SOCKET4677_AZIF0045P001C01CS(CHIPS)':
 'PE1_TX_DN10': CDS_PINID='PE1_TX_DN10';
NODE_NAME     C816 2
 '@S9S_MB_2U_LIB.S9S_MB_2U(SCH_1):PAGE166_I368@PURE_QUANTA.Q_CAP_DIFFBUS(CHIPS)':
 '2': CDS_PINID='\2\';
NET_NAME
'P5E_CPU1_PE1_TX_DN<11>'
 '@S9S_MB_2U_LIB.S9S_MB_2U(SCH_1):P5E_CPU1_PE1_TX_DN'<11>:
 C_SIGNAL='@s9s_mb_2u_lib.s9s_mb_2u(sch_1):p5e_cpu1_pe1_tx_dn(11)';
NODE_NAME     U1 BN13
 '@S9S_MB_2U_LIB.S9S_MB_2U(SCH_1):PAGE60_I69@PURE_QUANTA.SOCKET4677_AZIF0045P001C01CS(CHIPS)':
 'PE1_TX_DN11': CDS_PINID='PE1_TX_DN11';
NODE_NAME     C814 2
 '@S9S_MB_2U_LIB.S9S_MB_2U(SCH_1):PAGE166_I370@PURE_QUANTA.Q_CAP_DIFFBUS(CHIPS)':
 '2': CDS_PINID='\2\';
NET_NAME
'P5E_CPU1_PE1_TX_DN<12>'
 '@S9S_MB_2U_LIB.S9S_MB_2U(SCH_1):P5E_CPU1_PE1_TX_DN'<12>:
 C_SIGNAL='@s9s_mb_2u_lib.s9s_mb_2u(sch_1):p5e_cpu1_pe1_tx_dn(12)';
NODE_NAME     U1 BK14
 '@S9S_MB_2U_LIB.S9S_MB_2U(SCH_1):PAGE60_I69@PURE_QUANTA.SOCKET4677_AZIF0045P001C01CS(CHIPS)':
 'PE1_TX_DN12': CDS_PINID='PE1_TX_DN12';
NODE_NAME     C812 2
 '@S9S_MB_2U_LIB.S9S_MB_2U(SCH_1):PAGE166_I371@PURE_QUANTA.Q_CAP_DIFFBUS(CHIPS)':
 '2': CDS_PINID='\2\';
NET_NAME
'P5E_CPU1_PE1_TX_DN<13>'
 '@S9S_MB_2U_LIB.S9S_MB_2U(SCH_1):P5E_CPU1_PE1_TX_DN'<13>:
 C_SIGNAL='@s9s_mb_2u_lib.s9s_mb_2u(sch_1):p5e_cpu1_pe1_tx_dn(13)';
NODE_NAME     U1 BJ13
 '@S9S_MB_2U_LIB.S9S_MB_2U(SCH_1):PAGE60_I69@PURE_QUANTA.SOCKET4677_AZIF0045P001C01CS(CHIPS)':
 'PE1_TX_DN13': CDS_PINID='PE1_TX_DN13';
NODE_NAME     C810 2
 '@S9S_MB_2U_LIB.S9S_MB_2U(SCH_1):PAGE166_I374@PURE_QUANTA.Q_CAP_DIFFBUS(CHIPS)':
 '2': CDS_PINID='\2\';
NET_NAME
'P5E_CPU1_PE1_TX_DN<14>'
 '@S9S_MB_2U_LIB.S9S_MB_2U(SCH_1):P5E_CPU1_PE1_TX_DN'<14>:
 C_SIGNAL='@s9s_mb_2u_lib.s9s_mb_2u(sch_1):p5e_cpu1_pe1_tx_dn(14)';
NODE_NAME     U1 BF14
 '@S9S_MB_2U_LIB.S9S_MB_2U(SCH_1):PAGE60_I69@PURE_QUANTA.SOCKET4677_AZIF0045P001C01CS(CHIPS)':
 'PE1_TX_DN14': CDS_PINID='PE1_TX_DN14';
NODE_NAME     C808 2
 '@S9S_MB_2U_LIB.S9S_MB_2U(SCH_1):PAGE166_I376@PURE_QUANTA.Q_CAP_DIFFBUS(CHIPS)':
 '2': CDS_PINID='\2\';
NET_NAME
'P5E_CPU1_PE1_TX_DN<15>'
 '@S9S_MB_2U_LIB.S9S_MB_2U(SCH_1):P5E_CPU1_PE1_TX_DN'<15>:
 C_SIGNAL='@s9s_mb_2u_lib.s9s_mb_2u(sch_1):p5e_cpu1_pe1_tx_dn(15)';
NODE_NAME     U1 BE13
 '@S9S_MB_2U_LIB.S9S_MB_2U(SCH_1):PAGE60_I69@PURE_QUANTA.SOCKET4677_AZIF0045P001C01CS(CHIPS)':
 'PE1_TX_DN15': CDS_PINID='PE1_TX_DN15';
NODE_NAME     C806 2
 '@S9S_MB_2U_LIB.S9S_MB_2U(SCH_1):PAGE166_I377@PURE_QUANTA.Q_CAP_DIFFBUS(CHIPS)':
 '2': CDS_PINID='\2\';
NET_NAME
'P5E_CPU1_PE1_TX_DN<1>'
 '@S9S_MB_2U_LIB.S9S_MB_2U(SCH_1):P5E_CPU1_PE1_TX_DN'<1>:
 C_SIGNAL='@s9s_mb_2u_lib.s9s_mb_2u(sch_1):p5e_cpu1_pe1_tx_dn(1)';
NODE_NAME     U1 CN13
 '@S9S_MB_2U_LIB.S9S_MB_2U(SCH_1):PAGE60_I69@PURE_QUANTA.SOCKET4677_AZIF0045P001C01CS(CHIPS)':
 'PE1_TX_DN1': CDS_PINID='PE1_TX_DN1';
NODE_NAME     C834 2
 '@S9S_MB_2U_LIB.S9S_MB_2U(SCH_1):PAGE166_I335@PURE_QUANTA.Q_CAP_DIFFBUS(CHIPS)':
 '2': CDS_PINID='\2\';
NET_NAME
'P5E_CPU1_PE1_TX_DN<2>'
 '@S9S_MB_2U_LIB.S9S_MB_2U(SCH_1):P5E_CPU1_PE1_TX_DN'<2>:
 C_SIGNAL='@s9s_mb_2u_lib.s9s_mb_2u(sch_1):p5e_cpu1_pe1_tx_dn(2)';
NODE_NAME     U1 CK14
 '@S9S_MB_2U_LIB.S9S_MB_2U(SCH_1):PAGE60_I69@PURE_QUANTA.SOCKET4677_AZIF0045P001C01CS(CHIPS)':
 'PE1_TX_DN2': CDS_PINID='PE1_TX_DN2';
NODE_NAME     C832 2
 '@S9S_MB_2U_LIB.S9S_MB_2U(SCH_1):PAGE166_I338@PURE_QUANTA.Q_CAP_DIFFBUS(CHIPS)':
 '2': CDS_PINID='\2\';
NET_NAME
'P5E_CPU1_PE1_TX_DN<3>'
 '@S9S_MB_2U_LIB.S9S_MB_2U(SCH_1):P5E_CPU1_PE1_TX_DN'<3>:
 C_SIGNAL='@s9s_mb_2u_lib.s9s_mb_2u(sch_1):p5e_cpu1_pe1_tx_dn(3)';
NODE_NAME     U1 CJ13
 '@S9S_MB_2U_LIB.S9S_MB_2U(SCH_1):PAGE60_I69@PURE_QUANTA.SOCKET4677_AZIF0045P001C01CS(CHIPS)':
 'PE1_TX_DN3': CDS_PINID='PE1_TX_DN3';
NODE_NAME     C830 2
 '@S9S_MB_2U_LIB.S9S_MB_2U(SCH_1):PAGE166_I341@PURE_QUANTA.Q_CAP_DIFFBUS(CHIPS)':
 '2': CDS_PINID='\2\';
NET_NAME
'P5E_CPU1_PE1_TX_DN<4>'
 '@S9S_MB_2U_LIB.S9S_MB_2U(SCH_1):P5E_CPU1_PE1_TX_DN'<4>:
 C_SIGNAL='@s9s_mb_2u_lib.s9s_mb_2u(sch_1):p5e_cpu1_pe1_tx_dn(4)';
NODE_NAME     U1 CF14
 '@S9S_MB_2U_LIB.S9S_MB_2U(SCH_1):PAGE60_I69@PURE_QUANTA.SOCKET4677_AZIF0045P001C01CS(CHIPS)':
 'PE1_TX_DN4': CDS_PINID='PE1_TX_DN4';
NODE_NAME     C828 2
 '@S9S_MB_2U_LIB.S9S_MB_2U(SCH_1):PAGE166_I340@PURE_QUANTA.Q_CAP_DIFFBUS(CHIPS)':
 '2': CDS_PINID='\2\';
NET_NAME
'P5E_CPU1_PE1_TX_DN<5>'
 '@S9S_MB_2U_LIB.S9S_MB_2U(SCH_1):P5E_CPU1_PE1_TX_DN'<5>:
 C_SIGNAL='@s9s_mb_2u_lib.s9s_mb_2u(sch_1):p5e_cpu1_pe1_tx_dn(5)';
NODE_NAME     U1 CE13
 '@S9S_MB_2U_LIB.S9S_MB_2U(SCH_1):PAGE60_I69@PURE_QUANTA.SOCKET4677_AZIF0045P001C01CS(CHIPS)':
 'PE1_TX_DN5': CDS_PINID='PE1_TX_DN5';
NODE_NAME     C826 2
 '@S9S_MB_2U_LIB.S9S_MB_2U(SCH_1):PAGE166_I344@PURE_QUANTA.Q_CAP_DIFFBUS(CHIPS)':
 '2': CDS_PINID='\2\';
NET_NAME
'P5E_CPU1_PE1_TX_DN<6>'
 '@S9S_MB_2U_LIB.S9S_MB_2U(SCH_1):P5E_CPU1_PE1_TX_DN'<6>:
 C_SIGNAL='@s9s_mb_2u_lib.s9s_mb_2u(sch_1):p5e_cpu1_pe1_tx_dn(6)';
NODE_NAME     U1 CB14
 '@S9S_MB_2U_LIB.S9S_MB_2U(SCH_1):PAGE60_I69@PURE_QUANTA.SOCKET4677_AZIF0045P001C01CS(CHIPS)':
 'PE1_TX_DN6': CDS_PINID='PE1_TX_DN6';
NODE_NAME     C824 2
 '@S9S_MB_2U_LIB.S9S_MB_2U(SCH_1):PAGE166_I416@PURE_QUANTA.Q_CAP_DIFFBUS(CHIPS)':
 '2': CDS_PINID='\2\';
NET_NAME
'P5E_CPU1_PE1_TX_DN<7>'
 '@S9S_MB_2U_LIB.S9S_MB_2U(SCH_1):P5E_CPU1_PE1_TX_DN'<7>:
 C_SIGNAL='@s9s_mb_2u_lib.s9s_mb_2u(sch_1):p5e_cpu1_pe1_tx_dn(7)';
NODE_NAME     U1 CA13
 '@S9S_MB_2U_LIB.S9S_MB_2U(SCH_1):PAGE60_I69@PURE_QUANTA.SOCKET4677_AZIF0045P001C01CS(CHIPS)':
 'PE1_TX_DN7': CDS_PINID='PE1_TX_DN7';
NODE_NAME     C822 2
 '@S9S_MB_2U_LIB.S9S_MB_2U(SCH_1):PAGE166_I345@PURE_QUANTA.Q_CAP_DIFFBUS(CHIPS)':
 '2': CDS_PINID='\2\';
NET_NAME
'P5E_CPU1_PE1_TX_DN<8>'
 '@S9S_MB_2U_LIB.S9S_MB_2U(SCH_1):P5E_CPU1_PE1_TX_DN'<8>:
 C_SIGNAL='@s9s_mb_2u_lib.s9s_mb_2u(sch_1):p5e_cpu1_pe1_tx_dn(8)';
NODE_NAME     U1 BV14
 '@S9S_MB_2U_LIB.S9S_MB_2U(SCH_1):PAGE60_I69@PURE_QUANTA.SOCKET4677_AZIF0045P001C01CS(CHIPS)':
 'PE1_TX_DN8': CDS_PINID='PE1_TX_DN8';
NODE_NAME     C820 2
 '@S9S_MB_2U_LIB.S9S_MB_2U(SCH_1):PAGE166_I363@PURE_QUANTA.Q_CAP_DIFFBUS(CHIPS)':
 '2': CDS_PINID='\2\';
NET_NAME
'P5E_CPU1_PE1_TX_DN<9>'
 '@S9S_MB_2U_LIB.S9S_MB_2U(SCH_1):P5E_CPU1_PE1_TX_DN'<9>:
 C_SIGNAL='@s9s_mb_2u_lib.s9s_mb_2u(sch_1):p5e_cpu1_pe1_tx_dn(9)';
NODE_NAME     U1 BU13
 '@S9S_MB_2U_LIB.S9S_MB_2U(SCH_1):PAGE60_I69@PURE_QUANTA.SOCKET4677_AZIF0045P001C01CS(CHIPS)':
 'PE1_TX_DN9': CDS_PINID='PE1_TX_DN9';
NODE_NAME     C818 2
 '@S9S_MB_2U_LIB.S9S_MB_2U(SCH_1):PAGE166_I365@PURE_QUANTA.Q_CAP_DIFFBUS(CHIPS)':
 '2': CDS_PINID='\2\';
NET_NAME
'P5E_CPU1_PE1_TX_DP<0>'
 '@S9S_MB_2U_LIB.S9S_MB_2U(SCH_1):P5E_CPU1_PE1_TX_DP'<0>:
 C_SIGNAL='@s9s_mb_2u_lib.s9s_mb_2u(sch_1):p5e_cpu1_pe1_tx_dp(0)';
NODE_NAME     U1 CR15
 '@S9S_MB_2U_LIB.S9S_MB_2U(SCH_1):PAGE60_I69@PURE_QUANTA.SOCKET4677_AZIF0045P001C01CS(CHIPS)':
 'PE1_TX_DP0': CDS_PINID='PE1_TX_DP0';
NODE_NAME     C837 2
 '@S9S_MB_2U_LIB.S9S_MB_2U(SCH_1):PAGE166_I334@PURE_QUANTA.Q_CAP_DIFFBUS(CHIPS)':
 '2': CDS_PINID='\2\';
NET_NAME
'P5E_CPU1_PE1_TX_DP<10>'
 '@S9S_MB_2U_LIB.S9S_MB_2U(SCH_1):P5E_CPU1_PE1_TX_DP'<10>:
 C_SIGNAL='@s9s_mb_2u_lib.s9s_mb_2u(sch_1):p5e_cpu1_pe1_tx_dp(10)';
NODE_NAME     U1 BR15
 '@S9S_MB_2U_LIB.S9S_MB_2U(SCH_1):PAGE60_I69@PURE_QUANTA.SOCKET4677_AZIF0045P001C01CS(CHIPS)':
 'PE1_TX_DP10': CDS_PINID='PE1_TX_DP10';
NODE_NAME     C817 2
 '@S9S_MB_2U_LIB.S9S_MB_2U(SCH_1):PAGE166_I367@PURE_QUANTA.Q_CAP_DIFFBUS(CHIPS)':
 '2': CDS_PINID='\2\';
NET_NAME
'P5E_CPU1_PE1_TX_DP<11>'
 '@S9S_MB_2U_LIB.S9S_MB_2U(SCH_1):P5E_CPU1_PE1_TX_DP'<11>:
 C_SIGNAL='@s9s_mb_2u_lib.s9s_mb_2u(sch_1):p5e_cpu1_pe1_tx_dp(11)';
NODE_NAME     U1 BM14
 '@S9S_MB_2U_LIB.S9S_MB_2U(SCH_1):PAGE60_I69@PURE_QUANTA.SOCKET4677_AZIF0045P001C01CS(CHIPS)':
 'PE1_TX_DP11': CDS_PINID='PE1_TX_DP11';
NODE_NAME     C815 2
 '@S9S_MB_2U_LIB.S9S_MB_2U(SCH_1):PAGE166_I369@PURE_QUANTA.Q_CAP_DIFFBUS(CHIPS)':
 '2': CDS_PINID='\2\';
NET_NAME
'P5E_CPU1_PE1_TX_DP<12>'
 '@S9S_MB_2U_LIB.S9S_MB_2U(SCH_1):P5E_CPU1_PE1_TX_DP'<12>:
 C_SIGNAL='@s9s_mb_2u_lib.s9s_mb_2u(sch_1):p5e_cpu1_pe1_tx_dp(12)';
NODE_NAME     U1 BL15
 '@S9S_MB_2U_LIB.S9S_MB_2U(SCH_1):PAGE60_I69@PURE_QUANTA.SOCKET4677_AZIF0045P001C01CS(CHIPS)':
 'PE1_TX_DP12': CDS_PINID='PE1_TX_DP12';
NODE_NAME     C813 2
 '@S9S_MB_2U_LIB.S9S_MB_2U(SCH_1):PAGE166_I372@PURE_QUANTA.Q_CAP_DIFFBUS(CHIPS)':
 '2': CDS_PINID='\2\';
NET_NAME
'P5E_CPU1_PE1_TX_DP<13>'
 '@S9S_MB_2U_LIB.S9S_MB_2U(SCH_1):P5E_CPU1_PE1_TX_DP'<13>:
 C_SIGNAL='@s9s_mb_2u_lib.s9s_mb_2u(sch_1):p5e_cpu1_pe1_tx_dp(13)';
NODE_NAME     U1 BH14
 '@S9S_MB_2U_LIB.S9S_MB_2U(SCH_1):PAGE60_I69@PURE_QUANTA.SOCKET4677_AZIF0045P001C01CS(CHIPS)':
 'PE1_TX_DP13': CDS_PINID='PE1_TX_DP13';
NODE_NAME     C811 2
 '@S9S_MB_2U_LIB.S9S_MB_2U(SCH_1):PAGE166_I373@PURE_QUANTA.Q_CAP_DIFFBUS(CHIPS)':
 '2': CDS_PINID='\2\';
NET_NAME
'P5E_CPU1_PE1_TX_DP<14>'
 '@S9S_MB_2U_LIB.S9S_MB_2U(SCH_1):P5E_CPU1_PE1_TX_DP'<14>:
 C_SIGNAL='@s9s_mb_2u_lib.s9s_mb_2u(sch_1):p5e_cpu1_pe1_tx_dp(14)';
NODE_NAME     U1 BG15
 '@S9S_MB_2U_LIB.S9S_MB_2U(SCH_1):PAGE60_I69@PURE_QUANTA.SOCKET4677_AZIF0045P001C01CS(CHIPS)':
 'PE1_TX_DP14': CDS_PINID='PE1_TX_DP14';
NODE_NAME     C809 2
 '@S9S_MB_2U_LIB.S9S_MB_2U(SCH_1):PAGE166_I375@PURE_QUANTA.Q_CAP_DIFFBUS(CHIPS)':
 '2': CDS_PINID='\2\';
NET_NAME
'P5E_CPU1_PE1_TX_DP<15>'
 '@S9S_MB_2U_LIB.S9S_MB_2U(SCH_1):P5E_CPU1_PE1_TX_DP'<15>:
 C_SIGNAL='@s9s_mb_2u_lib.s9s_mb_2u(sch_1):p5e_cpu1_pe1_tx_dp(15)';
NODE_NAME     U1 BD14
 '@S9S_MB_2U_LIB.S9S_MB_2U(SCH_1):PAGE60_I69@PURE_QUANTA.SOCKET4677_AZIF0045P001C01CS(CHIPS)':
 'PE1_TX_DP15': CDS_PINID='PE1_TX_DP15';
NODE_NAME     C807 2
 '@S9S_MB_2U_LIB.S9S_MB_2U(SCH_1):PAGE166_I378@PURE_QUANTA.Q_CAP_DIFFBUS(CHIPS)':
 '2': CDS_PINID='\2\';
NET_NAME
'P5E_CPU1_PE1_TX_DP<1>'
 '@S9S_MB_2U_LIB.S9S_MB_2U(SCH_1):P5E_CPU1_PE1_TX_DP'<1>:
 C_SIGNAL='@s9s_mb_2u_lib.s9s_mb_2u(sch_1):p5e_cpu1_pe1_tx_dp(1)';
NODE_NAME     U1 CM14
 '@S9S_MB_2U_LIB.S9S_MB_2U(SCH_1):PAGE60_I69@PURE_QUANTA.SOCKET4677_AZIF0045P001C01CS(CHIPS)':
 'PE1_TX_DP1': CDS_PINID='PE1_TX_DP1';
NODE_NAME     C835 2
 '@S9S_MB_2U_LIB.S9S_MB_2U(SCH_1):PAGE166_I336@PURE_QUANTA.Q_CAP_DIFFBUS(CHIPS)':
 '2': CDS_PINID='\2\';
NET_NAME
'P5E_CPU1_PE1_TX_DP<2>'
 '@S9S_MB_2U_LIB.S9S_MB_2U(SCH_1):P5E_CPU1_PE1_TX_DP'<2>:
 C_SIGNAL='@s9s_mb_2u_lib.s9s_mb_2u(sch_1):p5e_cpu1_pe1_tx_dp(2)';
NODE_NAME     U1 CL15
 '@S9S_MB_2U_LIB.S9S_MB_2U(SCH_1):PAGE60_I69@PURE_QUANTA.SOCKET4677_AZIF0045P001C01CS(CHIPS)':
 'PE1_TX_DP2': CDS_PINID='PE1_TX_DP2';
NODE_NAME     C833 2
 '@S9S_MB_2U_LIB.S9S_MB_2U(SCH_1):PAGE166_I339@PURE_QUANTA.Q_CAP_DIFFBUS(CHIPS)':
 '2': CDS_PINID='\2\';
NET_NAME
'P5E_CPU1_PE1_TX_DP<3>'
 '@S9S_MB_2U_LIB.S9S_MB_2U(SCH_1):P5E_CPU1_PE1_TX_DP'<3>:
 C_SIGNAL='@s9s_mb_2u_lib.s9s_mb_2u(sch_1):p5e_cpu1_pe1_tx_dp(3)';
NODE_NAME     U1 CH14
 '@S9S_MB_2U_LIB.S9S_MB_2U(SCH_1):PAGE60_I69@PURE_QUANTA.SOCKET4677_AZIF0045P001C01CS(CHIPS)':
 'PE1_TX_DP3': CDS_PINID='PE1_TX_DP3';
NODE_NAME     C831 2
 '@S9S_MB_2U_LIB.S9S_MB_2U(SCH_1):PAGE166_I337@PURE_QUANTA.Q_CAP_DIFFBUS(CHIPS)':
 '2': CDS_PINID='\2\';
NET_NAME
'P5E_CPU1_PE1_TX_DP<4>'
 '@S9S_MB_2U_LIB.S9S_MB_2U(SCH_1):P5E_CPU1_PE1_TX_DP'<4>:
 C_SIGNAL='@s9s_mb_2u_lib.s9s_mb_2u(sch_1):p5e_cpu1_pe1_tx_dp(4)';
NODE_NAME     U1 CG15
 '@S9S_MB_2U_LIB.S9S_MB_2U(SCH_1):PAGE60_I69@PURE_QUANTA.SOCKET4677_AZIF0045P001C01CS(CHIPS)':
 'PE1_TX_DP4': CDS_PINID='PE1_TX_DP4';
NODE_NAME     C829 2
 '@S9S_MB_2U_LIB.S9S_MB_2U(SCH_1):PAGE166_I342@PURE_QUANTA.Q_CAP_DIFFBUS(CHIPS)':
 '2': CDS_PINID='\2\';
NET_NAME
'P5E_CPU1_PE1_TX_DP<5>'
 '@S9S_MB_2U_LIB.S9S_MB_2U(SCH_1):P5E_CPU1_PE1_TX_DP'<5>:
 C_SIGNAL='@s9s_mb_2u_lib.s9s_mb_2u(sch_1):p5e_cpu1_pe1_tx_dp(5)';
NODE_NAME     U1 CD14
 '@S9S_MB_2U_LIB.S9S_MB_2U(SCH_1):PAGE60_I69@PURE_QUANTA.SOCKET4677_AZIF0045P001C01CS(CHIPS)':
 'PE1_TX_DP5': CDS_PINID='PE1_TX_DP5';
NODE_NAME     C827 2
 '@S9S_MB_2U_LIB.S9S_MB_2U(SCH_1):PAGE166_I343@PURE_QUANTA.Q_CAP_DIFFBUS(CHIPS)':
 '2': CDS_PINID='\2\';
NET_NAME
'P5E_CPU1_PE1_TX_DP<6>'
 '@S9S_MB_2U_LIB.S9S_MB_2U(SCH_1):P5E_CPU1_PE1_TX_DP'<6>:
 C_SIGNAL='@s9s_mb_2u_lib.s9s_mb_2u(sch_1):p5e_cpu1_pe1_tx_dp(6)';
NODE_NAME     U1 CC15
 '@S9S_MB_2U_LIB.S9S_MB_2U(SCH_1):PAGE60_I69@PURE_QUANTA.SOCKET4677_AZIF0045P001C01CS(CHIPS)':
 'PE1_TX_DP6': CDS_PINID='PE1_TX_DP6';
NODE_NAME     C825 2
 '@S9S_MB_2U_LIB.S9S_MB_2U(SCH_1):PAGE166_I415@PURE_QUANTA.Q_CAP_DIFFBUS(CHIPS)':
 '2': CDS_PINID='\2\';
NET_NAME
'P5E_CPU1_PE1_TX_DP<7>'
 '@S9S_MB_2U_LIB.S9S_MB_2U(SCH_1):P5E_CPU1_PE1_TX_DP'<7>:
 C_SIGNAL='@s9s_mb_2u_lib.s9s_mb_2u(sch_1):p5e_cpu1_pe1_tx_dp(7)';
NODE_NAME     U1 BY14
 '@S9S_MB_2U_LIB.S9S_MB_2U(SCH_1):PAGE60_I69@PURE_QUANTA.SOCKET4677_AZIF0045P001C01CS(CHIPS)':
 'PE1_TX_DP7': CDS_PINID='PE1_TX_DP7';
NODE_NAME     C823 2
 '@S9S_MB_2U_LIB.S9S_MB_2U(SCH_1):PAGE166_I346@PURE_QUANTA.Q_CAP_DIFFBUS(CHIPS)':
 '2': CDS_PINID='\2\';
NET_NAME
'P5E_CPU1_PE1_TX_DP<8>'
 '@S9S_MB_2U_LIB.S9S_MB_2U(SCH_1):P5E_CPU1_PE1_TX_DP'<8>:
 C_SIGNAL='@s9s_mb_2u_lib.s9s_mb_2u(sch_1):p5e_cpu1_pe1_tx_dp(8)';
NODE_NAME     U1 BW15
 '@S9S_MB_2U_LIB.S9S_MB_2U(SCH_1):PAGE60_I69@PURE_QUANTA.SOCKET4677_AZIF0045P001C01CS(CHIPS)':
 'PE1_TX_DP8': CDS_PINID='PE1_TX_DP8';
NODE_NAME     C821 2
 '@S9S_MB_2U_LIB.S9S_MB_2U(SCH_1):PAGE166_I364@PURE_QUANTA.Q_CAP_DIFFBUS(CHIPS)':
 '2': CDS_PINID='\2\';
NET_NAME
'P5E_CPU1_PE1_TX_DP<9>'
 '@S9S_MB_2U_LIB.S9S_MB_2U(SCH_1):P5E_CPU1_PE1_TX_DP'<9>:
 C_SIGNAL='@s9s_mb_2u_lib.s9s_mb_2u(sch_1):p5e_cpu1_pe1_tx_dp(9)';
NODE_NAME     U1 BT14
 '@S9S_MB_2U_LIB.S9S_MB_2U(SCH_1):PAGE60_I69@PURE_QUANTA.SOCKET4677_AZIF0045P001C01CS(CHIPS)':
 'PE1_TX_DP9': CDS_PINID='PE1_TX_DP9';
NODE_NAME     C819 2
 '@S9S_MB_2U_LIB.S9S_MB_2U(SCH_1):PAGE166_I366@PURE_QUANTA.Q_CAP_DIFFBUS(CHIPS)':
 '2': CDS_PINID='\2\';
NET_NAME
'P5E_CPU1_PE2_RX_DN<0>'
 '@S9S_MB_2U_LIB.S9S_MB_2U(SCH_1):P5E_CPU1_PE2_RX_DN'<0>:
 C_SIGNAL='@s9s_mb_2u_lib.s9s_mb_2u(sch_1):p5e_cpu1_pe2_rx_dn(0)';
NODE_NAME     U1 CU9
 '@S9S_MB_2U_LIB.S9S_MB_2U(SCH_1):PAGE61_I54@PURE_QUANTA.SOCKET4677_AZIF0045P001C01CS(CHIPS)':
 'PE2_RX_DN0': CDS_PINID='PE2_RX_DN0';
NODE_NAME     J109 F8
 '@S9S_MB_2U_LIB.S9S_MB_2U(SCH_1):PAGE319_I76@PURE_QUANTA.CONN112_10137002101LF(CHIPS)':
 'F8': CDS_PINID='F8';
NET_NAME
'P5E_CPU1_PE2_RX_DN<10>'
 '@S9S_MB_2U_LIB.S9S_MB_2U(SCH_1):P5E_CPU1_PE2_RX_DN'<10>:
 C_SIGNAL='@s9s_mb_2u_lib.s9s_mb_2u(sch_1):p5e_cpu1_pe2_rx_dn(10)';
NODE_NAME     U1 DU9
 '@S9S_MB_2U_LIB.S9S_MB_2U(SCH_1):PAGE61_I54@PURE_QUANTA.SOCKET4677_AZIF0045P001C01CS(CHIPS)':
 'PE2_RX_DN10': CDS_PINID='PE2_RX_DN10';
NODE_NAME     J110 F6
 '@S9S_MB_2U_LIB.S9S_MB_2U(SCH_1):PAGE318_I16@PURE_QUANTA.CONN112_10137002101LF(CHIPS)':
 'F6': CDS_PINID='F6';
NET_NAME
'P5E_CPU1_PE2_RX_DN<11>'
 '@S9S_MB_2U_LIB.S9S_MB_2U(SCH_1):P5E_CPU1_PE2_RX_DN'<11>:
 C_SIGNAL='@s9s_mb_2u_lib.s9s_mb_2u(sch_1):p5e_cpu1_pe2_rx_dn(11)';
NODE_NAME     U1 DY10
 '@S9S_MB_2U_LIB.S9S_MB_2U(SCH_1):PAGE61_I54@PURE_QUANTA.SOCKET4677_AZIF0045P001C01CS(CHIPS)':
 'PE2_RX_DN11': CDS_PINID='PE2_RX_DN11';
NODE_NAME     J110 G5
 '@S9S_MB_2U_LIB.S9S_MB_2U(SCH_1):PAGE318_I16@PURE_QUANTA.CONN112_10137002101LF(CHIPS)':
 'G5': CDS_PINID='G5';
NET_NAME
'P5E_CPU1_PE2_RX_DN<12>'
 '@S9S_MB_2U_LIB.S9S_MB_2U(SCH_1):P5E_CPU1_PE2_RX_DN'<12>:
 C_SIGNAL='@s9s_mb_2u_lib.s9s_mb_2u(sch_1):p5e_cpu1_pe2_rx_dn(12)';
NODE_NAME     U1 EA9
 '@S9S_MB_2U_LIB.S9S_MB_2U(SCH_1):PAGE61_I54@PURE_QUANTA.SOCKET4677_AZIF0045P001C01CS(CHIPS)':
 'PE2_RX_DN12': CDS_PINID='PE2_RX_DN12';
NODE_NAME     J110 F4
 '@S9S_MB_2U_LIB.S9S_MB_2U(SCH_1):PAGE318_I54@PURE_QUANTA.CONN112_10137002101LF(CHIPS)':
 'F4': CDS_PINID='F4';
NET_NAME
'P5E_CPU1_PE2_RX_DN<13>'
 '@S9S_MB_2U_LIB.S9S_MB_2U(SCH_1):P5E_CPU1_PE2_RX_DN'<13>:
 C_SIGNAL='@s9s_mb_2u_lib.s9s_mb_2u(sch_1):p5e_cpu1_pe2_rx_dn(13)';
NODE_NAME     U1 ED10
 '@S9S_MB_2U_LIB.S9S_MB_2U(SCH_1):PAGE61_I54@PURE_QUANTA.SOCKET4677_AZIF0045P001C01CS(CHIPS)':
 'PE2_RX_DN13': CDS_PINID='PE2_RX_DN13';
NODE_NAME     J110 G3
 '@S9S_MB_2U_LIB.S9S_MB_2U(SCH_1):PAGE318_I54@PURE_QUANTA.CONN112_10137002101LF(CHIPS)':
 'G3': CDS_PINID='G3';
NET_NAME
'P5E_CPU1_PE2_RX_DN<14>'
 '@S9S_MB_2U_LIB.S9S_MB_2U(SCH_1):P5E_CPU1_PE2_RX_DN'<14>:
 C_SIGNAL='@s9s_mb_2u_lib.s9s_mb_2u(sch_1):p5e_cpu1_pe2_rx_dn(14)';
NODE_NAME     U1 EE9
 '@S9S_MB_2U_LIB.S9S_MB_2U(SCH_1):PAGE61_I54@PURE_QUANTA.SOCKET4677_AZIF0045P001C01CS(CHIPS)':
 'PE2_RX_DN14': CDS_PINID='PE2_RX_DN14';
NODE_NAME     J110 F2
 '@S9S_MB_2U_LIB.S9S_MB_2U(SCH_1):PAGE318_I54@PURE_QUANTA.CONN112_10137002101LF(CHIPS)':
 'F2': CDS_PINID='F2';
NET_NAME
'P5E_CPU1_PE2_RX_DN<15>'
 '@S9S_MB_2U_LIB.S9S_MB_2U(SCH_1):P5E_CPU1_PE2_RX_DN'<15>:
 C_SIGNAL='@s9s_mb_2u_lib.s9s_mb_2u(sch_1):p5e_cpu1_pe2_rx_dn(15)';
NODE_NAME     U1 EH10
 '@S9S_MB_2U_LIB.S9S_MB_2U(SCH_1):PAGE61_I54@PURE_QUANTA.SOCKET4677_AZIF0045P001C01CS(CHIPS)':
 'PE2_RX_DN15': CDS_PINID='PE2_RX_DN15';
NODE_NAME     J110 G1
 '@S9S_MB_2U_LIB.S9S_MB_2U(SCH_1):PAGE318_I54@PURE_QUANTA.CONN112_10137002101LF(CHIPS)':
 'G1': CDS_PINID='G1';
NET_NAME
'P5E_CPU1_PE2_RX_DN<1>'
 '@S9S_MB_2U_LIB.S9S_MB_2U(SCH_1):P5E_CPU1_PE2_RX_DN'<1>:
 C_SIGNAL='@s9s_mb_2u_lib.s9s_mb_2u(sch_1):p5e_cpu1_pe2_rx_dn(1)';
NODE_NAME     U1 CY10
 '@S9S_MB_2U_LIB.S9S_MB_2U(SCH_1):PAGE61_I54@PURE_QUANTA.SOCKET4677_AZIF0045P001C01CS(CHIPS)':
 'PE2_RX_DN1': CDS_PINID='PE2_RX_DN1';
NODE_NAME     J109 G7
 '@S9S_MB_2U_LIB.S9S_MB_2U(SCH_1):PAGE319_I76@PURE_QUANTA.CONN112_10137002101LF(CHIPS)':
 'G7': CDS_PINID='G7';
NET_NAME
'P5E_CPU1_PE2_RX_DN<2>'
 '@S9S_MB_2U_LIB.S9S_MB_2U(SCH_1):P5E_CPU1_PE2_RX_DN'<2>:
 C_SIGNAL='@s9s_mb_2u_lib.s9s_mb_2u(sch_1):p5e_cpu1_pe2_rx_dn(2)';
NODE_NAME     U1 DA9
 '@S9S_MB_2U_LIB.S9S_MB_2U(SCH_1):PAGE61_I54@PURE_QUANTA.SOCKET4677_AZIF0045P001C01CS(CHIPS)':
 'PE2_RX_DN2': CDS_PINID='PE2_RX_DN2';
NODE_NAME     J109 F6
 '@S9S_MB_2U_LIB.S9S_MB_2U(SCH_1):PAGE319_I76@PURE_QUANTA.CONN112_10137002101LF(CHIPS)':
 'F6': CDS_PINID='F6';
NET_NAME
'P5E_CPU1_PE2_RX_DN<3>'
 '@S9S_MB_2U_LIB.S9S_MB_2U(SCH_1):P5E_CPU1_PE2_RX_DN'<3>:
 C_SIGNAL='@s9s_mb_2u_lib.s9s_mb_2u(sch_1):p5e_cpu1_pe2_rx_dn(3)';
NODE_NAME     U1 DD10
 '@S9S_MB_2U_LIB.S9S_MB_2U(SCH_1):PAGE61_I54@PURE_QUANTA.SOCKET4677_AZIF0045P001C01CS(CHIPS)':
 'PE2_RX_DN3': CDS_PINID='PE2_RX_DN3';
NODE_NAME     J109 G5
 '@S9S_MB_2U_LIB.S9S_MB_2U(SCH_1):PAGE319_I76@PURE_QUANTA.CONN112_10137002101LF(CHIPS)':
 'G5': CDS_PINID='G5';
NET_NAME
'P5E_CPU1_PE2_RX_DN<4>'
 '@S9S_MB_2U_LIB.S9S_MB_2U(SCH_1):P5E_CPU1_PE2_RX_DN'<4>:
 C_SIGNAL='@s9s_mb_2u_lib.s9s_mb_2u(sch_1):p5e_cpu1_pe2_rx_dn(4)';
NODE_NAME     U1 DE9
 '@S9S_MB_2U_LIB.S9S_MB_2U(SCH_1):PAGE61_I54@PURE_QUANTA.SOCKET4677_AZIF0045P001C01CS(CHIPS)':
 'PE2_RX_DN4': CDS_PINID='PE2_RX_DN4';
NODE_NAME     J109 F4
 '@S9S_MB_2U_LIB.S9S_MB_2U(SCH_1):PAGE319_I53@PURE_QUANTA.CONN112_10137002101LF(CHIPS)':
 'F4': CDS_PINID='F4';
NET_NAME
'P5E_CPU1_PE2_RX_DN<5>'
 '@S9S_MB_2U_LIB.S9S_MB_2U(SCH_1):P5E_CPU1_PE2_RX_DN'<5>:
 C_SIGNAL='@s9s_mb_2u_lib.s9s_mb_2u(sch_1):p5e_cpu1_pe2_rx_dn(5)';
NODE_NAME     U1 DH10
 '@S9S_MB_2U_LIB.S9S_MB_2U(SCH_1):PAGE61_I54@PURE_QUANTA.SOCKET4677_AZIF0045P001C01CS(CHIPS)':
 'PE2_RX_DN5': CDS_PINID='PE2_RX_DN5';
NODE_NAME     J109 G3
 '@S9S_MB_2U_LIB.S9S_MB_2U(SCH_1):PAGE319_I53@PURE_QUANTA.CONN112_10137002101LF(CHIPS)':
 'G3': CDS_PINID='G3';
NET_NAME
'P5E_CPU1_PE2_RX_DN<6>'
 '@S9S_MB_2U_LIB.S9S_MB_2U(SCH_1):P5E_CPU1_PE2_RX_DN'<6>:
 C_SIGNAL='@s9s_mb_2u_lib.s9s_mb_2u(sch_1):p5e_cpu1_pe2_rx_dn(6)';
NODE_NAME     U1 DJ9
 '@S9S_MB_2U_LIB.S9S_MB_2U(SCH_1):PAGE61_I54@PURE_QUANTA.SOCKET4677_AZIF0045P001C01CS(CHIPS)':
 'PE2_RX_DN6': CDS_PINID='PE2_RX_DN6';
NODE_NAME     J109 F2
 '@S9S_MB_2U_LIB.S9S_MB_2U(SCH_1):PAGE319_I53@PURE_QUANTA.CONN112_10137002101LF(CHIPS)':
 'F2': CDS_PINID='F2';
NET_NAME
'P5E_CPU1_PE2_RX_DN<7>'
 '@S9S_MB_2U_LIB.S9S_MB_2U(SCH_1):P5E_CPU1_PE2_RX_DN'<7>:
 C_SIGNAL='@s9s_mb_2u_lib.s9s_mb_2u(sch_1):p5e_cpu1_pe2_rx_dn(7)';
NODE_NAME     U1 DM10
 '@S9S_MB_2U_LIB.S9S_MB_2U(SCH_1):PAGE61_I54@PURE_QUANTA.SOCKET4677_AZIF0045P001C01CS(CHIPS)':
 'PE2_RX_DN7': CDS_PINID='PE2_RX_DN7';
NODE_NAME     J109 G1
 '@S9S_MB_2U_LIB.S9S_MB_2U(SCH_1):PAGE319_I53@PURE_QUANTA.CONN112_10137002101LF(CHIPS)':
 'G1': CDS_PINID='G1';
NET_NAME
'P5E_CPU1_PE2_RX_DN<8>'
 '@S9S_MB_2U_LIB.S9S_MB_2U(SCH_1):P5E_CPU1_PE2_RX_DN'<8>:
 C_SIGNAL='@s9s_mb_2u_lib.s9s_mb_2u(sch_1):p5e_cpu1_pe2_rx_dn(8)';
NODE_NAME     U1 DN9
 '@S9S_MB_2U_LIB.S9S_MB_2U(SCH_1):PAGE61_I54@PURE_QUANTA.SOCKET4677_AZIF0045P001C01CS(CHIPS)':
 'PE2_RX_DN8': CDS_PINID='PE2_RX_DN8';
NODE_NAME     J110 F8
 '@S9S_MB_2U_LIB.S9S_MB_2U(SCH_1):PAGE318_I16@PURE_QUANTA.CONN112_10137002101LF(CHIPS)':
 'F8': CDS_PINID='F8';
NET_NAME
'P5E_CPU1_PE2_RX_DN<9>'
 '@S9S_MB_2U_LIB.S9S_MB_2U(SCH_1):P5E_CPU1_PE2_RX_DN'<9>:
 C_SIGNAL='@s9s_mb_2u_lib.s9s_mb_2u(sch_1):p5e_cpu1_pe2_rx_dn(9)';
NODE_NAME     U1 DT10
 '@S9S_MB_2U_LIB.S9S_MB_2U(SCH_1):PAGE61_I54@PURE_QUANTA.SOCKET4677_AZIF0045P001C01CS(CHIPS)':
 'PE2_RX_DN9': CDS_PINID='PE2_RX_DN9';
NODE_NAME     J110 G7
 '@S9S_MB_2U_LIB.S9S_MB_2U(SCH_1):PAGE318_I16@PURE_QUANTA.CONN112_10137002101LF(CHIPS)':
 'G7': CDS_PINID='G7';
NET_NAME
'P5E_CPU1_PE2_RX_DP<0>'
 '@S9S_MB_2U_LIB.S9S_MB_2U(SCH_1):P5E_CPU1_PE2_RX_DP'<0>:
 C_SIGNAL='@s9s_mb_2u_lib.s9s_mb_2u(sch_1):p5e_cpu1_pe2_rx_dp(0)';
NODE_NAME     U1 CV10
 '@S9S_MB_2U_LIB.S9S_MB_2U(SCH_1):PAGE61_I54@PURE_QUANTA.SOCKET4677_AZIF0045P001C01CS(CHIPS)':
 'PE2_RX_DP0': CDS_PINID='PE2_RX_DP0';
NODE_NAME     J109 E8
 '@S9S_MB_2U_LIB.S9S_MB_2U(SCH_1):PAGE319_I76@PURE_QUANTA.CONN112_10137002101LF(CHIPS)':
 'E8': CDS_PINID='E8';
NET_NAME
'P5E_CPU1_PE2_RX_DP<10>'
 '@S9S_MB_2U_LIB.S9S_MB_2U(SCH_1):P5E_CPU1_PE2_RX_DP'<10>:
 C_SIGNAL='@s9s_mb_2u_lib.s9s_mb_2u(sch_1):p5e_cpu1_pe2_rx_dp(10)';
NODE_NAME     U1 DV10
 '@S9S_MB_2U_LIB.S9S_MB_2U(SCH_1):PAGE61_I54@PURE_QUANTA.SOCKET4677_AZIF0045P001C01CS(CHIPS)':
 'PE2_RX_DP10': CDS_PINID='PE2_RX_DP10';
NODE_NAME     J110 E6
 '@S9S_MB_2U_LIB.S9S_MB_2U(SCH_1):PAGE318_I16@PURE_QUANTA.CONN112_10137002101LF(CHIPS)':
 'E6': CDS_PINID='E6';
NET_NAME
'P5E_CPU1_PE2_RX_DP<11>'
 '@S9S_MB_2U_LIB.S9S_MB_2U(SCH_1):P5E_CPU1_PE2_RX_DP'<11>:
 C_SIGNAL='@s9s_mb_2u_lib.s9s_mb_2u(sch_1):p5e_cpu1_pe2_rx_dp(11)';
NODE_NAME     U1 DW11
 '@S9S_MB_2U_LIB.S9S_MB_2U(SCH_1):PAGE61_I54@PURE_QUANTA.SOCKET4677_AZIF0045P001C01CS(CHIPS)':
 'PE2_RX_DP11': CDS_PINID='PE2_RX_DP11';
NODE_NAME     J110 F5
 '@S9S_MB_2U_LIB.S9S_MB_2U(SCH_1):PAGE318_I16@PURE_QUANTA.CONN112_10137002101LF(CHIPS)':
 'F5': CDS_PINID='F5';
NET_NAME
'P5E_CPU1_PE2_RX_DP<12>'
 '@S9S_MB_2U_LIB.S9S_MB_2U(SCH_1):P5E_CPU1_PE2_RX_DP'<12>:
 C_SIGNAL='@s9s_mb_2u_lib.s9s_mb_2u(sch_1):p5e_cpu1_pe2_rx_dp(12)';
NODE_NAME     U1 EB10
 '@S9S_MB_2U_LIB.S9S_MB_2U(SCH_1):PAGE61_I54@PURE_QUANTA.SOCKET4677_AZIF0045P001C01CS(CHIPS)':
 'PE2_RX_DP12': CDS_PINID='PE2_RX_DP12';
NODE_NAME     J110 E4
 '@S9S_MB_2U_LIB.S9S_MB_2U(SCH_1):PAGE318_I54@PURE_QUANTA.CONN112_10137002101LF(CHIPS)':
 'E4': CDS_PINID='E4';
NET_NAME
'P5E_CPU1_PE2_RX_DP<13>'
 '@S9S_MB_2U_LIB.S9S_MB_2U(SCH_1):P5E_CPU1_PE2_RX_DP'<13>:
 C_SIGNAL='@s9s_mb_2u_lib.s9s_mb_2u(sch_1):p5e_cpu1_pe2_rx_dp(13)';
NODE_NAME     U1 EC11
 '@S9S_MB_2U_LIB.S9S_MB_2U(SCH_1):PAGE61_I54@PURE_QUANTA.SOCKET4677_AZIF0045P001C01CS(CHIPS)':
 'PE2_RX_DP13': CDS_PINID='PE2_RX_DP13';
NODE_NAME     J110 F3
 '@S9S_MB_2U_LIB.S9S_MB_2U(SCH_1):PAGE318_I54@PURE_QUANTA.CONN112_10137002101LF(CHIPS)':
 'F3': CDS_PINID='F3';
NET_NAME
'P5E_CPU1_PE2_RX_DP<14>'
 '@S9S_MB_2U_LIB.S9S_MB_2U(SCH_1):P5E_CPU1_PE2_RX_DP'<14>:
 C_SIGNAL='@s9s_mb_2u_lib.s9s_mb_2u(sch_1):p5e_cpu1_pe2_rx_dp(14)';
NODE_NAME     U1 EF10
 '@S9S_MB_2U_LIB.S9S_MB_2U(SCH_1):PAGE61_I54@PURE_QUANTA.SOCKET4677_AZIF0045P001C01CS(CHIPS)':
 'PE2_RX_DP14': CDS_PINID='PE2_RX_DP14';
NODE_NAME     J110 E2
 '@S9S_MB_2U_LIB.S9S_MB_2U(SCH_1):PAGE318_I54@PURE_QUANTA.CONN112_10137002101LF(CHIPS)':
 'E2': CDS_PINID='E2';
NET_NAME
'P5E_CPU1_PE2_RX_DP<15>'
 '@S9S_MB_2U_LIB.S9S_MB_2U(SCH_1):P5E_CPU1_PE2_RX_DP'<15>:
 C_SIGNAL='@s9s_mb_2u_lib.s9s_mb_2u(sch_1):p5e_cpu1_pe2_rx_dp(15)';
NODE_NAME     U1 EG11
 '@S9S_MB_2U_LIB.S9S_MB_2U(SCH_1):PAGE61_I54@PURE_QUANTA.SOCKET4677_AZIF0045P001C01CS(CHIPS)':
 'PE2_RX_DP15': CDS_PINID='PE2_RX_DP15';
NODE_NAME     J110 F1
 '@S9S_MB_2U_LIB.S9S_MB_2U(SCH_1):PAGE318_I54@PURE_QUANTA.CONN112_10137002101LF(CHIPS)':
 'F1': CDS_PINID='F1';
NET_NAME
'P5E_CPU1_PE2_RX_DP<1>'
 '@S9S_MB_2U_LIB.S9S_MB_2U(SCH_1):P5E_CPU1_PE2_RX_DP'<1>:
 C_SIGNAL='@s9s_mb_2u_lib.s9s_mb_2u(sch_1):p5e_cpu1_pe2_rx_dp(1)';
NODE_NAME     U1 CW11
 '@S9S_MB_2U_LIB.S9S_MB_2U(SCH_1):PAGE61_I54@PURE_QUANTA.SOCKET4677_AZIF0045P001C01CS(CHIPS)':
 'PE2_RX_DP1': CDS_PINID='PE2_RX_DP1';
NODE_NAME     J109 F7
 '@S9S_MB_2U_LIB.S9S_MB_2U(SCH_1):PAGE319_I76@PURE_QUANTA.CONN112_10137002101LF(CHIPS)':
 'F7': CDS_PINID='F7';
NET_NAME
'P5E_CPU1_PE2_RX_DP<2>'
 '@S9S_MB_2U_LIB.S9S_MB_2U(SCH_1):P5E_CPU1_PE2_RX_DP'<2>:
 C_SIGNAL='@s9s_mb_2u_lib.s9s_mb_2u(sch_1):p5e_cpu1_pe2_rx_dp(2)';
NODE_NAME     U1 DB10
 '@S9S_MB_2U_LIB.S9S_MB_2U(SCH_1):PAGE61_I54@PURE_QUANTA.SOCKET4677_AZIF0045P001C01CS(CHIPS)':
 'PE2_RX_DP2': CDS_PINID='PE2_RX_DP2';
NODE_NAME     J109 E6
 '@S9S_MB_2U_LIB.S9S_MB_2U(SCH_1):PAGE319_I76@PURE_QUANTA.CONN112_10137002101LF(CHIPS)':
 'E6': CDS_PINID='E6';
NET_NAME
'P5E_CPU1_PE2_RX_DP<3>'
 '@S9S_MB_2U_LIB.S9S_MB_2U(SCH_1):P5E_CPU1_PE2_RX_DP'<3>:
 C_SIGNAL='@s9s_mb_2u_lib.s9s_mb_2u(sch_1):p5e_cpu1_pe2_rx_dp(3)';
NODE_NAME     U1 DC11
 '@S9S_MB_2U_LIB.S9S_MB_2U(SCH_1):PAGE61_I54@PURE_QUANTA.SOCKET4677_AZIF0045P001C01CS(CHIPS)':
 'PE2_RX_DP3': CDS_PINID='PE2_RX_DP3';
NODE_NAME     J109 F5
 '@S9S_MB_2U_LIB.S9S_MB_2U(SCH_1):PAGE319_I76@PURE_QUANTA.CONN112_10137002101LF(CHIPS)':
 'F5': CDS_PINID='F5';
NET_NAME
'P5E_CPU1_PE2_RX_DP<4>'
 '@S9S_MB_2U_LIB.S9S_MB_2U(SCH_1):P5E_CPU1_PE2_RX_DP'<4>:
 C_SIGNAL='@s9s_mb_2u_lib.s9s_mb_2u(sch_1):p5e_cpu1_pe2_rx_dp(4)';
NODE_NAME     U1 DF10
 '@S9S_MB_2U_LIB.S9S_MB_2U(SCH_1):PAGE61_I54@PURE_QUANTA.SOCKET4677_AZIF0045P001C01CS(CHIPS)':
 'PE2_RX_DP4': CDS_PINID='PE2_RX_DP4';
NODE_NAME     J109 E4
 '@S9S_MB_2U_LIB.S9S_MB_2U(SCH_1):PAGE319_I53@PURE_QUANTA.CONN112_10137002101LF(CHIPS)':
 'E4': CDS_PINID='E4';
NET_NAME
'P5E_CPU1_PE2_RX_DP<5>'
 '@S9S_MB_2U_LIB.S9S_MB_2U(SCH_1):P5E_CPU1_PE2_RX_DP'<5>:
 C_SIGNAL='@s9s_mb_2u_lib.s9s_mb_2u(sch_1):p5e_cpu1_pe2_rx_dp(5)';
NODE_NAME     U1 DG11
 '@S9S_MB_2U_LIB.S9S_MB_2U(SCH_1):PAGE61_I54@PURE_QUANTA.SOCKET4677_AZIF0045P001C01CS(CHIPS)':
 'PE2_RX_DP5': CDS_PINID='PE2_RX_DP5';
NODE_NAME     J109 F3
 '@S9S_MB_2U_LIB.S9S_MB_2U(SCH_1):PAGE319_I53@PURE_QUANTA.CONN112_10137002101LF(CHIPS)':
 'F3': CDS_PINID='F3';
NET_NAME
'P5E_CPU1_PE2_RX_DP<6>'
 '@S9S_MB_2U_LIB.S9S_MB_2U(SCH_1):P5E_CPU1_PE2_RX_DP'<6>:
 C_SIGNAL='@s9s_mb_2u_lib.s9s_mb_2u(sch_1):p5e_cpu1_pe2_rx_dp(6)';
NODE_NAME     U1 DK10
 '@S9S_MB_2U_LIB.S9S_MB_2U(SCH_1):PAGE61_I54@PURE_QUANTA.SOCKET4677_AZIF0045P001C01CS(CHIPS)':
 'PE2_RX_DP6': CDS_PINID='PE2_RX_DP6';
NODE_NAME     J109 E2
 '@S9S_MB_2U_LIB.S9S_MB_2U(SCH_1):PAGE319_I53@PURE_QUANTA.CONN112_10137002101LF(CHIPS)':
 'E2': CDS_PINID='E2';
NET_NAME
'P5E_CPU1_PE2_RX_DP<7>'
 '@S9S_MB_2U_LIB.S9S_MB_2U(SCH_1):P5E_CPU1_PE2_RX_DP'<7>:
 C_SIGNAL='@s9s_mb_2u_lib.s9s_mb_2u(sch_1):p5e_cpu1_pe2_rx_dp(7)';
NODE_NAME     U1 DL11
 '@S9S_MB_2U_LIB.S9S_MB_2U(SCH_1):PAGE61_I54@PURE_QUANTA.SOCKET4677_AZIF0045P001C01CS(CHIPS)':
 'PE2_RX_DP7': CDS_PINID='PE2_RX_DP7';
NODE_NAME     J109 F1
 '@S9S_MB_2U_LIB.S9S_MB_2U(SCH_1):PAGE319_I53@PURE_QUANTA.CONN112_10137002101LF(CHIPS)':
 'F1': CDS_PINID='F1';
NET_NAME
'P5E_CPU1_PE2_RX_DP<8>'
 '@S9S_MB_2U_LIB.S9S_MB_2U(SCH_1):P5E_CPU1_PE2_RX_DP'<8>:
 C_SIGNAL='@s9s_mb_2u_lib.s9s_mb_2u(sch_1):p5e_cpu1_pe2_rx_dp(8)';
NODE_NAME     U1 DP10
 '@S9S_MB_2U_LIB.S9S_MB_2U(SCH_1):PAGE61_I54@PURE_QUANTA.SOCKET4677_AZIF0045P001C01CS(CHIPS)':
 'PE2_RX_DP8': CDS_PINID='PE2_RX_DP8';
NODE_NAME     J110 E8
 '@S9S_MB_2U_LIB.S9S_MB_2U(SCH_1):PAGE318_I16@PURE_QUANTA.CONN112_10137002101LF(CHIPS)':
 'E8': CDS_PINID='E8';
NET_NAME
'P5E_CPU1_PE2_RX_DP<9>'
 '@S9S_MB_2U_LIB.S9S_MB_2U(SCH_1):P5E_CPU1_PE2_RX_DP'<9>:
 C_SIGNAL='@s9s_mb_2u_lib.s9s_mb_2u(sch_1):p5e_cpu1_pe2_rx_dp(9)';
NODE_NAME     U1 DR11
 '@S9S_MB_2U_LIB.S9S_MB_2U(SCH_1):PAGE61_I54@PURE_QUANTA.SOCKET4677_AZIF0045P001C01CS(CHIPS)':
 'PE2_RX_DP9': CDS_PINID='PE2_RX_DP9';
NODE_NAME     J110 F7
 '@S9S_MB_2U_LIB.S9S_MB_2U(SCH_1):PAGE318_I16@PURE_QUANTA.CONN112_10137002101LF(CHIPS)':
 'F7': CDS_PINID='F7';
NET_NAME
'P5E_CPU1_PE2_TX_C_DN<0>'
 '@S9S_MB_2U_LIB.S9S_MB_2U(SCH_1):P5E_CPU1_PE2_TX_C_DN'<0>:
 C_SIGNAL='@s9s_mb_2u_lib.s9s_mb_2u(sch_1):p5e_cpu1_pe2_tx_c_dn(0)';
NODE_NAME     C772 1
 '@S9S_MB_2U_LIB.S9S_MB_2U(SCH_1):PAGE167_I123@PURE_QUANTA.Q_CAP_DIFFBUS(CHIPS)':
 '1': CDS_PINID='\1\';
NODE_NAME     J109 L8
 '@S9S_MB_2U_LIB.S9S_MB_2U(SCH_1):PAGE319_I76@PURE_QUANTA.CONN112_10137002101LF(CHIPS)':
 'L8': CDS_PINID='L8';
NET_NAME
'P5E_CPU1_PE2_TX_C_DN<10>'
 '@S9S_MB_2U_LIB.S9S_MB_2U(SCH_1):P5E_CPU1_PE2_TX_C_DN'<10>:
 C_SIGNAL='@s9s_mb_2u_lib.s9s_mb_2u(sch_1):p5e_cpu1_pe2_tx_c_dn(10)';
NODE_NAME     C752 1
 '@S9S_MB_2U_LIB.S9S_MB_2U(SCH_1):PAGE167_I159@PURE_QUANTA.Q_CAP_DIFFBUS(CHIPS)':
 '1': CDS_PINID='\1\';
NODE_NAME     J110 L6
 '@S9S_MB_2U_LIB.S9S_MB_2U(SCH_1):PAGE318_I16@PURE_QUANTA.CONN112_10137002101LF(CHIPS)':
 'L6': CDS_PINID='L6';
NET_NAME
'P5E_CPU1_PE2_TX_C_DN<11>'
 '@S9S_MB_2U_LIB.S9S_MB_2U(SCH_1):P5E_CPU1_PE2_TX_C_DN'<11>:
 C_SIGNAL='@s9s_mb_2u_lib.s9s_mb_2u(sch_1):p5e_cpu1_pe2_tx_c_dn(11)';
NODE_NAME     C750 1
 '@S9S_MB_2U_LIB.S9S_MB_2U(SCH_1):PAGE167_I160@PURE_QUANTA.Q_CAP_DIFFBUS(CHIPS)':
 '1': CDS_PINID='\1\';
NODE_NAME     J110 M5
 '@S9S_MB_2U_LIB.S9S_MB_2U(SCH_1):PAGE318_I16@PURE_QUANTA.CONN112_10137002101LF(CHIPS)':
 'M5': CDS_PINID='M5';
NET_NAME
'P5E_CPU1_PE2_TX_C_DN<12>'
 '@S9S_MB_2U_LIB.S9S_MB_2U(SCH_1):P5E_CPU1_PE2_TX_C_DN'<12>:
 C_SIGNAL='@s9s_mb_2u_lib.s9s_mb_2u(sch_1):p5e_cpu1_pe2_tx_c_dn(12)';
NODE_NAME     C748 1
 '@S9S_MB_2U_LIB.S9S_MB_2U(SCH_1):PAGE167_I163@PURE_QUANTA.Q_CAP_DIFFBUS(CHIPS)':
 '1': CDS_PINID='\1\';
NODE_NAME     J110 L4
 '@S9S_MB_2U_LIB.S9S_MB_2U(SCH_1):PAGE318_I54@PURE_QUANTA.CONN112_10137002101LF(CHIPS)':
 'L4': CDS_PINID='L4';
NET_NAME
'P5E_CPU1_PE2_TX_C_DN<13>'
 '@S9S_MB_2U_LIB.S9S_MB_2U(SCH_1):P5E_CPU1_PE2_TX_C_DN'<13>:
 C_SIGNAL='@s9s_mb_2u_lib.s9s_mb_2u(sch_1):p5e_cpu1_pe2_tx_c_dn(13)';
NODE_NAME     C746 1
 '@S9S_MB_2U_LIB.S9S_MB_2U(SCH_1):PAGE167_I168@PURE_QUANTA.Q_CAP_DIFFBUS(CHIPS)':
 '1': CDS_PINID='\1\';
NODE_NAME     J110 M3
 '@S9S_MB_2U_LIB.S9S_MB_2U(SCH_1):PAGE318_I54@PURE_QUANTA.CONN112_10137002101LF(CHIPS)':
 'M3': CDS_PINID='M3';
NET_NAME
'P5E_CPU1_PE2_TX_C_DN<14>'
 '@S9S_MB_2U_LIB.S9S_MB_2U(SCH_1):P5E_CPU1_PE2_TX_C_DN'<14>:
 C_SIGNAL='@s9s_mb_2u_lib.s9s_mb_2u(sch_1):p5e_cpu1_pe2_tx_c_dn(14)';
NODE_NAME     C744 1
 '@S9S_MB_2U_LIB.S9S_MB_2U(SCH_1):PAGE167_I170@PURE_QUANTA.Q_CAP_DIFFBUS(CHIPS)':
 '1': CDS_PINID='\1\';
NODE_NAME     J110 L2
 '@S9S_MB_2U_LIB.S9S_MB_2U(SCH_1):PAGE318_I54@PURE_QUANTA.CONN112_10137002101LF(CHIPS)':
 'L2': CDS_PINID='L2';
NET_NAME
'P5E_CPU1_PE2_TX_C_DN<15>'
 '@S9S_MB_2U_LIB.S9S_MB_2U(SCH_1):P5E_CPU1_PE2_TX_C_DN'<15>:
 C_SIGNAL='@s9s_mb_2u_lib.s9s_mb_2u(sch_1):p5e_cpu1_pe2_tx_c_dn(15)';
NODE_NAME     C742 1
 '@S9S_MB_2U_LIB.S9S_MB_2U(SCH_1):PAGE167_I172@PURE_QUANTA.Q_CAP_DIFFBUS(CHIPS)':
 '1': CDS_PINID='\1\';
NODE_NAME     J110 M1
 '@S9S_MB_2U_LIB.S9S_MB_2U(SCH_1):PAGE318_I54@PURE_QUANTA.CONN112_10137002101LF(CHIPS)':
 'M1': CDS_PINID='M1';
NET_NAME
'P5E_CPU1_PE2_TX_C_DN<1>'
 '@S9S_MB_2U_LIB.S9S_MB_2U(SCH_1):P5E_CPU1_PE2_TX_C_DN'<1>:
 C_SIGNAL='@s9s_mb_2u_lib.s9s_mb_2u(sch_1):p5e_cpu1_pe2_tx_c_dn(1)';
NODE_NAME     C770 1
 '@S9S_MB_2U_LIB.S9S_MB_2U(SCH_1):PAGE167_I125@PURE_QUANTA.Q_CAP_DIFFBUS(CHIPS)':
 '1': CDS_PINID='\1\';
NODE_NAME     J109 M7
 '@S9S_MB_2U_LIB.S9S_MB_2U(SCH_1):PAGE319_I76@PURE_QUANTA.CONN112_10137002101LF(CHIPS)':
 'M7': CDS_PINID='M7';
NET_NAME
'P5E_CPU1_PE2_TX_C_DN<2>'
 '@S9S_MB_2U_LIB.S9S_MB_2U(SCH_1):P5E_CPU1_PE2_TX_C_DN'<2>:
 C_SIGNAL='@s9s_mb_2u_lib.s9s_mb_2u(sch_1):p5e_cpu1_pe2_tx_c_dn(2)';
NODE_NAME     C768 1
 '@S9S_MB_2U_LIB.S9S_MB_2U(SCH_1):PAGE167_I127@PURE_QUANTA.Q_CAP_DIFFBUS(CHIPS)':
 '1': CDS_PINID='\1\';
NODE_NAME     J109 L6
 '@S9S_MB_2U_LIB.S9S_MB_2U(SCH_1):PAGE319_I76@PURE_QUANTA.CONN112_10137002101LF(CHIPS)':
 'L6': CDS_PINID='L6';
NET_NAME
'P5E_CPU1_PE2_TX_C_DN<3>'
 '@S9S_MB_2U_LIB.S9S_MB_2U(SCH_1):P5E_CPU1_PE2_TX_C_DN'<3>:
 C_SIGNAL='@s9s_mb_2u_lib.s9s_mb_2u(sch_1):p5e_cpu1_pe2_tx_c_dn(3)';
NODE_NAME     C766 1
 '@S9S_MB_2U_LIB.S9S_MB_2U(SCH_1):PAGE167_I129@PURE_QUANTA.Q_CAP_DIFFBUS(CHIPS)':
 '1': CDS_PINID='\1\';
NODE_NAME     J109 M5
 '@S9S_MB_2U_LIB.S9S_MB_2U(SCH_1):PAGE319_I76@PURE_QUANTA.CONN112_10137002101LF(CHIPS)':
 'M5': CDS_PINID='M5';
NET_NAME
'P5E_CPU1_PE2_TX_C_DN<4>'
 '@S9S_MB_2U_LIB.S9S_MB_2U(SCH_1):P5E_CPU1_PE2_TX_C_DN'<4>:
 C_SIGNAL='@s9s_mb_2u_lib.s9s_mb_2u(sch_1):p5e_cpu1_pe2_tx_c_dn(4)';
NODE_NAME     C764 1
 '@S9S_MB_2U_LIB.S9S_MB_2U(SCH_1):PAGE167_I130@PURE_QUANTA.Q_CAP_DIFFBUS(CHIPS)':
 '1': CDS_PINID='\1\';
NODE_NAME     J109 L4
 '@S9S_MB_2U_LIB.S9S_MB_2U(SCH_1):PAGE319_I53@PURE_QUANTA.CONN112_10137002101LF(CHIPS)':
 'L4': CDS_PINID='L4';
NET_NAME
'P5E_CPU1_PE2_TX_C_DN<5>'
 '@S9S_MB_2U_LIB.S9S_MB_2U(SCH_1):P5E_CPU1_PE2_TX_C_DN'<5>:
 C_SIGNAL='@s9s_mb_2u_lib.s9s_mb_2u(sch_1):p5e_cpu1_pe2_tx_c_dn(5)';
NODE_NAME     C762 1
 '@S9S_MB_2U_LIB.S9S_MB_2U(SCH_1):PAGE167_I136@PURE_QUANTA.Q_CAP_DIFFBUS(CHIPS)':
 '1': CDS_PINID='\1\';
NODE_NAME     J109 M3
 '@S9S_MB_2U_LIB.S9S_MB_2U(SCH_1):PAGE319_I53@PURE_QUANTA.CONN112_10137002101LF(CHIPS)':
 'M3': CDS_PINID='M3';
NET_NAME
'P5E_CPU1_PE2_TX_C_DN<6>'
 '@S9S_MB_2U_LIB.S9S_MB_2U(SCH_1):P5E_CPU1_PE2_TX_C_DN'<6>:
 C_SIGNAL='@s9s_mb_2u_lib.s9s_mb_2u(sch_1):p5e_cpu1_pe2_tx_c_dn(6)';
NODE_NAME     C760 1
 '@S9S_MB_2U_LIB.S9S_MB_2U(SCH_1):PAGE167_I138@PURE_QUANTA.Q_CAP_DIFFBUS(CHIPS)':
 '1': CDS_PINID='\1\';
NODE_NAME     J109 L2
 '@S9S_MB_2U_LIB.S9S_MB_2U(SCH_1):PAGE319_I53@PURE_QUANTA.CONN112_10137002101LF(CHIPS)':
 'L2': CDS_PINID='L2';
NET_NAME
'P5E_CPU1_PE2_TX_C_DN<7>'
 '@S9S_MB_2U_LIB.S9S_MB_2U(SCH_1):P5E_CPU1_PE2_TX_C_DN'<7>:
 C_SIGNAL='@s9s_mb_2u_lib.s9s_mb_2u(sch_1):p5e_cpu1_pe2_tx_c_dn(7)';
NODE_NAME     C758 1
 '@S9S_MB_2U_LIB.S9S_MB_2U(SCH_1):PAGE167_I140@PURE_QUANTA.Q_CAP_DIFFBUS(CHIPS)':
 '1': CDS_PINID='\1\';
NODE_NAME     J109 M1
 '@S9S_MB_2U_LIB.S9S_MB_2U(SCH_1):PAGE319_I53@PURE_QUANTA.CONN112_10137002101LF(CHIPS)':
 'M1': CDS_PINID='M1';
NET_NAME
'P5E_CPU1_PE2_TX_C_DN<8>'
 '@S9S_MB_2U_LIB.S9S_MB_2U(SCH_1):P5E_CPU1_PE2_TX_C_DN'<8>:
 C_SIGNAL='@s9s_mb_2u_lib.s9s_mb_2u(sch_1):p5e_cpu1_pe2_tx_c_dn(8)';
NODE_NAME     C756 1
 '@S9S_MB_2U_LIB.S9S_MB_2U(SCH_1):PAGE167_I154@PURE_QUANTA.Q_CAP_DIFFBUS(CHIPS)':
 '1': CDS_PINID='\1\';
NODE_NAME     J110 L8
 '@S9S_MB_2U_LIB.S9S_MB_2U(SCH_1):PAGE318_I16@PURE_QUANTA.CONN112_10137002101LF(CHIPS)':
 'L8': CDS_PINID='L8';
NET_NAME
'P5E_CPU1_PE2_TX_C_DN<9>'
 '@S9S_MB_2U_LIB.S9S_MB_2U(SCH_1):P5E_CPU1_PE2_TX_C_DN'<9>:
 C_SIGNAL='@s9s_mb_2u_lib.s9s_mb_2u(sch_1):p5e_cpu1_pe2_tx_c_dn(9)';
NODE_NAME     C754 1
 '@S9S_MB_2U_LIB.S9S_MB_2U(SCH_1):PAGE167_I157@PURE_QUANTA.Q_CAP_DIFFBUS(CHIPS)':
 '1': CDS_PINID='\1\';
NODE_NAME     J110 M7
 '@S9S_MB_2U_LIB.S9S_MB_2U(SCH_1):PAGE318_I16@PURE_QUANTA.CONN112_10137002101LF(CHIPS)':
 'M7': CDS_PINID='M7';
NET_NAME
'P5E_CPU1_PE2_TX_C_DP<0>'
 '@S9S_MB_2U_LIB.S9S_MB_2U(SCH_1):P5E_CPU1_PE2_TX_C_DP'<0>:
 C_SIGNAL='@s9s_mb_2u_lib.s9s_mb_2u(sch_1):p5e_cpu1_pe2_tx_c_dp(0)';
NODE_NAME     C773 1
 '@S9S_MB_2U_LIB.S9S_MB_2U(SCH_1):PAGE167_I122@PURE_QUANTA.Q_CAP_DIFFBUS(CHIPS)':
 '1': CDS_PINID='\1\';
NODE_NAME     J109 K8
 '@S9S_MB_2U_LIB.S9S_MB_2U(SCH_1):PAGE319_I76@PURE_QUANTA.CONN112_10137002101LF(CHIPS)':
 'K8': CDS_PINID='K8';
NET_NAME
'P5E_CPU1_PE2_TX_C_DP<10>'
 '@S9S_MB_2U_LIB.S9S_MB_2U(SCH_1):P5E_CPU1_PE2_TX_C_DP'<10>:
 C_SIGNAL='@s9s_mb_2u_lib.s9s_mb_2u(sch_1):p5e_cpu1_pe2_tx_c_dp(10)';
NODE_NAME     C753 1
 '@S9S_MB_2U_LIB.S9S_MB_2U(SCH_1):PAGE167_I158@PURE_QUANTA.Q_CAP_DIFFBUS(CHIPS)':
 '1': CDS_PINID='\1\';
NODE_NAME     J110 K6
 '@S9S_MB_2U_LIB.S9S_MB_2U(SCH_1):PAGE318_I16@PURE_QUANTA.CONN112_10137002101LF(CHIPS)':
 'K6': CDS_PINID='K6';
NET_NAME
'P5E_CPU1_PE2_TX_C_DP<11>'
 '@S9S_MB_2U_LIB.S9S_MB_2U(SCH_1):P5E_CPU1_PE2_TX_C_DP'<11>:
 C_SIGNAL='@s9s_mb_2u_lib.s9s_mb_2u(sch_1):p5e_cpu1_pe2_tx_c_dp(11)';
NODE_NAME     C751 1
 '@S9S_MB_2U_LIB.S9S_MB_2U(SCH_1):PAGE167_I161@PURE_QUANTA.Q_CAP_DIFFBUS(CHIPS)':
 '1': CDS_PINID='\1\';
NODE_NAME     J110 L5
 '@S9S_MB_2U_LIB.S9S_MB_2U(SCH_1):PAGE318_I16@PURE_QUANTA.CONN112_10137002101LF(CHIPS)':
 'L5': CDS_PINID='L5';
NET_NAME
'P5E_CPU1_PE2_TX_C_DP<12>'
 '@S9S_MB_2U_LIB.S9S_MB_2U(SCH_1):P5E_CPU1_PE2_TX_C_DP'<12>:
 C_SIGNAL='@s9s_mb_2u_lib.s9s_mb_2u(sch_1):p5e_cpu1_pe2_tx_c_dp(12)';
NODE_NAME     C749 1
 '@S9S_MB_2U_LIB.S9S_MB_2U(SCH_1):PAGE167_I162@PURE_QUANTA.Q_CAP_DIFFBUS(CHIPS)':
 '1': CDS_PINID='\1\';
NODE_NAME     J110 K4
 '@S9S_MB_2U_LIB.S9S_MB_2U(SCH_1):PAGE318_I54@PURE_QUANTA.CONN112_10137002101LF(CHIPS)':
 'K4': CDS_PINID='K4';
NET_NAME
'P5E_CPU1_PE2_TX_C_DP<13>'
 '@S9S_MB_2U_LIB.S9S_MB_2U(SCH_1):P5E_CPU1_PE2_TX_C_DP'<13>:
 C_SIGNAL='@s9s_mb_2u_lib.s9s_mb_2u(sch_1):p5e_cpu1_pe2_tx_c_dp(13)';
NODE_NAME     C747 1
 '@S9S_MB_2U_LIB.S9S_MB_2U(SCH_1):PAGE167_I167@PURE_QUANTA.Q_CAP_DIFFBUS(CHIPS)':
 '1': CDS_PINID='\1\';
NODE_NAME     J110 L3
 '@S9S_MB_2U_LIB.S9S_MB_2U(SCH_1):PAGE318_I54@PURE_QUANTA.CONN112_10137002101LF(CHIPS)':
 'L3': CDS_PINID='L3';
NET_NAME
'P5E_CPU1_PE2_TX_C_DP<14>'
 '@S9S_MB_2U_LIB.S9S_MB_2U(SCH_1):P5E_CPU1_PE2_TX_C_DP'<14>:
 C_SIGNAL='@s9s_mb_2u_lib.s9s_mb_2u(sch_1):p5e_cpu1_pe2_tx_c_dp(14)';
NODE_NAME     C745 1
 '@S9S_MB_2U_LIB.S9S_MB_2U(SCH_1):PAGE167_I169@PURE_QUANTA.Q_CAP_DIFFBUS(CHIPS)':
 '1': CDS_PINID='\1\';
NODE_NAME     J110 K2
 '@S9S_MB_2U_LIB.S9S_MB_2U(SCH_1):PAGE318_I54@PURE_QUANTA.CONN112_10137002101LF(CHIPS)':
 'K2': CDS_PINID='K2';
NET_NAME
'P5E_CPU1_PE2_TX_C_DP<15>'
 '@S9S_MB_2U_LIB.S9S_MB_2U(SCH_1):P5E_CPU1_PE2_TX_C_DP'<15>:
 C_SIGNAL='@s9s_mb_2u_lib.s9s_mb_2u(sch_1):p5e_cpu1_pe2_tx_c_dp(15)';
NODE_NAME     C743 1
 '@S9S_MB_2U_LIB.S9S_MB_2U(SCH_1):PAGE167_I171@PURE_QUANTA.Q_CAP_DIFFBUS(CHIPS)':
 '1': CDS_PINID='\1\';
NODE_NAME     J110 L1
 '@S9S_MB_2U_LIB.S9S_MB_2U(SCH_1):PAGE318_I54@PURE_QUANTA.CONN112_10137002101LF(CHIPS)':
 'L1': CDS_PINID='L1';
NET_NAME
'P5E_CPU1_PE2_TX_C_DP<1>'
 '@S9S_MB_2U_LIB.S9S_MB_2U(SCH_1):P5E_CPU1_PE2_TX_C_DP'<1>:
 C_SIGNAL='@s9s_mb_2u_lib.s9s_mb_2u(sch_1):p5e_cpu1_pe2_tx_c_dp(1)';
NODE_NAME     C771 1
 '@S9S_MB_2U_LIB.S9S_MB_2U(SCH_1):PAGE167_I124@PURE_QUANTA.Q_CAP_DIFFBUS(CHIPS)':
 '1': CDS_PINID='\1\';
NODE_NAME     J109 L7
 '@S9S_MB_2U_LIB.S9S_MB_2U(SCH_1):PAGE319_I76@PURE_QUANTA.CONN112_10137002101LF(CHIPS)':
 'L7': CDS_PINID='L7';
NET_NAME
'P5E_CPU1_PE2_TX_C_DP<2>'
 '@S9S_MB_2U_LIB.S9S_MB_2U(SCH_1):P5E_CPU1_PE2_TX_C_DP'<2>:
 C_SIGNAL='@s9s_mb_2u_lib.s9s_mb_2u(sch_1):p5e_cpu1_pe2_tx_c_dp(2)';
NODE_NAME     C769 1
 '@S9S_MB_2U_LIB.S9S_MB_2U(SCH_1):PAGE167_I126@PURE_QUANTA.Q_CAP_DIFFBUS(CHIPS)':
 '1': CDS_PINID='\1\';
NODE_NAME     J109 K6
 '@S9S_MB_2U_LIB.S9S_MB_2U(SCH_1):PAGE319_I76@PURE_QUANTA.CONN112_10137002101LF(CHIPS)':
 'K6': CDS_PINID='K6';
NET_NAME
'P5E_CPU1_PE2_TX_C_DP<3>'
 '@S9S_MB_2U_LIB.S9S_MB_2U(SCH_1):P5E_CPU1_PE2_TX_C_DP'<3>:
 C_SIGNAL='@s9s_mb_2u_lib.s9s_mb_2u(sch_1):p5e_cpu1_pe2_tx_c_dp(3)';
NODE_NAME     C767 1
 '@S9S_MB_2U_LIB.S9S_MB_2U(SCH_1):PAGE167_I128@PURE_QUANTA.Q_CAP_DIFFBUS(CHIPS)':
 '1': CDS_PINID='\1\';
NODE_NAME     J109 L5
 '@S9S_MB_2U_LIB.S9S_MB_2U(SCH_1):PAGE319_I76@PURE_QUANTA.CONN112_10137002101LF(CHIPS)':
 'L5': CDS_PINID='L5';
NET_NAME
'P5E_CPU1_PE2_TX_C_DP<4>'
 '@S9S_MB_2U_LIB.S9S_MB_2U(SCH_1):P5E_CPU1_PE2_TX_C_DP'<4>:
 C_SIGNAL='@s9s_mb_2u_lib.s9s_mb_2u(sch_1):p5e_cpu1_pe2_tx_c_dp(4)';
NODE_NAME     C765 1
 '@S9S_MB_2U_LIB.S9S_MB_2U(SCH_1):PAGE167_I131@PURE_QUANTA.Q_CAP_DIFFBUS(CHIPS)':
 '1': CDS_PINID='\1\';
NODE_NAME     J109 K4
 '@S9S_MB_2U_LIB.S9S_MB_2U(SCH_1):PAGE319_I53@PURE_QUANTA.CONN112_10137002101LF(CHIPS)':
 'K4': CDS_PINID='K4';
NET_NAME
'P5E_CPU1_PE2_TX_C_DP<5>'
 '@S9S_MB_2U_LIB.S9S_MB_2U(SCH_1):P5E_CPU1_PE2_TX_C_DP'<5>:
 C_SIGNAL='@s9s_mb_2u_lib.s9s_mb_2u(sch_1):p5e_cpu1_pe2_tx_c_dp(5)';
NODE_NAME     C763 1
 '@S9S_MB_2U_LIB.S9S_MB_2U(SCH_1):PAGE167_I135@PURE_QUANTA.Q_CAP_DIFFBUS(CHIPS)':
 '1': CDS_PINID='\1\';
NODE_NAME     J109 L3
 '@S9S_MB_2U_LIB.S9S_MB_2U(SCH_1):PAGE319_I53@PURE_QUANTA.CONN112_10137002101LF(CHIPS)':
 'L3': CDS_PINID='L3';
NET_NAME
'P5E_CPU1_PE2_TX_C_DP<6>'
 '@S9S_MB_2U_LIB.S9S_MB_2U(SCH_1):P5E_CPU1_PE2_TX_C_DP'<6>:
 C_SIGNAL='@s9s_mb_2u_lib.s9s_mb_2u(sch_1):p5e_cpu1_pe2_tx_c_dp(6)';
NODE_NAME     C761 1
 '@S9S_MB_2U_LIB.S9S_MB_2U(SCH_1):PAGE167_I137@PURE_QUANTA.Q_CAP_DIFFBUS(CHIPS)':
 '1': CDS_PINID='\1\';
NODE_NAME     J109 K2
 '@S9S_MB_2U_LIB.S9S_MB_2U(SCH_1):PAGE319_I53@PURE_QUANTA.CONN112_10137002101LF(CHIPS)':
 'K2': CDS_PINID='K2';
NET_NAME
'P5E_CPU1_PE2_TX_C_DP<7>'
 '@S9S_MB_2U_LIB.S9S_MB_2U(SCH_1):P5E_CPU1_PE2_TX_C_DP'<7>:
 C_SIGNAL='@s9s_mb_2u_lib.s9s_mb_2u(sch_1):p5e_cpu1_pe2_tx_c_dp(7)';
NODE_NAME     C759 1
 '@S9S_MB_2U_LIB.S9S_MB_2U(SCH_1):PAGE167_I139@PURE_QUANTA.Q_CAP_DIFFBUS(CHIPS)':
 '1': CDS_PINID='\1\';
NODE_NAME     J109 L1
 '@S9S_MB_2U_LIB.S9S_MB_2U(SCH_1):PAGE319_I53@PURE_QUANTA.CONN112_10137002101LF(CHIPS)':
 'L1': CDS_PINID='L1';
NET_NAME
'P5E_CPU1_PE2_TX_C_DP<8>'
 '@S9S_MB_2U_LIB.S9S_MB_2U(SCH_1):P5E_CPU1_PE2_TX_C_DP'<8>:
 C_SIGNAL='@s9s_mb_2u_lib.s9s_mb_2u(sch_1):p5e_cpu1_pe2_tx_c_dp(8)';
NODE_NAME     C757 1
 '@S9S_MB_2U_LIB.S9S_MB_2U(SCH_1):PAGE167_I155@PURE_QUANTA.Q_CAP_DIFFBUS(CHIPS)':
 '1': CDS_PINID='\1\';
NODE_NAME     J110 K8
 '@S9S_MB_2U_LIB.S9S_MB_2U(SCH_1):PAGE318_I16@PURE_QUANTA.CONN112_10137002101LF(CHIPS)':
 'K8': CDS_PINID='K8';
NET_NAME
'P5E_CPU1_PE2_TX_C_DP<9>'
 '@S9S_MB_2U_LIB.S9S_MB_2U(SCH_1):P5E_CPU1_PE2_TX_C_DP'<9>:
 C_SIGNAL='@s9s_mb_2u_lib.s9s_mb_2u(sch_1):p5e_cpu1_pe2_tx_c_dp(9)';
NODE_NAME     C755 1
 '@S9S_MB_2U_LIB.S9S_MB_2U(SCH_1):PAGE167_I156@PURE_QUANTA.Q_CAP_DIFFBUS(CHIPS)':
 '1': CDS_PINID='\1\';
NODE_NAME     J110 L7
 '@S9S_MB_2U_LIB.S9S_MB_2U(SCH_1):PAGE318_I16@PURE_QUANTA.CONN112_10137002101LF(CHIPS)':
 'L7': CDS_PINID='L7';
NET_NAME
'P5E_CPU1_PE2_TX_DN<0>'
 '@S9S_MB_2U_LIB.S9S_MB_2U(SCH_1):P5E_CPU1_PE2_TX_DN'<0>:
 C_SIGNAL='@s9s_mb_2u_lib.s9s_mb_2u(sch_1):p5e_cpu1_pe2_tx_dn(0)';
NODE_NAME     U1 CU13
 '@S9S_MB_2U_LIB.S9S_MB_2U(SCH_1):PAGE61_I54@PURE_QUANTA.SOCKET4677_AZIF0045P001C01CS(CHIPS)':
 'PE2_TX_DN0': CDS_PINID='PE2_TX_DN0';
NODE_NAME     C772 2
 '@S9S_MB_2U_LIB.S9S_MB_2U(SCH_1):PAGE167_I123@PURE_QUANTA.Q_CAP_DIFFBUS(CHIPS)':
 '2': CDS_PINID='\2\';
NET_NAME
'P5E_CPU1_PE2_TX_DN<10>'
 '@S9S_MB_2U_LIB.S9S_MB_2U(SCH_1):P5E_CPU1_PE2_TX_DN'<10>:
 C_SIGNAL='@s9s_mb_2u_lib.s9s_mb_2u(sch_1):p5e_cpu1_pe2_tx_dn(10)';
NODE_NAME     U1 DU13
 '@S9S_MB_2U_LIB.S9S_MB_2U(SCH_1):PAGE61_I54@PURE_QUANTA.SOCKET4677_AZIF0045P001C01CS(CHIPS)':
 'PE2_TX_DN10': CDS_PINID='PE2_TX_DN10';
NODE_NAME     C752 2
 '@S9S_MB_2U_LIB.S9S_MB_2U(SCH_1):PAGE167_I159@PURE_QUANTA.Q_CAP_DIFFBUS(CHIPS)':
 '2': CDS_PINID='\2\';
NET_NAME
'P5E_CPU1_PE2_TX_DN<11>'
 '@S9S_MB_2U_LIB.S9S_MB_2U(SCH_1):P5E_CPU1_PE2_TX_DN'<11>:
 C_SIGNAL='@s9s_mb_2u_lib.s9s_mb_2u(sch_1):p5e_cpu1_pe2_tx_dn(11)';
NODE_NAME     U1 DV14
 '@S9S_MB_2U_LIB.S9S_MB_2U(SCH_1):PAGE61_I54@PURE_QUANTA.SOCKET4677_AZIF0045P001C01CS(CHIPS)':
 'PE2_TX_DN11': CDS_PINID='PE2_TX_DN11';
NODE_NAME     C750 2
 '@S9S_MB_2U_LIB.S9S_MB_2U(SCH_1):PAGE167_I160@PURE_QUANTA.Q_CAP_DIFFBUS(CHIPS)':
 '2': CDS_PINID='\2\';
NET_NAME
'P5E_CPU1_PE2_TX_DN<12>'
 '@S9S_MB_2U_LIB.S9S_MB_2U(SCH_1):P5E_CPU1_PE2_TX_DN'<12>:
 C_SIGNAL='@s9s_mb_2u_lib.s9s_mb_2u(sch_1):p5e_cpu1_pe2_tx_dn(12)';
NODE_NAME     U1 EA13
 '@S9S_MB_2U_LIB.S9S_MB_2U(SCH_1):PAGE61_I54@PURE_QUANTA.SOCKET4677_AZIF0045P001C01CS(CHIPS)':
 'PE2_TX_DN12': CDS_PINID='PE2_TX_DN12';
NODE_NAME     C748 2
 '@S9S_MB_2U_LIB.S9S_MB_2U(SCH_1):PAGE167_I163@PURE_QUANTA.Q_CAP_DIFFBUS(CHIPS)':
 '2': CDS_PINID='\2\';
NET_NAME
'P5E_CPU1_PE2_TX_DN<13>'
 '@S9S_MB_2U_LIB.S9S_MB_2U(SCH_1):P5E_CPU1_PE2_TX_DN'<13>:
 C_SIGNAL='@s9s_mb_2u_lib.s9s_mb_2u(sch_1):p5e_cpu1_pe2_tx_dn(13)';
NODE_NAME     U1 EB14
 '@S9S_MB_2U_LIB.S9S_MB_2U(SCH_1):PAGE61_I54@PURE_QUANTA.SOCKET4677_AZIF0045P001C01CS(CHIPS)':
 'PE2_TX_DN13': CDS_PINID='PE2_TX_DN13';
NODE_NAME     C746 2
 '@S9S_MB_2U_LIB.S9S_MB_2U(SCH_1):PAGE167_I168@PURE_QUANTA.Q_CAP_DIFFBUS(CHIPS)':
 '2': CDS_PINID='\2\';
NET_NAME
'P5E_CPU1_PE2_TX_DN<14>'
 '@S9S_MB_2U_LIB.S9S_MB_2U(SCH_1):P5E_CPU1_PE2_TX_DN'<14>:
 C_SIGNAL='@s9s_mb_2u_lib.s9s_mb_2u(sch_1):p5e_cpu1_pe2_tx_dn(14)';
NODE_NAME     U1 EE13
 '@S9S_MB_2U_LIB.S9S_MB_2U(SCH_1):PAGE61_I54@PURE_QUANTA.SOCKET4677_AZIF0045P001C01CS(CHIPS)':
 'PE2_TX_DN14': CDS_PINID='PE2_TX_DN14';
NODE_NAME     C744 2
 '@S9S_MB_2U_LIB.S9S_MB_2U(SCH_1):PAGE167_I170@PURE_QUANTA.Q_CAP_DIFFBUS(CHIPS)':
 '2': CDS_PINID='\2\';
NET_NAME
'P5E_CPU1_PE2_TX_DN<15>'
 '@S9S_MB_2U_LIB.S9S_MB_2U(SCH_1):P5E_CPU1_PE2_TX_DN'<15>:
 C_SIGNAL='@s9s_mb_2u_lib.s9s_mb_2u(sch_1):p5e_cpu1_pe2_tx_dn(15)';
NODE_NAME     U1 EF14
 '@S9S_MB_2U_LIB.S9S_MB_2U(SCH_1):PAGE61_I54@PURE_QUANTA.SOCKET4677_AZIF0045P001C01CS(CHIPS)':
 'PE2_TX_DN15': CDS_PINID='PE2_TX_DN15';
NODE_NAME     C742 2
 '@S9S_MB_2U_LIB.S9S_MB_2U(SCH_1):PAGE167_I172@PURE_QUANTA.Q_CAP_DIFFBUS(CHIPS)':
 '2': CDS_PINID='\2\';
NET_NAME
'P5E_CPU1_PE2_TX_DN<1>'
 '@S9S_MB_2U_LIB.S9S_MB_2U(SCH_1):P5E_CPU1_PE2_TX_DN'<1>:
 C_SIGNAL='@s9s_mb_2u_lib.s9s_mb_2u(sch_1):p5e_cpu1_pe2_tx_dn(1)';
NODE_NAME     U1 CV14
 '@S9S_MB_2U_LIB.S9S_MB_2U(SCH_1):PAGE61_I54@PURE_QUANTA.SOCKET4677_AZIF0045P001C01CS(CHIPS)':
 'PE2_TX_DN1': CDS_PINID='PE2_TX_DN1';
NODE_NAME     C770 2
 '@S9S_MB_2U_LIB.S9S_MB_2U(SCH_1):PAGE167_I125@PURE_QUANTA.Q_CAP_DIFFBUS(CHIPS)':
 '2': CDS_PINID='\2\';
NET_NAME
'P5E_CPU1_PE2_TX_DN<2>'
 '@S9S_MB_2U_LIB.S9S_MB_2U(SCH_1):P5E_CPU1_PE2_TX_DN'<2>:
 C_SIGNAL='@s9s_mb_2u_lib.s9s_mb_2u(sch_1):p5e_cpu1_pe2_tx_dn(2)';
NODE_NAME     U1 DA13
 '@S9S_MB_2U_LIB.S9S_MB_2U(SCH_1):PAGE61_I54@PURE_QUANTA.SOCKET4677_AZIF0045P001C01CS(CHIPS)':
 'PE2_TX_DN2': CDS_PINID='PE2_TX_DN2';
NODE_NAME     C768 2
 '@S9S_MB_2U_LIB.S9S_MB_2U(SCH_1):PAGE167_I127@PURE_QUANTA.Q_CAP_DIFFBUS(CHIPS)':
 '2': CDS_PINID='\2\';
NET_NAME
'P5E_CPU1_PE2_TX_DN<3>'
 '@S9S_MB_2U_LIB.S9S_MB_2U(SCH_1):P5E_CPU1_PE2_TX_DN'<3>:
 C_SIGNAL='@s9s_mb_2u_lib.s9s_mb_2u(sch_1):p5e_cpu1_pe2_tx_dn(3)';
NODE_NAME     U1 DB14
 '@S9S_MB_2U_LIB.S9S_MB_2U(SCH_1):PAGE61_I54@PURE_QUANTA.SOCKET4677_AZIF0045P001C01CS(CHIPS)':
 'PE2_TX_DN3': CDS_PINID='PE2_TX_DN3';
NODE_NAME     C766 2
 '@S9S_MB_2U_LIB.S9S_MB_2U(SCH_1):PAGE167_I129@PURE_QUANTA.Q_CAP_DIFFBUS(CHIPS)':
 '2': CDS_PINID='\2\';
NET_NAME
'P5E_CPU1_PE2_TX_DN<4>'
 '@S9S_MB_2U_LIB.S9S_MB_2U(SCH_1):P5E_CPU1_PE2_TX_DN'<4>:
 C_SIGNAL='@s9s_mb_2u_lib.s9s_mb_2u(sch_1):p5e_cpu1_pe2_tx_dn(4)';
NODE_NAME     U1 DE13
 '@S9S_MB_2U_LIB.S9S_MB_2U(SCH_1):PAGE61_I54@PURE_QUANTA.SOCKET4677_AZIF0045P001C01CS(CHIPS)':
 'PE2_TX_DN4': CDS_PINID='PE2_TX_DN4';
NODE_NAME     C764 2
 '@S9S_MB_2U_LIB.S9S_MB_2U(SCH_1):PAGE167_I130@PURE_QUANTA.Q_CAP_DIFFBUS(CHIPS)':
 '2': CDS_PINID='\2\';
NET_NAME
'P5E_CPU1_PE2_TX_DN<5>'
 '@S9S_MB_2U_LIB.S9S_MB_2U(SCH_1):P5E_CPU1_PE2_TX_DN'<5>:
 C_SIGNAL='@s9s_mb_2u_lib.s9s_mb_2u(sch_1):p5e_cpu1_pe2_tx_dn(5)';
NODE_NAME     U1 DF14
 '@S9S_MB_2U_LIB.S9S_MB_2U(SCH_1):PAGE61_I54@PURE_QUANTA.SOCKET4677_AZIF0045P001C01CS(CHIPS)':
 'PE2_TX_DN5': CDS_PINID='PE2_TX_DN5';
NODE_NAME     C762 2
 '@S9S_MB_2U_LIB.S9S_MB_2U(SCH_1):PAGE167_I136@PURE_QUANTA.Q_CAP_DIFFBUS(CHIPS)':
 '2': CDS_PINID='\2\';
NET_NAME
'P5E_CPU1_PE2_TX_DN<6>'
 '@S9S_MB_2U_LIB.S9S_MB_2U(SCH_1):P5E_CPU1_PE2_TX_DN'<6>:
 C_SIGNAL='@s9s_mb_2u_lib.s9s_mb_2u(sch_1):p5e_cpu1_pe2_tx_dn(6)';
NODE_NAME     U1 DJ13
 '@S9S_MB_2U_LIB.S9S_MB_2U(SCH_1):PAGE61_I54@PURE_QUANTA.SOCKET4677_AZIF0045P001C01CS(CHIPS)':
 'PE2_TX_DN6': CDS_PINID='PE2_TX_DN6';
NODE_NAME     C760 2
 '@S9S_MB_2U_LIB.S9S_MB_2U(SCH_1):PAGE167_I138@PURE_QUANTA.Q_CAP_DIFFBUS(CHIPS)':
 '2': CDS_PINID='\2\';
NET_NAME
'P5E_CPU1_PE2_TX_DN<7>'
 '@S9S_MB_2U_LIB.S9S_MB_2U(SCH_1):P5E_CPU1_PE2_TX_DN'<7>:
 C_SIGNAL='@s9s_mb_2u_lib.s9s_mb_2u(sch_1):p5e_cpu1_pe2_tx_dn(7)';
NODE_NAME     U1 DK14
 '@S9S_MB_2U_LIB.S9S_MB_2U(SCH_1):PAGE61_I54@PURE_QUANTA.SOCKET4677_AZIF0045P001C01CS(CHIPS)':
 'PE2_TX_DN7': CDS_PINID='PE2_TX_DN7';
NODE_NAME     C758 2
 '@S9S_MB_2U_LIB.S9S_MB_2U(SCH_1):PAGE167_I140@PURE_QUANTA.Q_CAP_DIFFBUS(CHIPS)':
 '2': CDS_PINID='\2\';
NET_NAME
'P5E_CPU1_PE2_TX_DN<8>'
 '@S9S_MB_2U_LIB.S9S_MB_2U(SCH_1):P5E_CPU1_PE2_TX_DN'<8>:
 C_SIGNAL='@s9s_mb_2u_lib.s9s_mb_2u(sch_1):p5e_cpu1_pe2_tx_dn(8)';
NODE_NAME     U1 DN13
 '@S9S_MB_2U_LIB.S9S_MB_2U(SCH_1):PAGE61_I54@PURE_QUANTA.SOCKET4677_AZIF0045P001C01CS(CHIPS)':
 'PE2_TX_DN8': CDS_PINID='PE2_TX_DN8';
NODE_NAME     C756 2
 '@S9S_MB_2U_LIB.S9S_MB_2U(SCH_1):PAGE167_I154@PURE_QUANTA.Q_CAP_DIFFBUS(CHIPS)':
 '2': CDS_PINID='\2\';
NET_NAME
'P5E_CPU1_PE2_TX_DN<9>'
 '@S9S_MB_2U_LIB.S9S_MB_2U(SCH_1):P5E_CPU1_PE2_TX_DN'<9>:
 C_SIGNAL='@s9s_mb_2u_lib.s9s_mb_2u(sch_1):p5e_cpu1_pe2_tx_dn(9)';
NODE_NAME     U1 DP14
 '@S9S_MB_2U_LIB.S9S_MB_2U(SCH_1):PAGE61_I54@PURE_QUANTA.SOCKET4677_AZIF0045P001C01CS(CHIPS)':
 'PE2_TX_DN9': CDS_PINID='PE2_TX_DN9';
NODE_NAME     C754 2
 '@S9S_MB_2U_LIB.S9S_MB_2U(SCH_1):PAGE167_I157@PURE_QUANTA.Q_CAP_DIFFBUS(CHIPS)':
 '2': CDS_PINID='\2\';
NET_NAME
'P5E_CPU1_PE2_TX_DP<0>'
 '@S9S_MB_2U_LIB.S9S_MB_2U(SCH_1):P5E_CPU1_PE2_TX_DP'<0>:
 C_SIGNAL='@s9s_mb_2u_lib.s9s_mb_2u(sch_1):p5e_cpu1_pe2_tx_dp(0)';
NODE_NAME     U1 CT14
 '@S9S_MB_2U_LIB.S9S_MB_2U(SCH_1):PAGE61_I54@PURE_QUANTA.SOCKET4677_AZIF0045P001C01CS(CHIPS)':
 'PE2_TX_DP0': CDS_PINID='PE2_TX_DP0';
NODE_NAME     C773 2
 '@S9S_MB_2U_LIB.S9S_MB_2U(SCH_1):PAGE167_I122@PURE_QUANTA.Q_CAP_DIFFBUS(CHIPS)':
 '2': CDS_PINID='\2\';
NET_NAME
'P5E_CPU1_PE2_TX_DP<10>'
 '@S9S_MB_2U_LIB.S9S_MB_2U(SCH_1):P5E_CPU1_PE2_TX_DP'<10>:
 C_SIGNAL='@s9s_mb_2u_lib.s9s_mb_2u(sch_1):p5e_cpu1_pe2_tx_dp(10)';
NODE_NAME     U1 DT14
 '@S9S_MB_2U_LIB.S9S_MB_2U(SCH_1):PAGE61_I54@PURE_QUANTA.SOCKET4677_AZIF0045P001C01CS(CHIPS)':
 'PE2_TX_DP10': CDS_PINID='PE2_TX_DP10';
NODE_NAME     C753 2
 '@S9S_MB_2U_LIB.S9S_MB_2U(SCH_1):PAGE167_I158@PURE_QUANTA.Q_CAP_DIFFBUS(CHIPS)':
 '2': CDS_PINID='\2\';
NET_NAME
'P5E_CPU1_PE2_TX_DP<11>'
 '@S9S_MB_2U_LIB.S9S_MB_2U(SCH_1):P5E_CPU1_PE2_TX_DP'<11>:
 C_SIGNAL='@s9s_mb_2u_lib.s9s_mb_2u(sch_1):p5e_cpu1_pe2_tx_dp(11)';
NODE_NAME     U1 DW15
 '@S9S_MB_2U_LIB.S9S_MB_2U(SCH_1):PAGE61_I54@PURE_QUANTA.SOCKET4677_AZIF0045P001C01CS(CHIPS)':
 'PE2_TX_DP11': CDS_PINID='PE2_TX_DP11';
NODE_NAME     C751 2
 '@S9S_MB_2U_LIB.S9S_MB_2U(SCH_1):PAGE167_I161@PURE_QUANTA.Q_CAP_DIFFBUS(CHIPS)':
 '2': CDS_PINID='\2\';
NET_NAME
'P5E_CPU1_PE2_TX_DP<12>'
 '@S9S_MB_2U_LIB.S9S_MB_2U(SCH_1):P5E_CPU1_PE2_TX_DP'<12>:
 C_SIGNAL='@s9s_mb_2u_lib.s9s_mb_2u(sch_1):p5e_cpu1_pe2_tx_dp(12)';
NODE_NAME     U1 DY14
 '@S9S_MB_2U_LIB.S9S_MB_2U(SCH_1):PAGE61_I54@PURE_QUANTA.SOCKET4677_AZIF0045P001C01CS(CHIPS)':
 'PE2_TX_DP12': CDS_PINID='PE2_TX_DP12';
NODE_NAME     C749 2
 '@S9S_MB_2U_LIB.S9S_MB_2U(SCH_1):PAGE167_I162@PURE_QUANTA.Q_CAP_DIFFBUS(CHIPS)':
 '2': CDS_PINID='\2\';
NET_NAME
'P5E_CPU1_PE2_TX_DP<13>'
 '@S9S_MB_2U_LIB.S9S_MB_2U(SCH_1):P5E_CPU1_PE2_TX_DP'<13>:
 C_SIGNAL='@s9s_mb_2u_lib.s9s_mb_2u(sch_1):p5e_cpu1_pe2_tx_dp(13)';
NODE_NAME     U1 EC15
 '@S9S_MB_2U_LIB.S9S_MB_2U(SCH_1):PAGE61_I54@PURE_QUANTA.SOCKET4677_AZIF0045P001C01CS(CHIPS)':
 'PE2_TX_DP13': CDS_PINID='PE2_TX_DP13';
NODE_NAME     C747 2
 '@S9S_MB_2U_LIB.S9S_MB_2U(SCH_1):PAGE167_I167@PURE_QUANTA.Q_CAP_DIFFBUS(CHIPS)':
 '2': CDS_PINID='\2\';
NET_NAME
'P5E_CPU1_PE2_TX_DP<14>'
 '@S9S_MB_2U_LIB.S9S_MB_2U(SCH_1):P5E_CPU1_PE2_TX_DP'<14>:
 C_SIGNAL='@s9s_mb_2u_lib.s9s_mb_2u(sch_1):p5e_cpu1_pe2_tx_dp(14)';
NODE_NAME     U1 ED14
 '@S9S_MB_2U_LIB.S9S_MB_2U(SCH_1):PAGE61_I54@PURE_QUANTA.SOCKET4677_AZIF0045P001C01CS(CHIPS)':
 'PE2_TX_DP14': CDS_PINID='PE2_TX_DP14';
NODE_NAME     C745 2
 '@S9S_MB_2U_LIB.S9S_MB_2U(SCH_1):PAGE167_I169@PURE_QUANTA.Q_CAP_DIFFBUS(CHIPS)':
 '2': CDS_PINID='\2\';
NET_NAME
'P5E_CPU1_PE2_TX_DP<15>'
 '@S9S_MB_2U_LIB.S9S_MB_2U(SCH_1):P5E_CPU1_PE2_TX_DP'<15>:
 C_SIGNAL='@s9s_mb_2u_lib.s9s_mb_2u(sch_1):p5e_cpu1_pe2_tx_dp(15)';
NODE_NAME     U1 EG15
 '@S9S_MB_2U_LIB.S9S_MB_2U(SCH_1):PAGE61_I54@PURE_QUANTA.SOCKET4677_AZIF0045P001C01CS(CHIPS)':
 'PE2_TX_DP15': CDS_PINID='PE2_TX_DP15';
NODE_NAME     C743 2
 '@S9S_MB_2U_LIB.S9S_MB_2U(SCH_1):PAGE167_I171@PURE_QUANTA.Q_CAP_DIFFBUS(CHIPS)':
 '2': CDS_PINID='\2\';
NET_NAME
'P5E_CPU1_PE2_TX_DP<1>'
 '@S9S_MB_2U_LIB.S9S_MB_2U(SCH_1):P5E_CPU1_PE2_TX_DP'<1>:
 C_SIGNAL='@s9s_mb_2u_lib.s9s_mb_2u(sch_1):p5e_cpu1_pe2_tx_dp(1)';
NODE_NAME     U1 CW15
 '@S9S_MB_2U_LIB.S9S_MB_2U(SCH_1):PAGE61_I54@PURE_QUANTA.SOCKET4677_AZIF0045P001C01CS(CHIPS)':
 'PE2_TX_DP1': CDS_PINID='PE2_TX_DP1';
NODE_NAME     C771 2
 '@S9S_MB_2U_LIB.S9S_MB_2U(SCH_1):PAGE167_I124@PURE_QUANTA.Q_CAP_DIFFBUS(CHIPS)':
 '2': CDS_PINID='\2\';
NET_NAME
'P5E_CPU1_PE2_TX_DP<2>'
 '@S9S_MB_2U_LIB.S9S_MB_2U(SCH_1):P5E_CPU1_PE2_TX_DP'<2>:
 C_SIGNAL='@s9s_mb_2u_lib.s9s_mb_2u(sch_1):p5e_cpu1_pe2_tx_dp(2)';
NODE_NAME     U1 CY14
 '@S9S_MB_2U_LIB.S9S_MB_2U(SCH_1):PAGE61_I54@PURE_QUANTA.SOCKET4677_AZIF0045P001C01CS(CHIPS)':
 'PE2_TX_DP2': CDS_PINID='PE2_TX_DP2';
NODE_NAME     C769 2
 '@S9S_MB_2U_LIB.S9S_MB_2U(SCH_1):PAGE167_I126@PURE_QUANTA.Q_CAP_DIFFBUS(CHIPS)':
 '2': CDS_PINID='\2\';
NET_NAME
'P5E_CPU1_PE2_TX_DP<3>'
 '@S9S_MB_2U_LIB.S9S_MB_2U(SCH_1):P5E_CPU1_PE2_TX_DP'<3>:
 C_SIGNAL='@s9s_mb_2u_lib.s9s_mb_2u(sch_1):p5e_cpu1_pe2_tx_dp(3)';
NODE_NAME     U1 DC15
 '@S9S_MB_2U_LIB.S9S_MB_2U(SCH_1):PAGE61_I54@PURE_QUANTA.SOCKET4677_AZIF0045P001C01CS(CHIPS)':
 'PE2_TX_DP3': CDS_PINID='PE2_TX_DP3';
NODE_NAME     C767 2
 '@S9S_MB_2U_LIB.S9S_MB_2U(SCH_1):PAGE167_I128@PURE_QUANTA.Q_CAP_DIFFBUS(CHIPS)':
 '2': CDS_PINID='\2\';
NET_NAME
'P5E_CPU1_PE2_TX_DP<4>'
 '@S9S_MB_2U_LIB.S9S_MB_2U(SCH_1):P5E_CPU1_PE2_TX_DP'<4>:
 C_SIGNAL='@s9s_mb_2u_lib.s9s_mb_2u(sch_1):p5e_cpu1_pe2_tx_dp(4)';
NODE_NAME     U1 DD14
 '@S9S_MB_2U_LIB.S9S_MB_2U(SCH_1):PAGE61_I54@PURE_QUANTA.SOCKET4677_AZIF0045P001C01CS(CHIPS)':
 'PE2_TX_DP4': CDS_PINID='PE2_TX_DP4';
NODE_NAME     C765 2
 '@S9S_MB_2U_LIB.S9S_MB_2U(SCH_1):PAGE167_I131@PURE_QUANTA.Q_CAP_DIFFBUS(CHIPS)':
 '2': CDS_PINID='\2\';
NET_NAME
'P5E_CPU1_PE2_TX_DP<5>'
 '@S9S_MB_2U_LIB.S9S_MB_2U(SCH_1):P5E_CPU1_PE2_TX_DP'<5>:
 C_SIGNAL='@s9s_mb_2u_lib.s9s_mb_2u(sch_1):p5e_cpu1_pe2_tx_dp(5)';
NODE_NAME     U1 DG15
 '@S9S_MB_2U_LIB.S9S_MB_2U(SCH_1):PAGE61_I54@PURE_QUANTA.SOCKET4677_AZIF0045P001C01CS(CHIPS)':
 'PE2_TX_DP5': CDS_PINID='PE2_TX_DP5';
NODE_NAME     C763 2
 '@S9S_MB_2U_LIB.S9S_MB_2U(SCH_1):PAGE167_I135@PURE_QUANTA.Q_CAP_DIFFBUS(CHIPS)':
 '2': CDS_PINID='\2\';
NET_NAME
'P5E_CPU1_PE2_TX_DP<6>'
 '@S9S_MB_2U_LIB.S9S_MB_2U(SCH_1):P5E_CPU1_PE2_TX_DP'<6>:
 C_SIGNAL='@s9s_mb_2u_lib.s9s_mb_2u(sch_1):p5e_cpu1_pe2_tx_dp(6)';
NODE_NAME     U1 DH14
 '@S9S_MB_2U_LIB.S9S_MB_2U(SCH_1):PAGE61_I54@PURE_QUANTA.SOCKET4677_AZIF0045P001C01CS(CHIPS)':
 'PE2_TX_DP6': CDS_PINID='PE2_TX_DP6';
NODE_NAME     C761 2
 '@S9S_MB_2U_LIB.S9S_MB_2U(SCH_1):PAGE167_I137@PURE_QUANTA.Q_CAP_DIFFBUS(CHIPS)':
 '2': CDS_PINID='\2\';
NET_NAME
'P5E_CPU1_PE2_TX_DP<7>'
 '@S9S_MB_2U_LIB.S9S_MB_2U(SCH_1):P5E_CPU1_PE2_TX_DP'<7>:
 C_SIGNAL='@s9s_mb_2u_lib.s9s_mb_2u(sch_1):p5e_cpu1_pe2_tx_dp(7)';
NODE_NAME     U1 DL15
 '@S9S_MB_2U_LIB.S9S_MB_2U(SCH_1):PAGE61_I54@PURE_QUANTA.SOCKET4677_AZIF0045P001C01CS(CHIPS)':
 'PE2_TX_DP7': CDS_PINID='PE2_TX_DP7';
NODE_NAME     C759 2
 '@S9S_MB_2U_LIB.S9S_MB_2U(SCH_1):PAGE167_I139@PURE_QUANTA.Q_CAP_DIFFBUS(CHIPS)':
 '2': CDS_PINID='\2\';
NET_NAME
'P5E_CPU1_PE2_TX_DP<8>'
 '@S9S_MB_2U_LIB.S9S_MB_2U(SCH_1):P5E_CPU1_PE2_TX_DP'<8>:
 C_SIGNAL='@s9s_mb_2u_lib.s9s_mb_2u(sch_1):p5e_cpu1_pe2_tx_dp(8)';
NODE_NAME     U1 DM14
 '@S9S_MB_2U_LIB.S9S_MB_2U(SCH_1):PAGE61_I54@PURE_QUANTA.SOCKET4677_AZIF0045P001C01CS(CHIPS)':
 'PE2_TX_DP8': CDS_PINID='PE2_TX_DP8';
NODE_NAME     C757 2
 '@S9S_MB_2U_LIB.S9S_MB_2U(SCH_1):PAGE167_I155@PURE_QUANTA.Q_CAP_DIFFBUS(CHIPS)':
 '2': CDS_PINID='\2\';
NET_NAME
'P5E_CPU1_PE2_TX_DP<9>'
 '@S9S_MB_2U_LIB.S9S_MB_2U(SCH_1):P5E_CPU1_PE2_TX_DP'<9>:
 C_SIGNAL='@s9s_mb_2u_lib.s9s_mb_2u(sch_1):p5e_cpu1_pe2_tx_dp(9)';
NODE_NAME     U1 DR15
 '@S9S_MB_2U_LIB.S9S_MB_2U(SCH_1):PAGE61_I54@PURE_QUANTA.SOCKET4677_AZIF0045P001C01CS(CHIPS)':
 'PE2_TX_DP9': CDS_PINID='PE2_TX_DP9';
NODE_NAME     C755 2
 '@S9S_MB_2U_LIB.S9S_MB_2U(SCH_1):PAGE167_I156@PURE_QUANTA.Q_CAP_DIFFBUS(CHIPS)':
 '2': CDS_PINID='\2\';
NET_NAME
'P5E_CPU1_PE3_RX_DN<0>'
 '@S9S_MB_2U_LIB.S9S_MB_2U(SCH_1):P5E_CPU1_PE3_RX_DN'<0>:
 C_SIGNAL='@s9s_mb_2u_lib.s9s_mb_2u(sch_1):p5e_cpu1_pe3_rx_dn(0)';
NODE_NAME     U1 EH89
 '@S9S_MB_2U_LIB.S9S_MB_2U(SCH_1):PAGE61_I12@PURE_QUANTA.SOCKET4677_AZIF0045P001C01CS(CHIPS)':
 'PE3_RX_DN0': CDS_PINID='PE3_RX_DN0';
NODE_NAME     J109 C8
 '@S9S_MB_2U_LIB.S9S_MB_2U(SCH_1):PAGE319_I76@PURE_QUANTA.CONN112_10137002101LF(CHIPS)':
 'C8': CDS_PINID='C8';
NET_NAME
'P5E_CPU1_PE3_RX_DN<10>'
 '@S9S_MB_2U_LIB.S9S_MB_2U(SCH_1):P5E_CPU1_PE3_RX_DN'<10>:
 C_SIGNAL='@s9s_mb_2u_lib.s9s_mb_2u(sch_1):p5e_cpu1_pe3_rx_dn(10)';
NODE_NAME     U1 DG90
 '@S9S_MB_2U_LIB.S9S_MB_2U(SCH_1):PAGE61_I12@PURE_QUANTA.SOCKET4677_AZIF0045P001C01CS(CHIPS)':
 'PE3_RX_DN10': CDS_PINID='PE3_RX_DN10';
NODE_NAME     J110 B6
 '@S9S_MB_2U_LIB.S9S_MB_2U(SCH_1):PAGE318_I16@PURE_QUANTA.CONN112_10137002101LF(CHIPS)':
 'B6': CDS_PINID='B6';
NET_NAME
'P5E_CPU1_PE3_RX_DN<11>'
 '@S9S_MB_2U_LIB.S9S_MB_2U(SCH_1):P5E_CPU1_PE3_RX_DN'<11>:
 C_SIGNAL='@s9s_mb_2u_lib.s9s_mb_2u(sch_1):p5e_cpu1_pe3_rx_dn(11)';
NODE_NAME     U1 DD91
 '@S9S_MB_2U_LIB.S9S_MB_2U(SCH_1):PAGE61_I12@PURE_QUANTA.SOCKET4677_AZIF0045P001C01CS(CHIPS)':
 'PE3_RX_DN11': CDS_PINID='PE3_RX_DN11';
NODE_NAME     J110 C5
 '@S9S_MB_2U_LIB.S9S_MB_2U(SCH_1):PAGE318_I16@PURE_QUANTA.CONN112_10137002101LF(CHIPS)':
 'C5': CDS_PINID='C5';
NET_NAME
'P5E_CPU1_PE3_RX_DN<12>'
 '@S9S_MB_2U_LIB.S9S_MB_2U(SCH_1):P5E_CPU1_PE3_RX_DN'<12>:
 C_SIGNAL='@s9s_mb_2u_lib.s9s_mb_2u(sch_1):p5e_cpu1_pe3_rx_dn(12)';
NODE_NAME     U1 DB89
 '@S9S_MB_2U_LIB.S9S_MB_2U(SCH_1):PAGE61_I12@PURE_QUANTA.SOCKET4677_AZIF0045P001C01CS(CHIPS)':
 'PE3_RX_DN12': CDS_PINID='PE3_RX_DN12';
NODE_NAME     J110 C4
 '@S9S_MB_2U_LIB.S9S_MB_2U(SCH_1):PAGE318_I54@PURE_QUANTA.CONN112_10137002101LF(CHIPS)':
 'C4': CDS_PINID='C4';
NET_NAME
'P5E_CPU1_PE3_RX_DN<13>'
 '@S9S_MB_2U_LIB.S9S_MB_2U(SCH_1):P5E_CPU1_PE3_RX_DN'<13>:
 C_SIGNAL='@s9s_mb_2u_lib.s9s_mb_2u(sch_1):p5e_cpu1_pe3_rx_dn(13)';
NODE_NAME     U1 DA90
 '@S9S_MB_2U_LIB.S9S_MB_2U(SCH_1):PAGE61_I12@PURE_QUANTA.SOCKET4677_AZIF0045P001C01CS(CHIPS)':
 'PE3_RX_DN13': CDS_PINID='PE3_RX_DN13';
NODE_NAME     J110 D3
 '@S9S_MB_2U_LIB.S9S_MB_2U(SCH_1):PAGE318_I54@PURE_QUANTA.CONN112_10137002101LF(CHIPS)':
 'D3': CDS_PINID='D3';
NET_NAME
'P5E_CPU1_PE3_RX_DN<14>'
 '@S9S_MB_2U_LIB.S9S_MB_2U(SCH_1):P5E_CPU1_PE3_RX_DN'<14>:
 C_SIGNAL='@s9s_mb_2u_lib.s9s_mb_2u(sch_1):p5e_cpu1_pe3_rx_dn(14)';
NODE_NAME     U1 CV89
 '@S9S_MB_2U_LIB.S9S_MB_2U(SCH_1):PAGE61_I12@PURE_QUANTA.SOCKET4677_AZIF0045P001C01CS(CHIPS)':
 'PE3_RX_DN14': CDS_PINID='PE3_RX_DN14';
NODE_NAME     J110 C2
 '@S9S_MB_2U_LIB.S9S_MB_2U(SCH_1):PAGE318_I54@PURE_QUANTA.CONN112_10137002101LF(CHIPS)':
 'C2': CDS_PINID='C2';
NET_NAME
'P5E_CPU1_PE3_RX_DN<15>'
 '@S9S_MB_2U_LIB.S9S_MB_2U(SCH_1):P5E_CPU1_PE3_RX_DN'<15>:
 C_SIGNAL='@s9s_mb_2u_lib.s9s_mb_2u(sch_1):p5e_cpu1_pe3_rx_dn(15)';
NODE_NAME     U1 CU90
 '@S9S_MB_2U_LIB.S9S_MB_2U(SCH_1):PAGE61_I12@PURE_QUANTA.SOCKET4677_AZIF0045P001C01CS(CHIPS)':
 'PE3_RX_DN15': CDS_PINID='PE3_RX_DN15';
NODE_NAME     J110 D1
 '@S9S_MB_2U_LIB.S9S_MB_2U(SCH_1):PAGE318_I54@PURE_QUANTA.CONN112_10137002101LF(CHIPS)':
 'D1': CDS_PINID='D1';
NET_NAME
'P5E_CPU1_PE3_RX_DN<1>'
 '@S9S_MB_2U_LIB.S9S_MB_2U(SCH_1):P5E_CPU1_PE3_RX_DN'<1>:
 C_SIGNAL='@s9s_mb_2u_lib.s9s_mb_2u(sch_1):p5e_cpu1_pe3_rx_dn(1)';
NODE_NAME     U1 ED91
 '@S9S_MB_2U_LIB.S9S_MB_2U(SCH_1):PAGE61_I12@PURE_QUANTA.SOCKET4677_AZIF0045P001C01CS(CHIPS)':
 'PE3_RX_DN1': CDS_PINID='PE3_RX_DN1';
NODE_NAME     J109 C7
 '@S9S_MB_2U_LIB.S9S_MB_2U(SCH_1):PAGE319_I76@PURE_QUANTA.CONN112_10137002101LF(CHIPS)':
 'C7': CDS_PINID='C7';
NET_NAME
'P5E_CPU1_PE3_RX_DN<2>'
 '@S9S_MB_2U_LIB.S9S_MB_2U(SCH_1):P5E_CPU1_PE3_RX_DN'<2>:
 C_SIGNAL='@s9s_mb_2u_lib.s9s_mb_2u(sch_1):p5e_cpu1_pe3_rx_dn(2)';
NODE_NAME     U1 EC90
 '@S9S_MB_2U_LIB.S9S_MB_2U(SCH_1):PAGE61_I12@PURE_QUANTA.SOCKET4677_AZIF0045P001C01CS(CHIPS)':
 'PE3_RX_DN2': CDS_PINID='PE3_RX_DN2';
NODE_NAME     J109 B6
 '@S9S_MB_2U_LIB.S9S_MB_2U(SCH_1):PAGE319_I76@PURE_QUANTA.CONN112_10137002101LF(CHIPS)':
 'B6': CDS_PINID='B6';
NET_NAME
'P5E_CPU1_PE3_RX_DN<3>'
 '@S9S_MB_2U_LIB.S9S_MB_2U(SCH_1):P5E_CPU1_PE3_RX_DN'<3>:
 C_SIGNAL='@s9s_mb_2u_lib.s9s_mb_2u(sch_1):p5e_cpu1_pe3_rx_dn(3)';
NODE_NAME     U1 DY91
 '@S9S_MB_2U_LIB.S9S_MB_2U(SCH_1):PAGE61_I12@PURE_QUANTA.SOCKET4677_AZIF0045P001C01CS(CHIPS)':
 'PE3_RX_DN3': CDS_PINID='PE3_RX_DN3';
NODE_NAME     J109 C5
 '@S9S_MB_2U_LIB.S9S_MB_2U(SCH_1):PAGE319_I76@PURE_QUANTA.CONN112_10137002101LF(CHIPS)':
 'C5': CDS_PINID='C5';
NET_NAME
'P5E_CPU1_PE3_RX_DN<4>'
 '@S9S_MB_2U_LIB.S9S_MB_2U(SCH_1):P5E_CPU1_PE3_RX_DN'<4>:
 C_SIGNAL='@s9s_mb_2u_lib.s9s_mb_2u(sch_1):p5e_cpu1_pe3_rx_dn(4)';
NODE_NAME     U1 DV89
 '@S9S_MB_2U_LIB.S9S_MB_2U(SCH_1):PAGE61_I12@PURE_QUANTA.SOCKET4677_AZIF0045P001C01CS(CHIPS)':
 'PE3_RX_DN4': CDS_PINID='PE3_RX_DN4';
NODE_NAME     J109 C4
 '@S9S_MB_2U_LIB.S9S_MB_2U(SCH_1):PAGE319_I53@PURE_QUANTA.CONN112_10137002101LF(CHIPS)':
 'C4': CDS_PINID='C4';
NET_NAME
'P5E_CPU1_PE3_RX_DN<5>'
 '@S9S_MB_2U_LIB.S9S_MB_2U(SCH_1):P5E_CPU1_PE3_RX_DN'<5>:
 C_SIGNAL='@s9s_mb_2u_lib.s9s_mb_2u(sch_1):p5e_cpu1_pe3_rx_dn(5)';
NODE_NAME     U1 DU90
 '@S9S_MB_2U_LIB.S9S_MB_2U(SCH_1):PAGE61_I12@PURE_QUANTA.SOCKET4677_AZIF0045P001C01CS(CHIPS)':
 'PE3_RX_DN5': CDS_PINID='PE3_RX_DN5';
NODE_NAME     J109 D3
 '@S9S_MB_2U_LIB.S9S_MB_2U(SCH_1):PAGE319_I53@PURE_QUANTA.CONN112_10137002101LF(CHIPS)':
 'D3': CDS_PINID='D3';
NET_NAME
'P5E_CPU1_PE3_RX_DN<6>'
 '@S9S_MB_2U_LIB.S9S_MB_2U(SCH_1):P5E_CPU1_PE3_RX_DN'<6>:
 C_SIGNAL='@s9s_mb_2u_lib.s9s_mb_2u(sch_1):p5e_cpu1_pe3_rx_dn(6)';
NODE_NAME     U1 DP89
 '@S9S_MB_2U_LIB.S9S_MB_2U(SCH_1):PAGE61_I12@PURE_QUANTA.SOCKET4677_AZIF0045P001C01CS(CHIPS)':
 'PE3_RX_DN6': CDS_PINID='PE3_RX_DN6';
NODE_NAME     J109 C2
 '@S9S_MB_2U_LIB.S9S_MB_2U(SCH_1):PAGE319_I53@PURE_QUANTA.CONN112_10137002101LF(CHIPS)':
 'C2': CDS_PINID='C2';
NET_NAME
'P5E_CPU1_PE3_RX_DN<7>'
 '@S9S_MB_2U_LIB.S9S_MB_2U(SCH_1):P5E_CPU1_PE3_RX_DN'<7>:
 C_SIGNAL='@s9s_mb_2u_lib.s9s_mb_2u(sch_1):p5e_cpu1_pe3_rx_dn(7)';
NODE_NAME     U1 DN90
 '@S9S_MB_2U_LIB.S9S_MB_2U(SCH_1):PAGE61_I12@PURE_QUANTA.SOCKET4677_AZIF0045P001C01CS(CHIPS)':
 'PE3_RX_DN7': CDS_PINID='PE3_RX_DN7';
NODE_NAME     J109 D1
 '@S9S_MB_2U_LIB.S9S_MB_2U(SCH_1):PAGE319_I53@PURE_QUANTA.CONN112_10137002101LF(CHIPS)':
 'D1': CDS_PINID='D1';
NET_NAME
'P5E_CPU1_PE3_RX_DN<8>'
 '@S9S_MB_2U_LIB.S9S_MB_2U(SCH_1):P5E_CPU1_PE3_RX_DN'<8>:
 C_SIGNAL='@s9s_mb_2u_lib.s9s_mb_2u(sch_1):p5e_cpu1_pe3_rx_dn(8)';
NODE_NAME     U1 DL90
 '@S9S_MB_2U_LIB.S9S_MB_2U(SCH_1):PAGE61_I12@PURE_QUANTA.SOCKET4677_AZIF0045P001C01CS(CHIPS)':
 'PE3_RX_DN8': CDS_PINID='PE3_RX_DN8';
NODE_NAME     J110 B8
 '@S9S_MB_2U_LIB.S9S_MB_2U(SCH_1):PAGE318_I16@PURE_QUANTA.CONN112_10137002101LF(CHIPS)':
 'B8': CDS_PINID='B8';
NET_NAME
'P5E_CPU1_PE3_RX_DN<9>'
 '@S9S_MB_2U_LIB.S9S_MB_2U(SCH_1):P5E_CPU1_PE3_RX_DN'<9>:
 C_SIGNAL='@s9s_mb_2u_lib.s9s_mb_2u(sch_1):p5e_cpu1_pe3_rx_dn(9)';
NODE_NAME     U1 DH91
 '@S9S_MB_2U_LIB.S9S_MB_2U(SCH_1):PAGE61_I12@PURE_QUANTA.SOCKET4677_AZIF0045P001C01CS(CHIPS)':
 'PE3_RX_DN9': CDS_PINID='PE3_RX_DN9';
NODE_NAME     J110 C7
 '@S9S_MB_2U_LIB.S9S_MB_2U(SCH_1):PAGE318_I16@PURE_QUANTA.CONN112_10137002101LF(CHIPS)':
 'C7': CDS_PINID='C7';
NET_NAME
'P5E_CPU1_PE3_RX_DP<0>'
 '@S9S_MB_2U_LIB.S9S_MB_2U(SCH_1):P5E_CPU1_PE3_RX_DP'<0>:
 C_SIGNAL='@s9s_mb_2u_lib.s9s_mb_2u(sch_1):p5e_cpu1_pe3_rx_dp(0)';
NODE_NAME     U1 EJ90
 '@S9S_MB_2U_LIB.S9S_MB_2U(SCH_1):PAGE61_I12@PURE_QUANTA.SOCKET4677_AZIF0045P001C01CS(CHIPS)':
 'PE3_RX_DP0': CDS_PINID='PE3_RX_DP0';
NODE_NAME     J109 B8
 '@S9S_MB_2U_LIB.S9S_MB_2U(SCH_1):PAGE319_I76@PURE_QUANTA.CONN112_10137002101LF(CHIPS)':
 'B8': CDS_PINID='B8';
NET_NAME
'P5E_CPU1_PE3_RX_DP<10>'
 '@S9S_MB_2U_LIB.S9S_MB_2U(SCH_1):P5E_CPU1_PE3_RX_DP'<10>:
 C_SIGNAL='@s9s_mb_2u_lib.s9s_mb_2u(sch_1):p5e_cpu1_pe3_rx_dp(10)';
NODE_NAME     U1 DF89
 '@S9S_MB_2U_LIB.S9S_MB_2U(SCH_1):PAGE61_I12@PURE_QUANTA.SOCKET4677_AZIF0045P001C01CS(CHIPS)':
 'PE3_RX_DP10': CDS_PINID='PE3_RX_DP10';
NODE_NAME     J110 C6
 '@S9S_MB_2U_LIB.S9S_MB_2U(SCH_1):PAGE318_I16@PURE_QUANTA.CONN112_10137002101LF(CHIPS)':
 'C6': CDS_PINID='C6';
NET_NAME
'P5E_CPU1_PE3_RX_DP<11>'
 '@S9S_MB_2U_LIB.S9S_MB_2U(SCH_1):P5E_CPU1_PE3_RX_DP'<11>:
 C_SIGNAL='@s9s_mb_2u_lib.s9s_mb_2u(sch_1):p5e_cpu1_pe3_rx_dp(11)';
NODE_NAME     U1 DE90
 '@S9S_MB_2U_LIB.S9S_MB_2U(SCH_1):PAGE61_I12@PURE_QUANTA.SOCKET4677_AZIF0045P001C01CS(CHIPS)':
 'PE3_RX_DP11': CDS_PINID='PE3_RX_DP11';
NODE_NAME     J110 D5
 '@S9S_MB_2U_LIB.S9S_MB_2U(SCH_1):PAGE318_I16@PURE_QUANTA.CONN112_10137002101LF(CHIPS)':
 'D5': CDS_PINID='D5';
NET_NAME
'P5E_CPU1_PE3_RX_DP<12>'
 '@S9S_MB_2U_LIB.S9S_MB_2U(SCH_1):P5E_CPU1_PE3_RX_DP'<12>:
 C_SIGNAL='@s9s_mb_2u_lib.s9s_mb_2u(sch_1):p5e_cpu1_pe3_rx_dp(12)';
NODE_NAME     U1 DC90
 '@S9S_MB_2U_LIB.S9S_MB_2U(SCH_1):PAGE61_I12@PURE_QUANTA.SOCKET4677_AZIF0045P001C01CS(CHIPS)':
 'PE3_RX_DP12': CDS_PINID='PE3_RX_DP12';
NODE_NAME     J110 B4
 '@S9S_MB_2U_LIB.S9S_MB_2U(SCH_1):PAGE318_I54@PURE_QUANTA.CONN112_10137002101LF(CHIPS)':
 'B4': CDS_PINID='B4';
NET_NAME
'P5E_CPU1_PE3_RX_DP<13>'
 '@S9S_MB_2U_LIB.S9S_MB_2U(SCH_1):P5E_CPU1_PE3_RX_DP'<13>:
 C_SIGNAL='@s9s_mb_2u_lib.s9s_mb_2u(sch_1):p5e_cpu1_pe3_rx_dp(13)';
NODE_NAME     U1 CY91
 '@S9S_MB_2U_LIB.S9S_MB_2U(SCH_1):PAGE61_I12@PURE_QUANTA.SOCKET4677_AZIF0045P001C01CS(CHIPS)':
 'PE3_RX_DP13': CDS_PINID='PE3_RX_DP13';
NODE_NAME     J110 C3
 '@S9S_MB_2U_LIB.S9S_MB_2U(SCH_1):PAGE318_I54@PURE_QUANTA.CONN112_10137002101LF(CHIPS)':
 'C3': CDS_PINID='C3';
NET_NAME
'P5E_CPU1_PE3_RX_DP<14>'
 '@S9S_MB_2U_LIB.S9S_MB_2U(SCH_1):P5E_CPU1_PE3_RX_DP'<14>:
 C_SIGNAL='@s9s_mb_2u_lib.s9s_mb_2u(sch_1):p5e_cpu1_pe3_rx_dp(14)';
NODE_NAME     U1 CW90
 '@S9S_MB_2U_LIB.S9S_MB_2U(SCH_1):PAGE61_I12@PURE_QUANTA.SOCKET4677_AZIF0045P001C01CS(CHIPS)':
 'PE3_RX_DP14': CDS_PINID='PE3_RX_DP14';
NODE_NAME     J110 B2
 '@S9S_MB_2U_LIB.S9S_MB_2U(SCH_1):PAGE318_I54@PURE_QUANTA.CONN112_10137002101LF(CHIPS)':
 'B2': CDS_PINID='B2';
NET_NAME
'P5E_CPU1_PE3_RX_DP<15>'
 '@S9S_MB_2U_LIB.S9S_MB_2U(SCH_1):P5E_CPU1_PE3_RX_DP'<15>:
 C_SIGNAL='@s9s_mb_2u_lib.s9s_mb_2u(sch_1):p5e_cpu1_pe3_rx_dp(15)';
NODE_NAME     U1 CT91
 '@S9S_MB_2U_LIB.S9S_MB_2U(SCH_1):PAGE61_I12@PURE_QUANTA.SOCKET4677_AZIF0045P001C01CS(CHIPS)':
 'PE3_RX_DP15': CDS_PINID='PE3_RX_DP15';
NODE_NAME     J110 C1
 '@S9S_MB_2U_LIB.S9S_MB_2U(SCH_1):PAGE318_I54@PURE_QUANTA.CONN112_10137002101LF(CHIPS)':
 'C1': CDS_PINID='C1';
NET_NAME
'P5E_CPU1_PE3_RX_DP<1>'
 '@S9S_MB_2U_LIB.S9S_MB_2U(SCH_1):P5E_CPU1_PE3_RX_DP'<1>:
 C_SIGNAL='@s9s_mb_2u_lib.s9s_mb_2u(sch_1):p5e_cpu1_pe3_rx_dp(1)';
NODE_NAME     U1 EE90
 '@S9S_MB_2U_LIB.S9S_MB_2U(SCH_1):PAGE61_I12@PURE_QUANTA.SOCKET4677_AZIF0045P001C01CS(CHIPS)':
 'PE3_RX_DP1': CDS_PINID='PE3_RX_DP1';
NODE_NAME     J109 D7
 '@S9S_MB_2U_LIB.S9S_MB_2U(SCH_1):PAGE319_I76@PURE_QUANTA.CONN112_10137002101LF(CHIPS)':
 'D7': CDS_PINID='D7';
NET_NAME
'P5E_CPU1_PE3_RX_DP<2>'
 '@S9S_MB_2U_LIB.S9S_MB_2U(SCH_1):P5E_CPU1_PE3_RX_DP'<2>:
 C_SIGNAL='@s9s_mb_2u_lib.s9s_mb_2u(sch_1):p5e_cpu1_pe3_rx_dp(2)';
NODE_NAME     U1 EB89
 '@S9S_MB_2U_LIB.S9S_MB_2U(SCH_1):PAGE61_I12@PURE_QUANTA.SOCKET4677_AZIF0045P001C01CS(CHIPS)':
 'PE3_RX_DP2': CDS_PINID='PE3_RX_DP2';
NODE_NAME     J109 C6
 '@S9S_MB_2U_LIB.S9S_MB_2U(SCH_1):PAGE319_I76@PURE_QUANTA.CONN112_10137002101LF(CHIPS)':
 'C6': CDS_PINID='C6';
NET_NAME
'P5E_CPU1_PE3_RX_DP<3>'
 '@S9S_MB_2U_LIB.S9S_MB_2U(SCH_1):P5E_CPU1_PE3_RX_DP'<3>:
 C_SIGNAL='@s9s_mb_2u_lib.s9s_mb_2u(sch_1):p5e_cpu1_pe3_rx_dp(3)';
NODE_NAME     U1 EA90
 '@S9S_MB_2U_LIB.S9S_MB_2U(SCH_1):PAGE61_I12@PURE_QUANTA.SOCKET4677_AZIF0045P001C01CS(CHIPS)':
 'PE3_RX_DP3': CDS_PINID='PE3_RX_DP3';
NODE_NAME     J109 D5
 '@S9S_MB_2U_LIB.S9S_MB_2U(SCH_1):PAGE319_I76@PURE_QUANTA.CONN112_10137002101LF(CHIPS)':
 'D5': CDS_PINID='D5';
NET_NAME
'P5E_CPU1_PE3_RX_DP<4>'
 '@S9S_MB_2U_LIB.S9S_MB_2U(SCH_1):P5E_CPU1_PE3_RX_DP'<4>:
 C_SIGNAL='@s9s_mb_2u_lib.s9s_mb_2u(sch_1):p5e_cpu1_pe3_rx_dp(4)';
NODE_NAME     U1 DW90
 '@S9S_MB_2U_LIB.S9S_MB_2U(SCH_1):PAGE61_I12@PURE_QUANTA.SOCKET4677_AZIF0045P001C01CS(CHIPS)':
 'PE3_RX_DP4': CDS_PINID='PE3_RX_DP4';
NODE_NAME     J109 B4
 '@S9S_MB_2U_LIB.S9S_MB_2U(SCH_1):PAGE319_I53@PURE_QUANTA.CONN112_10137002101LF(CHIPS)':
 'B4': CDS_PINID='B4';
NET_NAME
'P5E_CPU1_PE3_RX_DP<5>'
 '@S9S_MB_2U_LIB.S9S_MB_2U(SCH_1):P5E_CPU1_PE3_RX_DP'<5>:
 C_SIGNAL='@s9s_mb_2u_lib.s9s_mb_2u(sch_1):p5e_cpu1_pe3_rx_dp(5)';
NODE_NAME     U1 DT91
 '@S9S_MB_2U_LIB.S9S_MB_2U(SCH_1):PAGE61_I12@PURE_QUANTA.SOCKET4677_AZIF0045P001C01CS(CHIPS)':
 'PE3_RX_DP5': CDS_PINID='PE3_RX_DP5';
NODE_NAME     J109 C3
 '@S9S_MB_2U_LIB.S9S_MB_2U(SCH_1):PAGE319_I53@PURE_QUANTA.CONN112_10137002101LF(CHIPS)':
 'C3': CDS_PINID='C3';
NET_NAME
'P5E_CPU1_PE3_RX_DP<6>'
 '@S9S_MB_2U_LIB.S9S_MB_2U(SCH_1):P5E_CPU1_PE3_RX_DP'<6>:
 C_SIGNAL='@s9s_mb_2u_lib.s9s_mb_2u(sch_1):p5e_cpu1_pe3_rx_dp(6)';
NODE_NAME     U1 DR90
 '@S9S_MB_2U_LIB.S9S_MB_2U(SCH_1):PAGE61_I12@PURE_QUANTA.SOCKET4677_AZIF0045P001C01CS(CHIPS)':
 'PE3_RX_DP6': CDS_PINID='PE3_RX_DP6';
NODE_NAME     J109 B2
 '@S9S_MB_2U_LIB.S9S_MB_2U(SCH_1):PAGE319_I53@PURE_QUANTA.CONN112_10137002101LF(CHIPS)':
 'B2': CDS_PINID='B2';
NET_NAME
'P5E_CPU1_PE3_RX_DP<7>'
 '@S9S_MB_2U_LIB.S9S_MB_2U(SCH_1):P5E_CPU1_PE3_RX_DP'<7>:
 C_SIGNAL='@s9s_mb_2u_lib.s9s_mb_2u(sch_1):p5e_cpu1_pe3_rx_dp(7)';
NODE_NAME     U1 DM91
 '@S9S_MB_2U_LIB.S9S_MB_2U(SCH_1):PAGE61_I12@PURE_QUANTA.SOCKET4677_AZIF0045P001C01CS(CHIPS)':
 'PE3_RX_DP7': CDS_PINID='PE3_RX_DP7';
NODE_NAME     J109 C1
 '@S9S_MB_2U_LIB.S9S_MB_2U(SCH_1):PAGE319_I53@PURE_QUANTA.CONN112_10137002101LF(CHIPS)':
 'C1': CDS_PINID='C1';
NET_NAME
'P5E_CPU1_PE3_RX_DP<8>'
 '@S9S_MB_2U_LIB.S9S_MB_2U(SCH_1):P5E_CPU1_PE3_RX_DP'<8>:
 C_SIGNAL='@s9s_mb_2u_lib.s9s_mb_2u(sch_1):p5e_cpu1_pe3_rx_dp(8)';
NODE_NAME     U1 DK89
 '@S9S_MB_2U_LIB.S9S_MB_2U(SCH_1):PAGE61_I12@PURE_QUANTA.SOCKET4677_AZIF0045P001C01CS(CHIPS)':
 'PE3_RX_DP8': CDS_PINID='PE3_RX_DP8';
NODE_NAME     J110 C8
 '@S9S_MB_2U_LIB.S9S_MB_2U(SCH_1):PAGE318_I16@PURE_QUANTA.CONN112_10137002101LF(CHIPS)':
 'C8': CDS_PINID='C8';
NET_NAME
'P5E_CPU1_PE3_RX_DP<9>'
 '@S9S_MB_2U_LIB.S9S_MB_2U(SCH_1):P5E_CPU1_PE3_RX_DP'<9>:
 C_SIGNAL='@s9s_mb_2u_lib.s9s_mb_2u(sch_1):p5e_cpu1_pe3_rx_dp(9)';
NODE_NAME     U1 DJ90
 '@S9S_MB_2U_LIB.S9S_MB_2U(SCH_1):PAGE61_I12@PURE_QUANTA.SOCKET4677_AZIF0045P001C01CS(CHIPS)':
 'PE3_RX_DP9': CDS_PINID='PE3_RX_DP9';
NODE_NAME     J110 D7
 '@S9S_MB_2U_LIB.S9S_MB_2U(SCH_1):PAGE318_I16@PURE_QUANTA.CONN112_10137002101LF(CHIPS)':
 'D7': CDS_PINID='D7';
NET_NAME
'P5E_CPU1_PE3_TX_C_DN<0>'
 '@S9S_MB_2U_LIB.S9S_MB_2U(SCH_1):P5E_CPU1_PE3_TX_C_DN'<0>:
 C_SIGNAL='@s9s_mb_2u_lib.s9s_mb_2u(sch_1):p5e_cpu1_pe3_tx_c_dn(0)';
NODE_NAME     C1546 1
 '@S9S_MB_2U_LIB.S9S_MB_2U(SCH_1):PAGE168_I230@PURE_QUANTA.Q_CAP_DIFFBUS(CHIPS)':
 '1': CDS_PINID='\1\';
NODE_NAME     J109 I8
 '@S9S_MB_2U_LIB.S9S_MB_2U(SCH_1):PAGE319_I76@PURE_QUANTA.CONN112_10137002101LF(CHIPS)':
 'I8': CDS_PINID='I8';
NET_NAME
'P5E_CPU1_PE3_TX_C_DN<10>'
 '@S9S_MB_2U_LIB.S9S_MB_2U(SCH_1):P5E_CPU1_PE3_TX_C_DN'<10>:
 C_SIGNAL='@s9s_mb_2u_lib.s9s_mb_2u(sch_1):p5e_cpu1_pe3_tx_c_dn(10)';
NODE_NAME     C1526 1
 '@S9S_MB_2U_LIB.S9S_MB_2U(SCH_1):PAGE168_I282@PURE_QUANTA.Q_CAP_DIFFBUS(CHIPS)':
 '1': CDS_PINID='\1\';
NODE_NAME     J110 H6
 '@S9S_MB_2U_LIB.S9S_MB_2U(SCH_1):PAGE318_I16@PURE_QUANTA.CONN112_10137002101LF(CHIPS)':
 'H6': CDS_PINID='H6';
NET_NAME
'P5E_CPU1_PE3_TX_C_DN<11>'
 '@S9S_MB_2U_LIB.S9S_MB_2U(SCH_1):P5E_CPU1_PE3_TX_C_DN'<11>:
 C_SIGNAL='@s9s_mb_2u_lib.s9s_mb_2u(sch_1):p5e_cpu1_pe3_tx_c_dn(11)';
NODE_NAME     C1524 1
 '@S9S_MB_2U_LIB.S9S_MB_2U(SCH_1):PAGE168_I284@PURE_QUANTA.Q_CAP_DIFFBUS(CHIPS)':
 '1': CDS_PINID='\1\';
NODE_NAME     J110 I5
 '@S9S_MB_2U_LIB.S9S_MB_2U(SCH_1):PAGE318_I16@PURE_QUANTA.CONN112_10137002101LF(CHIPS)':
 'I5': CDS_PINID='I5';
NET_NAME
'P5E_CPU1_PE3_TX_C_DN<12>'
 '@S9S_MB_2U_LIB.S9S_MB_2U(SCH_1):P5E_CPU1_PE3_TX_C_DN'<12>:
 C_SIGNAL='@s9s_mb_2u_lib.s9s_mb_2u(sch_1):p5e_cpu1_pe3_tx_c_dn(12)';
NODE_NAME     C1522 1
 '@S9S_MB_2U_LIB.S9S_MB_2U(SCH_1):PAGE168_I286@PURE_QUANTA.Q_CAP_DIFFBUS(CHIPS)':
 '1': CDS_PINID='\1\';
NODE_NAME     J110 H4
 '@S9S_MB_2U_LIB.S9S_MB_2U(SCH_1):PAGE318_I54@PURE_QUANTA.CONN112_10137002101LF(CHIPS)':
 'H4': CDS_PINID='H4';
NET_NAME
'P5E_CPU1_PE3_TX_C_DN<13>'
 '@S9S_MB_2U_LIB.S9S_MB_2U(SCH_1):P5E_CPU1_PE3_TX_C_DN'<13>:
 C_SIGNAL='@s9s_mb_2u_lib.s9s_mb_2u(sch_1):p5e_cpu1_pe3_tx_c_dn(13)';
NODE_NAME     C1520 1
 '@S9S_MB_2U_LIB.S9S_MB_2U(SCH_1):PAGE168_I297@PURE_QUANTA.Q_CAP_DIFFBUS(CHIPS)':
 '1': CDS_PINID='\1\';
NODE_NAME     J110 I3
 '@S9S_MB_2U_LIB.S9S_MB_2U(SCH_1):PAGE318_I54@PURE_QUANTA.CONN112_10137002101LF(CHIPS)':
 'I3': CDS_PINID='I3';
NET_NAME
'P5E_CPU1_PE3_TX_C_DN<14>'
 '@S9S_MB_2U_LIB.S9S_MB_2U(SCH_1):P5E_CPU1_PE3_TX_C_DN'<14>:
 C_SIGNAL='@s9s_mb_2u_lib.s9s_mb_2u(sch_1):p5e_cpu1_pe3_tx_c_dn(14)';
NODE_NAME     C1518 1
 '@S9S_MB_2U_LIB.S9S_MB_2U(SCH_1):PAGE168_I300@PURE_QUANTA.Q_CAP_DIFFBUS(CHIPS)':
 '1': CDS_PINID='\1\';
NODE_NAME     J110 H2
 '@S9S_MB_2U_LIB.S9S_MB_2U(SCH_1):PAGE318_I54@PURE_QUANTA.CONN112_10137002101LF(CHIPS)':
 'H2': CDS_PINID='H2';
NET_NAME
'P5E_CPU1_PE3_TX_C_DN<15>'
 '@S9S_MB_2U_LIB.S9S_MB_2U(SCH_1):P5E_CPU1_PE3_TX_C_DN'<15>:
 C_SIGNAL='@s9s_mb_2u_lib.s9s_mb_2u(sch_1):p5e_cpu1_pe3_tx_c_dn(15)';
NODE_NAME     C1516 1
 '@S9S_MB_2U_LIB.S9S_MB_2U(SCH_1):PAGE168_I302@PURE_QUANTA.Q_CAP_DIFFBUS(CHIPS)':
 '1': CDS_PINID='\1\';
NODE_NAME     J110 I1
 '@S9S_MB_2U_LIB.S9S_MB_2U(SCH_1):PAGE318_I54@PURE_QUANTA.CONN112_10137002101LF(CHIPS)':
 'I1': CDS_PINID='I1';
NET_NAME
'P5E_CPU1_PE3_TX_C_DN<1>'
 '@S9S_MB_2U_LIB.S9S_MB_2U(SCH_1):P5E_CPU1_PE3_TX_C_DN'<1>:
 C_SIGNAL='@s9s_mb_2u_lib.s9s_mb_2u(sch_1):p5e_cpu1_pe3_tx_c_dn(1)';
NODE_NAME     C1544 1
 '@S9S_MB_2U_LIB.S9S_MB_2U(SCH_1):PAGE168_I232@PURE_QUANTA.Q_CAP_DIFFBUS(CHIPS)':
 '1': CDS_PINID='\1\';
NODE_NAME     J109 I7
 '@S9S_MB_2U_LIB.S9S_MB_2U(SCH_1):PAGE319_I76@PURE_QUANTA.CONN112_10137002101LF(CHIPS)':
 'I7': CDS_PINID='I7';
NET_NAME
'P5E_CPU1_PE3_TX_C_DN<2>'
 '@S9S_MB_2U_LIB.S9S_MB_2U(SCH_1):P5E_CPU1_PE3_TX_C_DN'<2>:
 C_SIGNAL='@s9s_mb_2u_lib.s9s_mb_2u(sch_1):p5e_cpu1_pe3_tx_c_dn(2)';
NODE_NAME     C1542 1
 '@S9S_MB_2U_LIB.S9S_MB_2U(SCH_1):PAGE168_I233@PURE_QUANTA.Q_CAP_DIFFBUS(CHIPS)':
 '1': CDS_PINID='\1\';
NODE_NAME     J109 H6
 '@S9S_MB_2U_LIB.S9S_MB_2U(SCH_1):PAGE319_I76@PURE_QUANTA.CONN112_10137002101LF(CHIPS)':
 'H6': CDS_PINID='H6';
NET_NAME
'P5E_CPU1_PE3_TX_C_DN<3>'
 '@S9S_MB_2U_LIB.S9S_MB_2U(SCH_1):P5E_CPU1_PE3_TX_C_DN'<3>:
 C_SIGNAL='@s9s_mb_2u_lib.s9s_mb_2u(sch_1):p5e_cpu1_pe3_tx_c_dn(3)';
NODE_NAME     C1540 1
 '@S9S_MB_2U_LIB.S9S_MB_2U(SCH_1):PAGE168_I236@PURE_QUANTA.Q_CAP_DIFFBUS(CHIPS)':
 '1': CDS_PINID='\1\';
NODE_NAME     J109 I5
 '@S9S_MB_2U_LIB.S9S_MB_2U(SCH_1):PAGE319_I76@PURE_QUANTA.CONN112_10137002101LF(CHIPS)':
 'I5': CDS_PINID='I5';
NET_NAME
'P5E_CPU1_PE3_TX_C_DN<4>'
 '@S9S_MB_2U_LIB.S9S_MB_2U(SCH_1):P5E_CPU1_PE3_TX_C_DN'<4>:
 C_SIGNAL='@s9s_mb_2u_lib.s9s_mb_2u(sch_1):p5e_cpu1_pe3_tx_c_dn(4)';
NODE_NAME     C1538 1
 '@S9S_MB_2U_LIB.S9S_MB_2U(SCH_1):PAGE168_I238@PURE_QUANTA.Q_CAP_DIFFBUS(CHIPS)':
 '1': CDS_PINID='\1\';
NODE_NAME     J109 H4
 '@S9S_MB_2U_LIB.S9S_MB_2U(SCH_1):PAGE319_I53@PURE_QUANTA.CONN112_10137002101LF(CHIPS)':
 'H4': CDS_PINID='H4';
NET_NAME
'P5E_CPU1_PE3_TX_C_DN<5>'
 '@S9S_MB_2U_LIB.S9S_MB_2U(SCH_1):P5E_CPU1_PE3_TX_C_DN'<5>:
 C_SIGNAL='@s9s_mb_2u_lib.s9s_mb_2u(sch_1):p5e_cpu1_pe3_tx_c_dn(5)';
NODE_NAME     C1536 1
 '@S9S_MB_2U_LIB.S9S_MB_2U(SCH_1):PAGE168_I250@PURE_QUANTA.Q_CAP_DIFFBUS(CHIPS)':
 '1': CDS_PINID='\1\';
NODE_NAME     J109 I3
 '@S9S_MB_2U_LIB.S9S_MB_2U(SCH_1):PAGE319_I53@PURE_QUANTA.CONN112_10137002101LF(CHIPS)':
 'I3': CDS_PINID='I3';
NET_NAME
'P5E_CPU1_PE3_TX_C_DN<6>'
 '@S9S_MB_2U_LIB.S9S_MB_2U(SCH_1):P5E_CPU1_PE3_TX_C_DN'<6>:
 C_SIGNAL='@s9s_mb_2u_lib.s9s_mb_2u(sch_1):p5e_cpu1_pe3_tx_c_dn(6)';
NODE_NAME     C1534 1
 '@S9S_MB_2U_LIB.S9S_MB_2U(SCH_1):PAGE168_I251@PURE_QUANTA.Q_CAP_DIFFBUS(CHIPS)':
 '1': CDS_PINID='\1\';
NODE_NAME     J109 H2
 '@S9S_MB_2U_LIB.S9S_MB_2U(SCH_1):PAGE319_I53@PURE_QUANTA.CONN112_10137002101LF(CHIPS)':
 'H2': CDS_PINID='H2';
NET_NAME
'P5E_CPU1_PE3_TX_C_DN<7>'
 '@S9S_MB_2U_LIB.S9S_MB_2U(SCH_1):P5E_CPU1_PE3_TX_C_DN'<7>:
 C_SIGNAL='@s9s_mb_2u_lib.s9s_mb_2u(sch_1):p5e_cpu1_pe3_tx_c_dn(7)';
NODE_NAME     C1532 1
 '@S9S_MB_2U_LIB.S9S_MB_2U(SCH_1):PAGE168_I254@PURE_QUANTA.Q_CAP_DIFFBUS(CHIPS)':
 '1': CDS_PINID='\1\';
NODE_NAME     J109 I1
 '@S9S_MB_2U_LIB.S9S_MB_2U(SCH_1):PAGE319_I53@PURE_QUANTA.CONN112_10137002101LF(CHIPS)':
 'I1': CDS_PINID='I1';
NET_NAME
'P5E_CPU1_PE3_TX_C_DN<8>'
 '@S9S_MB_2U_LIB.S9S_MB_2U(SCH_1):P5E_CPU1_PE3_TX_C_DN'<8>:
 C_SIGNAL='@s9s_mb_2u_lib.s9s_mb_2u(sch_1):p5e_cpu1_pe3_tx_c_dn(8)';
NODE_NAME     C1530 1
 '@S9S_MB_2U_LIB.S9S_MB_2U(SCH_1):PAGE168_I277@PURE_QUANTA.Q_CAP_DIFFBUS(CHIPS)':
 '1': CDS_PINID='\1\';
NODE_NAME     J110 H8
 '@S9S_MB_2U_LIB.S9S_MB_2U(SCH_1):PAGE318_I16@PURE_QUANTA.CONN112_10137002101LF(CHIPS)':
 'H8': CDS_PINID='H8';
NET_NAME
'P5E_CPU1_PE3_TX_C_DN<9>'
 '@S9S_MB_2U_LIB.S9S_MB_2U(SCH_1):P5E_CPU1_PE3_TX_C_DN'<9>:
 C_SIGNAL='@s9s_mb_2u_lib.s9s_mb_2u(sch_1):p5e_cpu1_pe3_tx_c_dn(9)';
NODE_NAME     C1528 1
 '@S9S_MB_2U_LIB.S9S_MB_2U(SCH_1):PAGE168_I280@PURE_QUANTA.Q_CAP_DIFFBUS(CHIPS)':
 '1': CDS_PINID='\1\';
NODE_NAME     J110 I7
 '@S9S_MB_2U_LIB.S9S_MB_2U(SCH_1):PAGE318_I16@PURE_QUANTA.CONN112_10137002101LF(CHIPS)':
 'I7': CDS_PINID='I7';
NET_NAME
'P5E_CPU1_PE3_TX_C_DP<0>'
 '@S9S_MB_2U_LIB.S9S_MB_2U(SCH_1):P5E_CPU1_PE3_TX_C_DP'<0>:
 C_SIGNAL='@s9s_mb_2u_lib.s9s_mb_2u(sch_1):p5e_cpu1_pe3_tx_c_dp(0)';
NODE_NAME     C1547 1
 '@S9S_MB_2U_LIB.S9S_MB_2U(SCH_1):PAGE168_I229@PURE_QUANTA.Q_CAP_DIFFBUS(CHIPS)':
 '1': CDS_PINID='\1\';
NODE_NAME     J109 H8
 '@S9S_MB_2U_LIB.S9S_MB_2U(SCH_1):PAGE319_I76@PURE_QUANTA.CONN112_10137002101LF(CHIPS)':
 'H8': CDS_PINID='H8';
NET_NAME
'P5E_CPU1_PE3_TX_C_DP<10>'
 '@S9S_MB_2U_LIB.S9S_MB_2U(SCH_1):P5E_CPU1_PE3_TX_C_DP'<10>:
 C_SIGNAL='@s9s_mb_2u_lib.s9s_mb_2u(sch_1):p5e_cpu1_pe3_tx_c_dp(10)';
NODE_NAME     C1527 1
 '@S9S_MB_2U_LIB.S9S_MB_2U(SCH_1):PAGE168_I281@PURE_QUANTA.Q_CAP_DIFFBUS(CHIPS)':
 '1': CDS_PINID='\1\';
NODE_NAME     J110 I6
 '@S9S_MB_2U_LIB.S9S_MB_2U(SCH_1):PAGE318_I16@PURE_QUANTA.CONN112_10137002101LF(CHIPS)':
 'I6': CDS_PINID='I6';
NET_NAME
'P5E_CPU1_PE3_TX_C_DP<11>'
 '@S9S_MB_2U_LIB.S9S_MB_2U(SCH_1):P5E_CPU1_PE3_TX_C_DP'<11>:
 C_SIGNAL='@s9s_mb_2u_lib.s9s_mb_2u(sch_1):p5e_cpu1_pe3_tx_c_dp(11)';
NODE_NAME     C1525 1
 '@S9S_MB_2U_LIB.S9S_MB_2U(SCH_1):PAGE168_I283@PURE_QUANTA.Q_CAP_DIFFBUS(CHIPS)':
 '1': CDS_PINID='\1\';
NODE_NAME     J110 J5
 '@S9S_MB_2U_LIB.S9S_MB_2U(SCH_1):PAGE318_I16@PURE_QUANTA.CONN112_10137002101LF(CHIPS)':
 'J5': CDS_PINID='J5';
NET_NAME
'P5E_CPU1_PE3_TX_C_DP<12>'
 '@S9S_MB_2U_LIB.S9S_MB_2U(SCH_1):P5E_CPU1_PE3_TX_C_DP'<12>:
 C_SIGNAL='@s9s_mb_2u_lib.s9s_mb_2u(sch_1):p5e_cpu1_pe3_tx_c_dp(12)';
NODE_NAME     C1523 1
 '@S9S_MB_2U_LIB.S9S_MB_2U(SCH_1):PAGE168_I285@PURE_QUANTA.Q_CAP_DIFFBUS(CHIPS)':
 '1': CDS_PINID='\1\';
NODE_NAME     J110 I4
 '@S9S_MB_2U_LIB.S9S_MB_2U(SCH_1):PAGE318_I54@PURE_QUANTA.CONN112_10137002101LF(CHIPS)':
 'I4': CDS_PINID='I4';
NET_NAME
'P5E_CPU1_PE3_TX_C_DP<13>'
 '@S9S_MB_2U_LIB.S9S_MB_2U(SCH_1):P5E_CPU1_PE3_TX_C_DP'<13>:
 C_SIGNAL='@s9s_mb_2u_lib.s9s_mb_2u(sch_1):p5e_cpu1_pe3_tx_c_dp(13)';
NODE_NAME     C1521 1
 '@S9S_MB_2U_LIB.S9S_MB_2U(SCH_1):PAGE168_I298@PURE_QUANTA.Q_CAP_DIFFBUS(CHIPS)':
 '1': CDS_PINID='\1\';
NODE_NAME     J110 J3
 '@S9S_MB_2U_LIB.S9S_MB_2U(SCH_1):PAGE318_I54@PURE_QUANTA.CONN112_10137002101LF(CHIPS)':
 'J3': CDS_PINID='J3';
NET_NAME
'P5E_CPU1_PE3_TX_C_DP<14>'
 '@S9S_MB_2U_LIB.S9S_MB_2U(SCH_1):P5E_CPU1_PE3_TX_C_DP'<14>:
 C_SIGNAL='@s9s_mb_2u_lib.s9s_mb_2u(sch_1):p5e_cpu1_pe3_tx_c_dp(14)';
NODE_NAME     C1519 1
 '@S9S_MB_2U_LIB.S9S_MB_2U(SCH_1):PAGE168_I299@PURE_QUANTA.Q_CAP_DIFFBUS(CHIPS)':
 '1': CDS_PINID='\1\';
NODE_NAME     J110 I2
 '@S9S_MB_2U_LIB.S9S_MB_2U(SCH_1):PAGE318_I54@PURE_QUANTA.CONN112_10137002101LF(CHIPS)':
 'I2': CDS_PINID='I2';
NET_NAME
'P5E_CPU1_PE3_TX_C_DP<15>'
 '@S9S_MB_2U_LIB.S9S_MB_2U(SCH_1):P5E_CPU1_PE3_TX_C_DP'<15>:
 C_SIGNAL='@s9s_mb_2u_lib.s9s_mb_2u(sch_1):p5e_cpu1_pe3_tx_c_dp(15)';
NODE_NAME     C1517 1
 '@S9S_MB_2U_LIB.S9S_MB_2U(SCH_1):PAGE168_I301@PURE_QUANTA.Q_CAP_DIFFBUS(CHIPS)':
 '1': CDS_PINID='\1\';
NODE_NAME     J110 J1
 '@S9S_MB_2U_LIB.S9S_MB_2U(SCH_1):PAGE318_I54@PURE_QUANTA.CONN112_10137002101LF(CHIPS)':
 'J1': CDS_PINID='J1';
NET_NAME
'P5E_CPU1_PE3_TX_C_DP<1>'
 '@S9S_MB_2U_LIB.S9S_MB_2U(SCH_1):P5E_CPU1_PE3_TX_C_DP'<1>:
 C_SIGNAL='@s9s_mb_2u_lib.s9s_mb_2u(sch_1):p5e_cpu1_pe3_tx_c_dp(1)';
NODE_NAME     C1545 1
 '@S9S_MB_2U_LIB.S9S_MB_2U(SCH_1):PAGE168_I231@PURE_QUANTA.Q_CAP_DIFFBUS(CHIPS)':
 '1': CDS_PINID='\1\';
NODE_NAME     J109 J7
 '@S9S_MB_2U_LIB.S9S_MB_2U(SCH_1):PAGE319_I76@PURE_QUANTA.CONN112_10137002101LF(CHIPS)':
 'J7': CDS_PINID='J7';
NET_NAME
'P5E_CPU1_PE3_TX_C_DP<2>'
 '@S9S_MB_2U_LIB.S9S_MB_2U(SCH_1):P5E_CPU1_PE3_TX_C_DP'<2>:
 C_SIGNAL='@s9s_mb_2u_lib.s9s_mb_2u(sch_1):p5e_cpu1_pe3_tx_c_dp(2)';
NODE_NAME     C1543 1
 '@S9S_MB_2U_LIB.S9S_MB_2U(SCH_1):PAGE168_I234@PURE_QUANTA.Q_CAP_DIFFBUS(CHIPS)':
 '1': CDS_PINID='\1\';
NODE_NAME     J109 I6
 '@S9S_MB_2U_LIB.S9S_MB_2U(SCH_1):PAGE319_I76@PURE_QUANTA.CONN112_10137002101LF(CHIPS)':
 'I6': CDS_PINID='I6';
NET_NAME
'P5E_CPU1_PE3_TX_C_DP<3>'
 '@S9S_MB_2U_LIB.S9S_MB_2U(SCH_1):P5E_CPU1_PE3_TX_C_DP'<3>:
 C_SIGNAL='@s9s_mb_2u_lib.s9s_mb_2u(sch_1):p5e_cpu1_pe3_tx_c_dp(3)';
NODE_NAME     C1541 1
 '@S9S_MB_2U_LIB.S9S_MB_2U(SCH_1):PAGE168_I235@PURE_QUANTA.Q_CAP_DIFFBUS(CHIPS)':
 '1': CDS_PINID='\1\';
NODE_NAME     J109 J5
 '@S9S_MB_2U_LIB.S9S_MB_2U(SCH_1):PAGE319_I76@PURE_QUANTA.CONN112_10137002101LF(CHIPS)':
 'J5': CDS_PINID='J5';
NET_NAME
'P5E_CPU1_PE3_TX_C_DP<4>'
 '@S9S_MB_2U_LIB.S9S_MB_2U(SCH_1):P5E_CPU1_PE3_TX_C_DP'<4>:
 C_SIGNAL='@s9s_mb_2u_lib.s9s_mb_2u(sch_1):p5e_cpu1_pe3_tx_c_dp(4)';
NODE_NAME     C1539 1
 '@S9S_MB_2U_LIB.S9S_MB_2U(SCH_1):PAGE168_I237@PURE_QUANTA.Q_CAP_DIFFBUS(CHIPS)':
 '1': CDS_PINID='\1\';
NODE_NAME     J109 I4
 '@S9S_MB_2U_LIB.S9S_MB_2U(SCH_1):PAGE319_I53@PURE_QUANTA.CONN112_10137002101LF(CHIPS)':
 'I4': CDS_PINID='I4';
NET_NAME
'P5E_CPU1_PE3_TX_C_DP<5>'
 '@S9S_MB_2U_LIB.S9S_MB_2U(SCH_1):P5E_CPU1_PE3_TX_C_DP'<5>:
 C_SIGNAL='@s9s_mb_2u_lib.s9s_mb_2u(sch_1):p5e_cpu1_pe3_tx_c_dp(5)';
NODE_NAME     C1537 1
 '@S9S_MB_2U_LIB.S9S_MB_2U(SCH_1):PAGE168_I249@PURE_QUANTA.Q_CAP_DIFFBUS(CHIPS)':
 '1': CDS_PINID='\1\';
NODE_NAME     J109 J3
 '@S9S_MB_2U_LIB.S9S_MB_2U(SCH_1):PAGE319_I53@PURE_QUANTA.CONN112_10137002101LF(CHIPS)':
 'J3': CDS_PINID='J3';
NET_NAME
'P5E_CPU1_PE3_TX_C_DP<6>'
 '@S9S_MB_2U_LIB.S9S_MB_2U(SCH_1):P5E_CPU1_PE3_TX_C_DP'<6>:
 C_SIGNAL='@s9s_mb_2u_lib.s9s_mb_2u(sch_1):p5e_cpu1_pe3_tx_c_dp(6)';
NODE_NAME     C1535 1
 '@S9S_MB_2U_LIB.S9S_MB_2U(SCH_1):PAGE168_I252@PURE_QUANTA.Q_CAP_DIFFBUS(CHIPS)':
 '1': CDS_PINID='\1\';
NODE_NAME     J109 I2
 '@S9S_MB_2U_LIB.S9S_MB_2U(SCH_1):PAGE319_I53@PURE_QUANTA.CONN112_10137002101LF(CHIPS)':
 'I2': CDS_PINID='I2';
NET_NAME
'P5E_CPU1_PE3_TX_C_DP<7>'
 '@S9S_MB_2U_LIB.S9S_MB_2U(SCH_1):P5E_CPU1_PE3_TX_C_DP'<7>:
 C_SIGNAL='@s9s_mb_2u_lib.s9s_mb_2u(sch_1):p5e_cpu1_pe3_tx_c_dp(7)';
NODE_NAME     C1533 1
 '@S9S_MB_2U_LIB.S9S_MB_2U(SCH_1):PAGE168_I253@PURE_QUANTA.Q_CAP_DIFFBUS(CHIPS)':
 '1': CDS_PINID='\1\';
NODE_NAME     J109 J1
 '@S9S_MB_2U_LIB.S9S_MB_2U(SCH_1):PAGE319_I53@PURE_QUANTA.CONN112_10137002101LF(CHIPS)':
 'J1': CDS_PINID='J1';
NET_NAME
'P5E_CPU1_PE3_TX_C_DP<8>'
 '@S9S_MB_2U_LIB.S9S_MB_2U(SCH_1):P5E_CPU1_PE3_TX_C_DP'<8>:
 C_SIGNAL='@s9s_mb_2u_lib.s9s_mb_2u(sch_1):p5e_cpu1_pe3_tx_c_dp(8)';
NODE_NAME     C1531 1
 '@S9S_MB_2U_LIB.S9S_MB_2U(SCH_1):PAGE168_I278@PURE_QUANTA.Q_CAP_DIFFBUS(CHIPS)':
 '1': CDS_PINID='\1\';
NODE_NAME     J110 I8
 '@S9S_MB_2U_LIB.S9S_MB_2U(SCH_1):PAGE318_I16@PURE_QUANTA.CONN112_10137002101LF(CHIPS)':
 'I8': CDS_PINID='I8';
NET_NAME
'P5E_CPU1_PE3_TX_C_DP<9>'
 '@S9S_MB_2U_LIB.S9S_MB_2U(SCH_1):P5E_CPU1_PE3_TX_C_DP'<9>:
 C_SIGNAL='@s9s_mb_2u_lib.s9s_mb_2u(sch_1):p5e_cpu1_pe3_tx_c_dp(9)';
NODE_NAME     C1529 1
 '@S9S_MB_2U_LIB.S9S_MB_2U(SCH_1):PAGE168_I279@PURE_QUANTA.Q_CAP_DIFFBUS(CHIPS)':
 '1': CDS_PINID='\1\';
NODE_NAME     J110 J7
 '@S9S_MB_2U_LIB.S9S_MB_2U(SCH_1):PAGE318_I16@PURE_QUANTA.CONN112_10137002101LF(CHIPS)':
 'J7': CDS_PINID='J7';
NET_NAME
'P5E_CPU1_PE3_TX_DN<0>'
 '@S9S_MB_2U_LIB.S9S_MB_2U(SCH_1):P5E_CPU1_PE3_TX_DN'<0>:
 C_SIGNAL='@s9s_mb_2u_lib.s9s_mb_2u(sch_1):p5e_cpu1_pe3_tx_dn(0)';
NODE_NAME     U1 EE86
 '@S9S_MB_2U_LIB.S9S_MB_2U(SCH_1):PAGE61_I12@PURE_QUANTA.SOCKET4677_AZIF0045P001C01CS(CHIPS)':
 'PE3_TX_DN0': CDS_PINID='PE3_TX_DN0';
NODE_NAME     C1546 2
 '@S9S_MB_2U_LIB.S9S_MB_2U(SCH_1):PAGE168_I230@PURE_QUANTA.Q_CAP_DIFFBUS(CHIPS)':
 '2': CDS_PINID='\2\';
NET_NAME
'P5E_CPU1_PE3_TX_DN<10>'
 '@S9S_MB_2U_LIB.S9S_MB_2U(SCH_1):P5E_CPU1_PE3_TX_DN'<10>:
 C_SIGNAL='@s9s_mb_2u_lib.s9s_mb_2u(sch_1):p5e_cpu1_pe3_tx_dn(10)';
NODE_NAME     U1 DD87
 '@S9S_MB_2U_LIB.S9S_MB_2U(SCH_1):PAGE61_I12@PURE_QUANTA.SOCKET4677_AZIF0045P001C01CS(CHIPS)':
 'PE3_TX_DN10': CDS_PINID='PE3_TX_DN10';
NODE_NAME     C1526 2
 '@S9S_MB_2U_LIB.S9S_MB_2U(SCH_1):PAGE168_I282@PURE_QUANTA.Q_CAP_DIFFBUS(CHIPS)':
 '2': CDS_PINID='\2\';
NET_NAME
'P5E_CPU1_PE3_TX_DN<11>'
 '@S9S_MB_2U_LIB.S9S_MB_2U(SCH_1):P5E_CPU1_PE3_TX_DN'<11>:
 C_SIGNAL='@s9s_mb_2u_lib.s9s_mb_2u(sch_1):p5e_cpu1_pe3_tx_dn(11)';
NODE_NAME     U1 DB85
 '@S9S_MB_2U_LIB.S9S_MB_2U(SCH_1):PAGE61_I12@PURE_QUANTA.SOCKET4677_AZIF0045P001C01CS(CHIPS)':
 'PE3_TX_DN11': CDS_PINID='PE3_TX_DN11';
NODE_NAME     C1524 2
 '@S9S_MB_2U_LIB.S9S_MB_2U(SCH_1):PAGE168_I284@PURE_QUANTA.Q_CAP_DIFFBUS(CHIPS)':
 '2': CDS_PINID='\2\';
NET_NAME
'P5E_CPU1_PE3_TX_DN<12>'
 '@S9S_MB_2U_LIB.S9S_MB_2U(SCH_1):P5E_CPU1_PE3_TX_DN'<12>:
 C_SIGNAL='@s9s_mb_2u_lib.s9s_mb_2u(sch_1):p5e_cpu1_pe3_tx_dn(12)';
NODE_NAME     U1 CY87
 '@S9S_MB_2U_LIB.S9S_MB_2U(SCH_1):PAGE61_I12@PURE_QUANTA.SOCKET4677_AZIF0045P001C01CS(CHIPS)':
 'PE3_TX_DN12': CDS_PINID='PE3_TX_DN12';
NODE_NAME     C1522 2
 '@S9S_MB_2U_LIB.S9S_MB_2U(SCH_1):PAGE168_I286@PURE_QUANTA.Q_CAP_DIFFBUS(CHIPS)':
 '2': CDS_PINID='\2\';
NET_NAME
'P5E_CPU1_PE3_TX_DN<13>'
 '@S9S_MB_2U_LIB.S9S_MB_2U(SCH_1):P5E_CPU1_PE3_TX_DN'<13>:
 C_SIGNAL='@s9s_mb_2u_lib.s9s_mb_2u(sch_1):p5e_cpu1_pe3_tx_dn(13)';
NODE_NAME     U1 CV85
 '@S9S_MB_2U_LIB.S9S_MB_2U(SCH_1):PAGE61_I12@PURE_QUANTA.SOCKET4677_AZIF0045P001C01CS(CHIPS)':
 'PE3_TX_DN13': CDS_PINID='PE3_TX_DN13';
NODE_NAME     C1520 2
 '@S9S_MB_2U_LIB.S9S_MB_2U(SCH_1):PAGE168_I297@PURE_QUANTA.Q_CAP_DIFFBUS(CHIPS)':
 '2': CDS_PINID='\2\';
NET_NAME
'P5E_CPU1_PE3_TX_DN<14>'
 '@S9S_MB_2U_LIB.S9S_MB_2U(SCH_1):P5E_CPU1_PE3_TX_DN'<14>:
 C_SIGNAL='@s9s_mb_2u_lib.s9s_mb_2u(sch_1):p5e_cpu1_pe3_tx_dn(14)';
NODE_NAME     U1 CT87
 '@S9S_MB_2U_LIB.S9S_MB_2U(SCH_1):PAGE61_I12@PURE_QUANTA.SOCKET4677_AZIF0045P001C01CS(CHIPS)':
 'PE3_TX_DN14': CDS_PINID='PE3_TX_DN14';
NODE_NAME     C1518 2
 '@S9S_MB_2U_LIB.S9S_MB_2U(SCH_1):PAGE168_I300@PURE_QUANTA.Q_CAP_DIFFBUS(CHIPS)':
 '2': CDS_PINID='\2\';
NET_NAME
'P5E_CPU1_PE3_TX_DN<15>'
 '@S9S_MB_2U_LIB.S9S_MB_2U(SCH_1):P5E_CPU1_PE3_TX_DN'<15>:
 C_SIGNAL='@s9s_mb_2u_lib.s9s_mb_2u(sch_1):p5e_cpu1_pe3_tx_dn(15)';
NODE_NAME     U1 CP85
 '@S9S_MB_2U_LIB.S9S_MB_2U(SCH_1):PAGE61_I12@PURE_QUANTA.SOCKET4677_AZIF0045P001C01CS(CHIPS)':
 'PE3_TX_DN15': CDS_PINID='PE3_TX_DN15';
NODE_NAME     C1516 2
 '@S9S_MB_2U_LIB.S9S_MB_2U(SCH_1):PAGE168_I302@PURE_QUANTA.Q_CAP_DIFFBUS(CHIPS)':
 '2': CDS_PINID='\2\';
NET_NAME
'P5E_CPU1_PE3_TX_DN<1>'
 '@S9S_MB_2U_LIB.S9S_MB_2U(SCH_1):P5E_CPU1_PE3_TX_DN'<1>:
 C_SIGNAL='@s9s_mb_2u_lib.s9s_mb_2u(sch_1):p5e_cpu1_pe3_tx_dn(1)';
NODE_NAME     U1 EB85
 '@S9S_MB_2U_LIB.S9S_MB_2U(SCH_1):PAGE61_I12@PURE_QUANTA.SOCKET4677_AZIF0045P001C01CS(CHIPS)':
 'PE3_TX_DN1': CDS_PINID='PE3_TX_DN1';
NODE_NAME     C1544 2
 '@S9S_MB_2U_LIB.S9S_MB_2U(SCH_1):PAGE168_I232@PURE_QUANTA.Q_CAP_DIFFBUS(CHIPS)':
 '2': CDS_PINID='\2\';
NET_NAME
'P5E_CPU1_PE3_TX_DN<2>'
 '@S9S_MB_2U_LIB.S9S_MB_2U(SCH_1):P5E_CPU1_PE3_TX_DN'<2>:
 C_SIGNAL='@s9s_mb_2u_lib.s9s_mb_2u(sch_1):p5e_cpu1_pe3_tx_dn(2)';
NODE_NAME     U1 DY87
 '@S9S_MB_2U_LIB.S9S_MB_2U(SCH_1):PAGE61_I12@PURE_QUANTA.SOCKET4677_AZIF0045P001C01CS(CHIPS)':
 'PE3_TX_DN2': CDS_PINID='PE3_TX_DN2';
NODE_NAME     C1542 2
 '@S9S_MB_2U_LIB.S9S_MB_2U(SCH_1):PAGE168_I233@PURE_QUANTA.Q_CAP_DIFFBUS(CHIPS)':
 '2': CDS_PINID='\2\';
NET_NAME
'P5E_CPU1_PE3_TX_DN<3>'
 '@S9S_MB_2U_LIB.S9S_MB_2U(SCH_1):P5E_CPU1_PE3_TX_DN'<3>:
 C_SIGNAL='@s9s_mb_2u_lib.s9s_mb_2u(sch_1):p5e_cpu1_pe3_tx_dn(3)';
NODE_NAME     U1 DV85
 '@S9S_MB_2U_LIB.S9S_MB_2U(SCH_1):PAGE61_I12@PURE_QUANTA.SOCKET4677_AZIF0045P001C01CS(CHIPS)':
 'PE3_TX_DN3': CDS_PINID='PE3_TX_DN3';
NODE_NAME     C1540 2
 '@S9S_MB_2U_LIB.S9S_MB_2U(SCH_1):PAGE168_I236@PURE_QUANTA.Q_CAP_DIFFBUS(CHIPS)':
 '2': CDS_PINID='\2\';
NET_NAME
'P5E_CPU1_PE3_TX_DN<4>'
 '@S9S_MB_2U_LIB.S9S_MB_2U(SCH_1):P5E_CPU1_PE3_TX_DN'<4>:
 C_SIGNAL='@s9s_mb_2u_lib.s9s_mb_2u(sch_1):p5e_cpu1_pe3_tx_dn(4)';
NODE_NAME     U1 DT87
 '@S9S_MB_2U_LIB.S9S_MB_2U(SCH_1):PAGE61_I12@PURE_QUANTA.SOCKET4677_AZIF0045P001C01CS(CHIPS)':
 'PE3_TX_DN4': CDS_PINID='PE3_TX_DN4';
NODE_NAME     C1538 2
 '@S9S_MB_2U_LIB.S9S_MB_2U(SCH_1):PAGE168_I238@PURE_QUANTA.Q_CAP_DIFFBUS(CHIPS)':
 '2': CDS_PINID='\2\';
NET_NAME
'P5E_CPU1_PE3_TX_DN<5>'
 '@S9S_MB_2U_LIB.S9S_MB_2U(SCH_1):P5E_CPU1_PE3_TX_DN'<5>:
 C_SIGNAL='@s9s_mb_2u_lib.s9s_mb_2u(sch_1):p5e_cpu1_pe3_tx_dn(5)';
NODE_NAME     U1 DP85
 '@S9S_MB_2U_LIB.S9S_MB_2U(SCH_1):PAGE61_I12@PURE_QUANTA.SOCKET4677_AZIF0045P001C01CS(CHIPS)':
 'PE3_TX_DN5': CDS_PINID='PE3_TX_DN5';
NODE_NAME     C1536 2
 '@S9S_MB_2U_LIB.S9S_MB_2U(SCH_1):PAGE168_I250@PURE_QUANTA.Q_CAP_DIFFBUS(CHIPS)':
 '2': CDS_PINID='\2\';
NET_NAME
'P5E_CPU1_PE3_TX_DN<6>'
 '@S9S_MB_2U_LIB.S9S_MB_2U(SCH_1):P5E_CPU1_PE3_TX_DN'<6>:
 C_SIGNAL='@s9s_mb_2u_lib.s9s_mb_2u(sch_1):p5e_cpu1_pe3_tx_dn(6)';
NODE_NAME     U1 DM87
 '@S9S_MB_2U_LIB.S9S_MB_2U(SCH_1):PAGE61_I12@PURE_QUANTA.SOCKET4677_AZIF0045P001C01CS(CHIPS)':
 'PE3_TX_DN6': CDS_PINID='PE3_TX_DN6';
NODE_NAME     C1534 2
 '@S9S_MB_2U_LIB.S9S_MB_2U(SCH_1):PAGE168_I251@PURE_QUANTA.Q_CAP_DIFFBUS(CHIPS)':
 '2': CDS_PINID='\2\';
NET_NAME
'P5E_CPU1_PE3_TX_DN<7>'
 '@S9S_MB_2U_LIB.S9S_MB_2U(SCH_1):P5E_CPU1_PE3_TX_DN'<7>:
 C_SIGNAL='@s9s_mb_2u_lib.s9s_mb_2u(sch_1):p5e_cpu1_pe3_tx_dn(7)';
NODE_NAME     U1 DK85
 '@S9S_MB_2U_LIB.S9S_MB_2U(SCH_1):PAGE61_I12@PURE_QUANTA.SOCKET4677_AZIF0045P001C01CS(CHIPS)':
 'PE3_TX_DN7': CDS_PINID='PE3_TX_DN7';
NODE_NAME     C1532 2
 '@S9S_MB_2U_LIB.S9S_MB_2U(SCH_1):PAGE168_I254@PURE_QUANTA.Q_CAP_DIFFBUS(CHIPS)':
 '2': CDS_PINID='\2\';
NET_NAME
'P5E_CPU1_PE3_TX_DN<8>'
 '@S9S_MB_2U_LIB.S9S_MB_2U(SCH_1):P5E_CPU1_PE3_TX_DN'<8>:
 C_SIGNAL='@s9s_mb_2u_lib.s9s_mb_2u(sch_1):p5e_cpu1_pe3_tx_dn(8)';
NODE_NAME     U1 DH87
 '@S9S_MB_2U_LIB.S9S_MB_2U(SCH_1):PAGE61_I12@PURE_QUANTA.SOCKET4677_AZIF0045P001C01CS(CHIPS)':
 'PE3_TX_DN8': CDS_PINID='PE3_TX_DN8';
NODE_NAME     C1530 2
 '@S9S_MB_2U_LIB.S9S_MB_2U(SCH_1):PAGE168_I277@PURE_QUANTA.Q_CAP_DIFFBUS(CHIPS)':
 '2': CDS_PINID='\2\';
NET_NAME
'P5E_CPU1_PE3_TX_DN<9>'
 '@S9S_MB_2U_LIB.S9S_MB_2U(SCH_1):P5E_CPU1_PE3_TX_DN'<9>:
 C_SIGNAL='@s9s_mb_2u_lib.s9s_mb_2u(sch_1):p5e_cpu1_pe3_tx_dn(9)';
NODE_NAME     U1 DF85
 '@S9S_MB_2U_LIB.S9S_MB_2U(SCH_1):PAGE61_I12@PURE_QUANTA.SOCKET4677_AZIF0045P001C01CS(CHIPS)':
 'PE3_TX_DN9': CDS_PINID='PE3_TX_DN9';
NODE_NAME     C1528 2
 '@S9S_MB_2U_LIB.S9S_MB_2U(SCH_1):PAGE168_I280@PURE_QUANTA.Q_CAP_DIFFBUS(CHIPS)':
 '2': CDS_PINID='\2\';
NET_NAME
'P5E_CPU1_PE3_TX_DP<0>'
 '@S9S_MB_2U_LIB.S9S_MB_2U(SCH_1):P5E_CPU1_PE3_TX_DP'<0>:
 C_SIGNAL='@s9s_mb_2u_lib.s9s_mb_2u(sch_1):p5e_cpu1_pe3_tx_dp(0)';
NODE_NAME     U1 ED87
 '@S9S_MB_2U_LIB.S9S_MB_2U(SCH_1):PAGE61_I12@PURE_QUANTA.SOCKET4677_AZIF0045P001C01CS(CHIPS)':
 'PE3_TX_DP0': CDS_PINID='PE3_TX_DP0';
NODE_NAME     C1547 2
 '@S9S_MB_2U_LIB.S9S_MB_2U(SCH_1):PAGE168_I229@PURE_QUANTA.Q_CAP_DIFFBUS(CHIPS)':
 '2': CDS_PINID='\2\';
NET_NAME
'P5E_CPU1_PE3_TX_DP<10>'
 '@S9S_MB_2U_LIB.S9S_MB_2U(SCH_1):P5E_CPU1_PE3_TX_DP'<10>:
 C_SIGNAL='@s9s_mb_2u_lib.s9s_mb_2u(sch_1):p5e_cpu1_pe3_tx_dp(10)';
NODE_NAME     U1 DE86
 '@S9S_MB_2U_LIB.S9S_MB_2U(SCH_1):PAGE61_I12@PURE_QUANTA.SOCKET4677_AZIF0045P001C01CS(CHIPS)':
 'PE3_TX_DP10': CDS_PINID='PE3_TX_DP10';
NODE_NAME     C1527 2
 '@S9S_MB_2U_LIB.S9S_MB_2U(SCH_1):PAGE168_I281@PURE_QUANTA.Q_CAP_DIFFBUS(CHIPS)':
 '2': CDS_PINID='\2\';
NET_NAME
'P5E_CPU1_PE3_TX_DP<11>'
 '@S9S_MB_2U_LIB.S9S_MB_2U(SCH_1):P5E_CPU1_PE3_TX_DP'<11>:
 C_SIGNAL='@s9s_mb_2u_lib.s9s_mb_2u(sch_1):p5e_cpu1_pe3_tx_dp(11)';
NODE_NAME     U1 DC86
 '@S9S_MB_2U_LIB.S9S_MB_2U(SCH_1):PAGE61_I12@PURE_QUANTA.SOCKET4677_AZIF0045P001C01CS(CHIPS)':
 'PE3_TX_DP11': CDS_PINID='PE3_TX_DP11';
NODE_NAME     C1525 2
 '@S9S_MB_2U_LIB.S9S_MB_2U(SCH_1):PAGE168_I283@PURE_QUANTA.Q_CAP_DIFFBUS(CHIPS)':
 '2': CDS_PINID='\2\';
NET_NAME
'P5E_CPU1_PE3_TX_DP<12>'
 '@S9S_MB_2U_LIB.S9S_MB_2U(SCH_1):P5E_CPU1_PE3_TX_DP'<12>:
 C_SIGNAL='@s9s_mb_2u_lib.s9s_mb_2u(sch_1):p5e_cpu1_pe3_tx_dp(12)';
NODE_NAME     U1 DA86
 '@S9S_MB_2U_LIB.S9S_MB_2U(SCH_1):PAGE61_I12@PURE_QUANTA.SOCKET4677_AZIF0045P001C01CS(CHIPS)':
 'PE3_TX_DP12': CDS_PINID='PE3_TX_DP12';
NODE_NAME     C1523 2
 '@S9S_MB_2U_LIB.S9S_MB_2U(SCH_1):PAGE168_I285@PURE_QUANTA.Q_CAP_DIFFBUS(CHIPS)':
 '2': CDS_PINID='\2\';
NET_NAME
'P5E_CPU1_PE3_TX_DP<13>'
 '@S9S_MB_2U_LIB.S9S_MB_2U(SCH_1):P5E_CPU1_PE3_TX_DP'<13>:
 C_SIGNAL='@s9s_mb_2u_lib.s9s_mb_2u(sch_1):p5e_cpu1_pe3_tx_dp(13)';
NODE_NAME     U1 CW86
 '@S9S_MB_2U_LIB.S9S_MB_2U(SCH_1):PAGE61_I12@PURE_QUANTA.SOCKET4677_AZIF0045P001C01CS(CHIPS)':
 'PE3_TX_DP13': CDS_PINID='PE3_TX_DP13';
NODE_NAME     C1521 2
 '@S9S_MB_2U_LIB.S9S_MB_2U(SCH_1):PAGE168_I298@PURE_QUANTA.Q_CAP_DIFFBUS(CHIPS)':
 '2': CDS_PINID='\2\';
NET_NAME
'P5E_CPU1_PE3_TX_DP<14>'
 '@S9S_MB_2U_LIB.S9S_MB_2U(SCH_1):P5E_CPU1_PE3_TX_DP'<14>:
 C_SIGNAL='@s9s_mb_2u_lib.s9s_mb_2u(sch_1):p5e_cpu1_pe3_tx_dp(14)';
NODE_NAME     U1 CU86
 '@S9S_MB_2U_LIB.S9S_MB_2U(SCH_1):PAGE61_I12@PURE_QUANTA.SOCKET4677_AZIF0045P001C01CS(CHIPS)':
 'PE3_TX_DP14': CDS_PINID='PE3_TX_DP14';
NODE_NAME     C1519 2
 '@S9S_MB_2U_LIB.S9S_MB_2U(SCH_1):PAGE168_I299@PURE_QUANTA.Q_CAP_DIFFBUS(CHIPS)':
 '2': CDS_PINID='\2\';
NET_NAME
'P5E_CPU1_PE3_TX_DP<15>'
 '@S9S_MB_2U_LIB.S9S_MB_2U(SCH_1):P5E_CPU1_PE3_TX_DP'<15>:
 C_SIGNAL='@s9s_mb_2u_lib.s9s_mb_2u(sch_1):p5e_cpu1_pe3_tx_dp(15)';
NODE_NAME     U1 CR86
 '@S9S_MB_2U_LIB.S9S_MB_2U(SCH_1):PAGE61_I12@PURE_QUANTA.SOCKET4677_AZIF0045P001C01CS(CHIPS)':
 'PE3_TX_DP15': CDS_PINID='PE3_TX_DP15';
NODE_NAME     C1517 2
 '@S9S_MB_2U_LIB.S9S_MB_2U(SCH_1):PAGE168_I301@PURE_QUANTA.Q_CAP_DIFFBUS(CHIPS)':
 '2': CDS_PINID='\2\';
NET_NAME
'P5E_CPU1_PE3_TX_DP<1>'
 '@S9S_MB_2U_LIB.S9S_MB_2U(SCH_1):P5E_CPU1_PE3_TX_DP'<1>:
 C_SIGNAL='@s9s_mb_2u_lib.s9s_mb_2u(sch_1):p5e_cpu1_pe3_tx_dp(1)';
NODE_NAME     U1 EC86
 '@S9S_MB_2U_LIB.S9S_MB_2U(SCH_1):PAGE61_I12@PURE_QUANTA.SOCKET4677_AZIF0045P001C01CS(CHIPS)':
 'PE3_TX_DP1': CDS_PINID='PE3_TX_DP1';
NODE_NAME     C1545 2
 '@S9S_MB_2U_LIB.S9S_MB_2U(SCH_1):PAGE168_I231@PURE_QUANTA.Q_CAP_DIFFBUS(CHIPS)':
 '2': CDS_PINID='\2\';
NET_NAME
'P5E_CPU1_PE3_TX_DP<2>'
 '@S9S_MB_2U_LIB.S9S_MB_2U(SCH_1):P5E_CPU1_PE3_TX_DP'<2>:
 C_SIGNAL='@s9s_mb_2u_lib.s9s_mb_2u(sch_1):p5e_cpu1_pe3_tx_dp(2)';
NODE_NAME     U1 EA86
 '@S9S_MB_2U_LIB.S9S_MB_2U(SCH_1):PAGE61_I12@PURE_QUANTA.SOCKET4677_AZIF0045P001C01CS(CHIPS)':
 'PE3_TX_DP2': CDS_PINID='PE3_TX_DP2';
NODE_NAME     C1543 2
 '@S9S_MB_2U_LIB.S9S_MB_2U(SCH_1):PAGE168_I234@PURE_QUANTA.Q_CAP_DIFFBUS(CHIPS)':
 '2': CDS_PINID='\2\';
NET_NAME
'P5E_CPU1_PE3_TX_DP<3>'
 '@S9S_MB_2U_LIB.S9S_MB_2U(SCH_1):P5E_CPU1_PE3_TX_DP'<3>:
 C_SIGNAL='@s9s_mb_2u_lib.s9s_mb_2u(sch_1):p5e_cpu1_pe3_tx_dp(3)';
NODE_NAME     U1 DW86
 '@S9S_MB_2U_LIB.S9S_MB_2U(SCH_1):PAGE61_I12@PURE_QUANTA.SOCKET4677_AZIF0045P001C01CS(CHIPS)':
 'PE3_TX_DP3': CDS_PINID='PE3_TX_DP3';
NODE_NAME     C1541 2
 '@S9S_MB_2U_LIB.S9S_MB_2U(SCH_1):PAGE168_I235@PURE_QUANTA.Q_CAP_DIFFBUS(CHIPS)':
 '2': CDS_PINID='\2\';
NET_NAME
'P5E_CPU1_PE3_TX_DP<4>'
 '@S9S_MB_2U_LIB.S9S_MB_2U(SCH_1):P5E_CPU1_PE3_TX_DP'<4>:
 C_SIGNAL='@s9s_mb_2u_lib.s9s_mb_2u(sch_1):p5e_cpu1_pe3_tx_dp(4)';
NODE_NAME     U1 DU86
 '@S9S_MB_2U_LIB.S9S_MB_2U(SCH_1):PAGE61_I12@PURE_QUANTA.SOCKET4677_AZIF0045P001C01CS(CHIPS)':
 'PE3_TX_DP4': CDS_PINID='PE3_TX_DP4';
NODE_NAME     C1539 2
 '@S9S_MB_2U_LIB.S9S_MB_2U(SCH_1):PAGE168_I237@PURE_QUANTA.Q_CAP_DIFFBUS(CHIPS)':
 '2': CDS_PINID='\2\';
NET_NAME
'P5E_CPU1_PE3_TX_DP<5>'
 '@S9S_MB_2U_LIB.S9S_MB_2U(SCH_1):P5E_CPU1_PE3_TX_DP'<5>:
 C_SIGNAL='@s9s_mb_2u_lib.s9s_mb_2u(sch_1):p5e_cpu1_pe3_tx_dp(5)';
NODE_NAME     U1 DR86
 '@S9S_MB_2U_LIB.S9S_MB_2U(SCH_1):PAGE61_I12@PURE_QUANTA.SOCKET4677_AZIF0045P001C01CS(CHIPS)':
 'PE3_TX_DP5': CDS_PINID='PE3_TX_DP5';
NODE_NAME     C1537 2
 '@S9S_MB_2U_LIB.S9S_MB_2U(SCH_1):PAGE168_I249@PURE_QUANTA.Q_CAP_DIFFBUS(CHIPS)':
 '2': CDS_PINID='\2\';
NET_NAME
'P5E_CPU1_PE3_TX_DP<6>'
 '@S9S_MB_2U_LIB.S9S_MB_2U(SCH_1):P5E_CPU1_PE3_TX_DP'<6>:
 C_SIGNAL='@s9s_mb_2u_lib.s9s_mb_2u(sch_1):p5e_cpu1_pe3_tx_dp(6)';
NODE_NAME     U1 DN86
 '@S9S_MB_2U_LIB.S9S_MB_2U(SCH_1):PAGE61_I12@PURE_QUANTA.SOCKET4677_AZIF0045P001C01CS(CHIPS)':
 'PE3_TX_DP6': CDS_PINID='PE3_TX_DP6';
NODE_NAME     C1535 2
 '@S9S_MB_2U_LIB.S9S_MB_2U(SCH_1):PAGE168_I252@PURE_QUANTA.Q_CAP_DIFFBUS(CHIPS)':
 '2': CDS_PINID='\2\';
NET_NAME
'P5E_CPU1_PE3_TX_DP<7>'
 '@S9S_MB_2U_LIB.S9S_MB_2U(SCH_1):P5E_CPU1_PE3_TX_DP'<7>:
 C_SIGNAL='@s9s_mb_2u_lib.s9s_mb_2u(sch_1):p5e_cpu1_pe3_tx_dp(7)';
NODE_NAME     U1 DL86
 '@S9S_MB_2U_LIB.S9S_MB_2U(SCH_1):PAGE61_I12@PURE_QUANTA.SOCKET4677_AZIF0045P001C01CS(CHIPS)':
 'PE3_TX_DP7': CDS_PINID='PE3_TX_DP7';
NODE_NAME     C1533 2
 '@S9S_MB_2U_LIB.S9S_MB_2U(SCH_1):PAGE168_I253@PURE_QUANTA.Q_CAP_DIFFBUS(CHIPS)':
 '2': CDS_PINID='\2\';
NET_NAME
'P5E_CPU1_PE3_TX_DP<8>'
 '@S9S_MB_2U_LIB.S9S_MB_2U(SCH_1):P5E_CPU1_PE3_TX_DP'<8>:
 C_SIGNAL='@s9s_mb_2u_lib.s9s_mb_2u(sch_1):p5e_cpu1_pe3_tx_dp(8)';
NODE_NAME     U1 DJ86
 '@S9S_MB_2U_LIB.S9S_MB_2U(SCH_1):PAGE61_I12@PURE_QUANTA.SOCKET4677_AZIF0045P001C01CS(CHIPS)':
 'PE3_TX_DP8': CDS_PINID='PE3_TX_DP8';
NODE_NAME     C1531 2
 '@S9S_MB_2U_LIB.S9S_MB_2U(SCH_1):PAGE168_I278@PURE_QUANTA.Q_CAP_DIFFBUS(CHIPS)':
 '2': CDS_PINID='\2\';
NET_NAME
'P5E_CPU1_PE3_TX_DP<9>'
 '@S9S_MB_2U_LIB.S9S_MB_2U(SCH_1):P5E_CPU1_PE3_TX_DP'<9>:
 C_SIGNAL='@s9s_mb_2u_lib.s9s_mb_2u(sch_1):p5e_cpu1_pe3_tx_dp(9)';
NODE_NAME     U1 DG86
 '@S9S_MB_2U_LIB.S9S_MB_2U(SCH_1):PAGE61_I12@PURE_QUANTA.SOCKET4677_AZIF0045P001C01CS(CHIPS)':
 'PE3_TX_DP9': CDS_PINID='PE3_TX_DP9';
NODE_NAME     C1529 2
 '@S9S_MB_2U_LIB.S9S_MB_2U(SCH_1):PAGE168_I279@PURE_QUANTA.Q_CAP_DIFFBUS(CHIPS)':
 '2': CDS_PINID='\2\';
NET_NAME
'P5E_CPU1_PE4_RX_DN<0>'
 '@S9S_MB_2U_LIB.S9S_MB_2U(SCH_1):P5E_CPU1_PE4_RX_DN'<0>:
 C_SIGNAL='@s9s_mb_2u_lib.s9s_mb_2u(sch_1):p5e_cpu1_pe4_rx_dn(0)';
NODE_NAME     U1 J90
 '@S9S_MB_2U_LIB.S9S_MB_2U(SCH_1):PAGE62_I18@PURE_QUANTA.SOCKET4677_AZIF0045P001C01CS(CHIPS)':
 'PE4_RX_DN0': CDS_PINID='PE4_RX_DN0';
NODE_NAME     J112 F1
 '@S9S_MB_2U_LIB.S9S_MB_2U(SCH_1):PAGE149_I76@PURE_QUANTA.CONN160_10131762101LF(CHIPS)':
 'F1': CDS_PINID='F1';
NET_NAME
'P5E_CPU1_PE4_RX_DN<10>'
 '@S9S_MB_2U_LIB.S9S_MB_2U(SCH_1):P5E_CPU1_PE4_RX_DN'<10>:
 C_SIGNAL='@s9s_mb_2u_lib.s9s_mb_2u(sch_1):p5e_cpu1_pe4_rx_dn(10)';
NODE_NAME     U1 AM91
 '@S9S_MB_2U_LIB.S9S_MB_2U(SCH_1):PAGE62_I18@PURE_QUANTA.SOCKET4677_AZIF0045P001C01CS(CHIPS)':
 'PE4_RX_DN10': CDS_PINID='PE4_RX_DN10';
NODE_NAME     J111 F3
 '@S9S_MB_2U_LIB.S9S_MB_2U(SCH_1):PAGE148_I75@PURE_QUANTA.CONN112_10137002101LF(CHIPS)':
 'F3': CDS_PINID='F3';
NET_NAME
'P5E_CPU1_PE4_RX_DN<11>'
 '@S9S_MB_2U_LIB.S9S_MB_2U(SCH_1):P5E_CPU1_PE4_RX_DN'<11>:
 C_SIGNAL='@s9s_mb_2u_lib.s9s_mb_2u(sch_1):p5e_cpu1_pe4_rx_dn(11)';
NODE_NAME     U1 AP89
 '@S9S_MB_2U_LIB.S9S_MB_2U(SCH_1):PAGE62_I18@PURE_QUANTA.SOCKET4677_AZIF0045P001C01CS(CHIPS)':
 'PE4_RX_DN11': CDS_PINID='PE4_RX_DN11';
NODE_NAME     J111 F4
 '@S9S_MB_2U_LIB.S9S_MB_2U(SCH_1):PAGE148_I75@PURE_QUANTA.CONN112_10137002101LF(CHIPS)':
 'F4': CDS_PINID='F4';
NET_NAME
'P5E_CPU1_PE4_RX_DN<12>'
 '@S9S_MB_2U_LIB.S9S_MB_2U(SCH_1):P5E_CPU1_PE4_RX_DN'<12>:
 C_SIGNAL='@s9s_mb_2u_lib.s9s_mb_2u(sch_1):p5e_cpu1_pe4_rx_dn(12)';
NODE_NAME     U1 AT91
 '@S9S_MB_2U_LIB.S9S_MB_2U(SCH_1):PAGE62_I18@PURE_QUANTA.SOCKET4677_AZIF0045P001C01CS(CHIPS)':
 'PE4_RX_DN12': CDS_PINID='PE4_RX_DN12';
NODE_NAME     J111 F5
 '@S9S_MB_2U_LIB.S9S_MB_2U(SCH_1):PAGE148_I74@PURE_QUANTA.CONN112_10137002101LF(CHIPS)':
 'F5': CDS_PINID='F5';
NET_NAME
'P5E_CPU1_PE4_RX_DN<13>'
 '@S9S_MB_2U_LIB.S9S_MB_2U(SCH_1):P5E_CPU1_PE4_RX_DN'<13>:
 C_SIGNAL='@s9s_mb_2u_lib.s9s_mb_2u(sch_1):p5e_cpu1_pe4_rx_dn(13)';
NODE_NAME     U1 AV89
 '@S9S_MB_2U_LIB.S9S_MB_2U(SCH_1):PAGE62_I18@PURE_QUANTA.SOCKET4677_AZIF0045P001C01CS(CHIPS)':
 'PE4_RX_DN13': CDS_PINID='PE4_RX_DN13';
NODE_NAME     J111 F6
 '@S9S_MB_2U_LIB.S9S_MB_2U(SCH_1):PAGE148_I74@PURE_QUANTA.CONN112_10137002101LF(CHIPS)':
 'F6': CDS_PINID='F6';
NET_NAME
'P5E_CPU1_PE4_RX_DN<14>'
 '@S9S_MB_2U_LIB.S9S_MB_2U(SCH_1):P5E_CPU1_PE4_RX_DN'<14>:
 C_SIGNAL='@s9s_mb_2u_lib.s9s_mb_2u(sch_1):p5e_cpu1_pe4_rx_dn(14)';
NODE_NAME     U1 AY91
 '@S9S_MB_2U_LIB.S9S_MB_2U(SCH_1):PAGE62_I18@PURE_QUANTA.SOCKET4677_AZIF0045P001C01CS(CHIPS)':
 'PE4_RX_DN14': CDS_PINID='PE4_RX_DN14';
NODE_NAME     J111 F7
 '@S9S_MB_2U_LIB.S9S_MB_2U(SCH_1):PAGE148_I74@PURE_QUANTA.CONN112_10137002101LF(CHIPS)':
 'F7': CDS_PINID='F7';
NET_NAME
'P5E_CPU1_PE4_RX_DN<15>'
 '@S9S_MB_2U_LIB.S9S_MB_2U(SCH_1):P5E_CPU1_PE4_RX_DN'<15>:
 C_SIGNAL='@s9s_mb_2u_lib.s9s_mb_2u(sch_1):p5e_cpu1_pe4_rx_dn(15)';
NODE_NAME     U1 BB89
 '@S9S_MB_2U_LIB.S9S_MB_2U(SCH_1):PAGE62_I18@PURE_QUANTA.SOCKET4677_AZIF0045P001C01CS(CHIPS)':
 'PE4_RX_DN15': CDS_PINID='PE4_RX_DN15';
NODE_NAME     J111 F8
 '@S9S_MB_2U_LIB.S9S_MB_2U(SCH_1):PAGE148_I74@PURE_QUANTA.CONN112_10137002101LF(CHIPS)':
 'F8': CDS_PINID='F8';
NET_NAME
'P5E_CPU1_PE4_RX_DN<1>'
 '@S9S_MB_2U_LIB.S9S_MB_2U(SCH_1):P5E_CPU1_PE4_RX_DN'<1>:
 C_SIGNAL='@s9s_mb_2u_lib.s9s_mb_2u(sch_1):p5e_cpu1_pe4_rx_dn(1)';
NODE_NAME     U1 P89
 '@S9S_MB_2U_LIB.S9S_MB_2U(SCH_1):PAGE62_I18@PURE_QUANTA.SOCKET4677_AZIF0045P001C01CS(CHIPS)':
 'PE4_RX_DN1': CDS_PINID='PE4_RX_DN1';
NODE_NAME     J112 F2
 '@S9S_MB_2U_LIB.S9S_MB_2U(SCH_1):PAGE149_I76@PURE_QUANTA.CONN160_10131762101LF(CHIPS)':
 'F2': CDS_PINID='F2';
NET_NAME
'P5E_CPU1_PE4_RX_DN<2>'
 '@S9S_MB_2U_LIB.S9S_MB_2U(SCH_1):P5E_CPU1_PE4_RX_DN'<2>:
 C_SIGNAL='@s9s_mb_2u_lib.s9s_mb_2u(sch_1):p5e_cpu1_pe4_rx_dn(2)';
NODE_NAME     U1 T91
 '@S9S_MB_2U_LIB.S9S_MB_2U(SCH_1):PAGE62_I18@PURE_QUANTA.SOCKET4677_AZIF0045P001C01CS(CHIPS)':
 'PE4_RX_DN2': CDS_PINID='PE4_RX_DN2';
NODE_NAME     J112 F3
 '@S9S_MB_2U_LIB.S9S_MB_2U(SCH_1):PAGE149_I76@PURE_QUANTA.CONN160_10131762101LF(CHIPS)':
 'F3': CDS_PINID='F3';
NET_NAME
'P5E_CPU1_PE4_RX_DN<3>'
 '@S9S_MB_2U_LIB.S9S_MB_2U(SCH_1):P5E_CPU1_PE4_RX_DN'<3>:
 C_SIGNAL='@s9s_mb_2u_lib.s9s_mb_2u(sch_1):p5e_cpu1_pe4_rx_dn(3)';
NODE_NAME     U1 V89
 '@S9S_MB_2U_LIB.S9S_MB_2U(SCH_1):PAGE62_I18@PURE_QUANTA.SOCKET4677_AZIF0045P001C01CS(CHIPS)':
 'PE4_RX_DN3': CDS_PINID='PE4_RX_DN3';
NODE_NAME     J112 F4
 '@S9S_MB_2U_LIB.S9S_MB_2U(SCH_1):PAGE149_I76@PURE_QUANTA.CONN160_10131762101LF(CHIPS)':
 'F4': CDS_PINID='F4';
NET_NAME
'P5E_CPU1_PE4_RX_DN<4>'
 '@S9S_MB_2U_LIB.S9S_MB_2U(SCH_1):P5E_CPU1_PE4_RX_DN'<4>:
 C_SIGNAL='@s9s_mb_2u_lib.s9s_mb_2u(sch_1):p5e_cpu1_pe4_rx_dn(4)';
NODE_NAME     U1 Y91
 '@S9S_MB_2U_LIB.S9S_MB_2U(SCH_1):PAGE62_I18@PURE_QUANTA.SOCKET4677_AZIF0045P001C01CS(CHIPS)':
 'PE4_RX_DN4': CDS_PINID='PE4_RX_DN4';
NODE_NAME     J112 F5
 '@S9S_MB_2U_LIB.S9S_MB_2U(SCH_1):PAGE149_I75@PURE_QUANTA.CONN160_10131762101LF(CHIPS)':
 'F5': CDS_PINID='F5';
NET_NAME
'P5E_CPU1_PE4_RX_DN<5>'
 '@S9S_MB_2U_LIB.S9S_MB_2U(SCH_1):P5E_CPU1_PE4_RX_DN'<5>:
 C_SIGNAL='@s9s_mb_2u_lib.s9s_mb_2u(sch_1):p5e_cpu1_pe4_rx_dn(5)';
NODE_NAME     U1 AB89
 '@S9S_MB_2U_LIB.S9S_MB_2U(SCH_1):PAGE62_I18@PURE_QUANTA.SOCKET4677_AZIF0045P001C01CS(CHIPS)':
 'PE4_RX_DN5': CDS_PINID='PE4_RX_DN5';
NODE_NAME     J112 F6
 '@S9S_MB_2U_LIB.S9S_MB_2U(SCH_1):PAGE149_I75@PURE_QUANTA.CONN160_10131762101LF(CHIPS)':
 'F6': CDS_PINID='F6';
NET_NAME
'P5E_CPU1_PE4_RX_DN<6>'
 '@S9S_MB_2U_LIB.S9S_MB_2U(SCH_1):P5E_CPU1_PE4_RX_DN'<6>:
 C_SIGNAL='@s9s_mb_2u_lib.s9s_mb_2u(sch_1):p5e_cpu1_pe4_rx_dn(6)';
NODE_NAME     U1 AD91
 '@S9S_MB_2U_LIB.S9S_MB_2U(SCH_1):PAGE62_I18@PURE_QUANTA.SOCKET4677_AZIF0045P001C01CS(CHIPS)':
 'PE4_RX_DN6': CDS_PINID='PE4_RX_DN6';
NODE_NAME     J112 F7
 '@S9S_MB_2U_LIB.S9S_MB_2U(SCH_1):PAGE149_I75@PURE_QUANTA.CONN160_10131762101LF(CHIPS)':
 'F7': CDS_PINID='F7';
NET_NAME
'P5E_CPU1_PE4_RX_DN<7>'
 '@S9S_MB_2U_LIB.S9S_MB_2U(SCH_1):P5E_CPU1_PE4_RX_DN'<7>:
 C_SIGNAL='@s9s_mb_2u_lib.s9s_mb_2u(sch_1):p5e_cpu1_pe4_rx_dn(7)';
NODE_NAME     U1 AF89
 '@S9S_MB_2U_LIB.S9S_MB_2U(SCH_1):PAGE62_I18@PURE_QUANTA.SOCKET4677_AZIF0045P001C01CS(CHIPS)':
 'PE4_RX_DN7': CDS_PINID='PE4_RX_DN7';
NODE_NAME     J112 F8
 '@S9S_MB_2U_LIB.S9S_MB_2U(SCH_1):PAGE149_I75@PURE_QUANTA.CONN160_10131762101LF(CHIPS)':
 'F8': CDS_PINID='F8';
NET_NAME
'P5E_CPU1_PE4_RX_DN<8>'
 '@S9S_MB_2U_LIB.S9S_MB_2U(SCH_1):P5E_CPU1_PE4_RX_DN'<8>:
 C_SIGNAL='@s9s_mb_2u_lib.s9s_mb_2u(sch_1):p5e_cpu1_pe4_rx_dn(8)';
NODE_NAME     U1 AH91
 '@S9S_MB_2U_LIB.S9S_MB_2U(SCH_1):PAGE62_I18@PURE_QUANTA.SOCKET4677_AZIF0045P001C01CS(CHIPS)':
 'PE4_RX_DN8': CDS_PINID='PE4_RX_DN8';
NODE_NAME     J111 F1
 '@S9S_MB_2U_LIB.S9S_MB_2U(SCH_1):PAGE148_I75@PURE_QUANTA.CONN112_10137002101LF(CHIPS)':
 'F1': CDS_PINID='F1';
NET_NAME
'P5E_CPU1_PE4_RX_DN<9>'
 '@S9S_MB_2U_LIB.S9S_MB_2U(SCH_1):P5E_CPU1_PE4_RX_DN'<9>:
 C_SIGNAL='@s9s_mb_2u_lib.s9s_mb_2u(sch_1):p5e_cpu1_pe4_rx_dn(9)';
NODE_NAME     U1 AK89
 '@S9S_MB_2U_LIB.S9S_MB_2U(SCH_1):PAGE62_I18@PURE_QUANTA.SOCKET4677_AZIF0045P001C01CS(CHIPS)':
 'PE4_RX_DN9': CDS_PINID='PE4_RX_DN9';
NODE_NAME     J111 F2
 '@S9S_MB_2U_LIB.S9S_MB_2U(SCH_1):PAGE148_I75@PURE_QUANTA.CONN112_10137002101LF(CHIPS)':
 'F2': CDS_PINID='F2';
NET_NAME
'P5E_CPU1_PE4_RX_DP<0>'
 '@S9S_MB_2U_LIB.S9S_MB_2U(SCH_1):P5E_CPU1_PE4_RX_DP'<0>:
 C_SIGNAL='@s9s_mb_2u_lib.s9s_mb_2u(sch_1):p5e_cpu1_pe4_rx_dp(0)';
NODE_NAME     U1 K89
 '@S9S_MB_2U_LIB.S9S_MB_2U(SCH_1):PAGE62_I18@PURE_QUANTA.SOCKET4677_AZIF0045P001C01CS(CHIPS)':
 'PE4_RX_DP0': CDS_PINID='PE4_RX_DP0';
NODE_NAME     J112 G1
 '@S9S_MB_2U_LIB.S9S_MB_2U(SCH_1):PAGE149_I76@PURE_QUANTA.CONN160_10131762101LF(CHIPS)':
 'G1': CDS_PINID='G1';
NET_NAME
'P5E_CPU1_PE4_RX_DP<10>'
 '@S9S_MB_2U_LIB.S9S_MB_2U(SCH_1):P5E_CPU1_PE4_RX_DP'<10>:
 C_SIGNAL='@s9s_mb_2u_lib.s9s_mb_2u(sch_1):p5e_cpu1_pe4_rx_dp(10)';
NODE_NAME     U1 AL90
 '@S9S_MB_2U_LIB.S9S_MB_2U(SCH_1):PAGE62_I18@PURE_QUANTA.SOCKET4677_AZIF0045P001C01CS(CHIPS)':
 'PE4_RX_DP10': CDS_PINID='PE4_RX_DP10';
NODE_NAME     J111 G3
 '@S9S_MB_2U_LIB.S9S_MB_2U(SCH_1):PAGE148_I75@PURE_QUANTA.CONN112_10137002101LF(CHIPS)':
 'G3': CDS_PINID='G3';
NET_NAME
'P5E_CPU1_PE4_RX_DP<11>'
 '@S9S_MB_2U_LIB.S9S_MB_2U(SCH_1):P5E_CPU1_PE4_RX_DP'<11>:
 C_SIGNAL='@s9s_mb_2u_lib.s9s_mb_2u(sch_1):p5e_cpu1_pe4_rx_dp(11)';
NODE_NAME     U1 AN90
 '@S9S_MB_2U_LIB.S9S_MB_2U(SCH_1):PAGE62_I18@PURE_QUANTA.SOCKET4677_AZIF0045P001C01CS(CHIPS)':
 'PE4_RX_DP11': CDS_PINID='PE4_RX_DP11';
NODE_NAME     J111 E4
 '@S9S_MB_2U_LIB.S9S_MB_2U(SCH_1):PAGE148_I75@PURE_QUANTA.CONN112_10137002101LF(CHIPS)':
 'E4': CDS_PINID='E4';
NET_NAME
'P5E_CPU1_PE4_RX_DP<12>'
 '@S9S_MB_2U_LIB.S9S_MB_2U(SCH_1):P5E_CPU1_PE4_RX_DP'<12>:
 C_SIGNAL='@s9s_mb_2u_lib.s9s_mb_2u(sch_1):p5e_cpu1_pe4_rx_dp(12)';
NODE_NAME     U1 AR90
 '@S9S_MB_2U_LIB.S9S_MB_2U(SCH_1):PAGE62_I18@PURE_QUANTA.SOCKET4677_AZIF0045P001C01CS(CHIPS)':
 'PE4_RX_DP12': CDS_PINID='PE4_RX_DP12';
NODE_NAME     J111 G5
 '@S9S_MB_2U_LIB.S9S_MB_2U(SCH_1):PAGE148_I74@PURE_QUANTA.CONN112_10137002101LF(CHIPS)':
 'G5': CDS_PINID='G5';
NET_NAME
'P5E_CPU1_PE4_RX_DP<13>'
 '@S9S_MB_2U_LIB.S9S_MB_2U(SCH_1):P5E_CPU1_PE4_RX_DP'<13>:
 C_SIGNAL='@s9s_mb_2u_lib.s9s_mb_2u(sch_1):p5e_cpu1_pe4_rx_dp(13)';
NODE_NAME     U1 AU90
 '@S9S_MB_2U_LIB.S9S_MB_2U(SCH_1):PAGE62_I18@PURE_QUANTA.SOCKET4677_AZIF0045P001C01CS(CHIPS)':
 'PE4_RX_DP13': CDS_PINID='PE4_RX_DP13';
NODE_NAME     J111 E6
 '@S9S_MB_2U_LIB.S9S_MB_2U(SCH_1):PAGE148_I74@PURE_QUANTA.CONN112_10137002101LF(CHIPS)':
 'E6': CDS_PINID='E6';
NET_NAME
'P5E_CPU1_PE4_RX_DP<14>'
 '@S9S_MB_2U_LIB.S9S_MB_2U(SCH_1):P5E_CPU1_PE4_RX_DP'<14>:
 C_SIGNAL='@s9s_mb_2u_lib.s9s_mb_2u(sch_1):p5e_cpu1_pe4_rx_dp(14)';
NODE_NAME     U1 AW90
 '@S9S_MB_2U_LIB.S9S_MB_2U(SCH_1):PAGE62_I18@PURE_QUANTA.SOCKET4677_AZIF0045P001C01CS(CHIPS)':
 'PE4_RX_DP14': CDS_PINID='PE4_RX_DP14';
NODE_NAME     J111 G7
 '@S9S_MB_2U_LIB.S9S_MB_2U(SCH_1):PAGE148_I74@PURE_QUANTA.CONN112_10137002101LF(CHIPS)':
 'G7': CDS_PINID='G7';
NET_NAME
'P5E_CPU1_PE4_RX_DP<15>'
 '@S9S_MB_2U_LIB.S9S_MB_2U(SCH_1):P5E_CPU1_PE4_RX_DP'<15>:
 C_SIGNAL='@s9s_mb_2u_lib.s9s_mb_2u(sch_1):p5e_cpu1_pe4_rx_dp(15)';
NODE_NAME     U1 BA90
 '@S9S_MB_2U_LIB.S9S_MB_2U(SCH_1):PAGE62_I18@PURE_QUANTA.SOCKET4677_AZIF0045P001C01CS(CHIPS)':
 'PE4_RX_DP15': CDS_PINID='PE4_RX_DP15';
NODE_NAME     J111 E8
 '@S9S_MB_2U_LIB.S9S_MB_2U(SCH_1):PAGE148_I74@PURE_QUANTA.CONN112_10137002101LF(CHIPS)':
 'E8': CDS_PINID='E8';
NET_NAME
'P5E_CPU1_PE4_RX_DP<1>'
 '@S9S_MB_2U_LIB.S9S_MB_2U(SCH_1):P5E_CPU1_PE4_RX_DP'<1>:
 C_SIGNAL='@s9s_mb_2u_lib.s9s_mb_2u(sch_1):p5e_cpu1_pe4_rx_dp(1)';
NODE_NAME     U1 N90
 '@S9S_MB_2U_LIB.S9S_MB_2U(SCH_1):PAGE62_I18@PURE_QUANTA.SOCKET4677_AZIF0045P001C01CS(CHIPS)':
 'PE4_RX_DP1': CDS_PINID='PE4_RX_DP1';
NODE_NAME     J112 E2
 '@S9S_MB_2U_LIB.S9S_MB_2U(SCH_1):PAGE149_I76@PURE_QUANTA.CONN160_10131762101LF(CHIPS)':
 'E2': CDS_PINID='E2';
NET_NAME
'P5E_CPU1_PE4_RX_DP<2>'
 '@S9S_MB_2U_LIB.S9S_MB_2U(SCH_1):P5E_CPU1_PE4_RX_DP'<2>:
 C_SIGNAL='@s9s_mb_2u_lib.s9s_mb_2u(sch_1):p5e_cpu1_pe4_rx_dp(2)';
NODE_NAME     U1 R90
 '@S9S_MB_2U_LIB.S9S_MB_2U(SCH_1):PAGE62_I18@PURE_QUANTA.SOCKET4677_AZIF0045P001C01CS(CHIPS)':
 'PE4_RX_DP2': CDS_PINID='PE4_RX_DP2';
NODE_NAME     J112 G3
 '@S9S_MB_2U_LIB.S9S_MB_2U(SCH_1):PAGE149_I76@PURE_QUANTA.CONN160_10131762101LF(CHIPS)':
 'G3': CDS_PINID='G3';
NET_NAME
'P5E_CPU1_PE4_RX_DP<3>'
 '@S9S_MB_2U_LIB.S9S_MB_2U(SCH_1):P5E_CPU1_PE4_RX_DP'<3>:
 C_SIGNAL='@s9s_mb_2u_lib.s9s_mb_2u(sch_1):p5e_cpu1_pe4_rx_dp(3)';
NODE_NAME     U1 U90
 '@S9S_MB_2U_LIB.S9S_MB_2U(SCH_1):PAGE62_I18@PURE_QUANTA.SOCKET4677_AZIF0045P001C01CS(CHIPS)':
 'PE4_RX_DP3': CDS_PINID='PE4_RX_DP3';
NODE_NAME     J112 E4
 '@S9S_MB_2U_LIB.S9S_MB_2U(SCH_1):PAGE149_I76@PURE_QUANTA.CONN160_10131762101LF(CHIPS)':
 'E4': CDS_PINID='E4';
NET_NAME
'P5E_CPU1_PE4_RX_DP<4>'
 '@S9S_MB_2U_LIB.S9S_MB_2U(SCH_1):P5E_CPU1_PE4_RX_DP'<4>:
 C_SIGNAL='@s9s_mb_2u_lib.s9s_mb_2u(sch_1):p5e_cpu1_pe4_rx_dp(4)';
NODE_NAME     U1 W90
 '@S9S_MB_2U_LIB.S9S_MB_2U(SCH_1):PAGE62_I18@PURE_QUANTA.SOCKET4677_AZIF0045P001C01CS(CHIPS)':
 'PE4_RX_DP4': CDS_PINID='PE4_RX_DP4';
NODE_NAME     J112 G5
 '@S9S_MB_2U_LIB.S9S_MB_2U(SCH_1):PAGE149_I75@PURE_QUANTA.CONN160_10131762101LF(CHIPS)':
 'G5': CDS_PINID='G5';
NET_NAME
'P5E_CPU1_PE4_RX_DP<5>'
 '@S9S_MB_2U_LIB.S9S_MB_2U(SCH_1):P5E_CPU1_PE4_RX_DP'<5>:
 C_SIGNAL='@s9s_mb_2u_lib.s9s_mb_2u(sch_1):p5e_cpu1_pe4_rx_dp(5)';
NODE_NAME     U1 AA90
 '@S9S_MB_2U_LIB.S9S_MB_2U(SCH_1):PAGE62_I18@PURE_QUANTA.SOCKET4677_AZIF0045P001C01CS(CHIPS)':
 'PE4_RX_DP5': CDS_PINID='PE4_RX_DP5';
NODE_NAME     J112 E6
 '@S9S_MB_2U_LIB.S9S_MB_2U(SCH_1):PAGE149_I75@PURE_QUANTA.CONN160_10131762101LF(CHIPS)':
 'E6': CDS_PINID='E6';
NET_NAME
'P5E_CPU1_PE4_RX_DP<6>'
 '@S9S_MB_2U_LIB.S9S_MB_2U(SCH_1):P5E_CPU1_PE4_RX_DP'<6>:
 C_SIGNAL='@s9s_mb_2u_lib.s9s_mb_2u(sch_1):p5e_cpu1_pe4_rx_dp(6)';
NODE_NAME     U1 AC90
 '@S9S_MB_2U_LIB.S9S_MB_2U(SCH_1):PAGE62_I18@PURE_QUANTA.SOCKET4677_AZIF0045P001C01CS(CHIPS)':
 'PE4_RX_DP6': CDS_PINID='PE4_RX_DP6';
NODE_NAME     J112 G7
 '@S9S_MB_2U_LIB.S9S_MB_2U(SCH_1):PAGE149_I75@PURE_QUANTA.CONN160_10131762101LF(CHIPS)':
 'G7': CDS_PINID='G7';
NET_NAME
'P5E_CPU1_PE4_RX_DP<7>'
 '@S9S_MB_2U_LIB.S9S_MB_2U(SCH_1):P5E_CPU1_PE4_RX_DP'<7>:
 C_SIGNAL='@s9s_mb_2u_lib.s9s_mb_2u(sch_1):p5e_cpu1_pe4_rx_dp(7)';
NODE_NAME     U1 AE90
 '@S9S_MB_2U_LIB.S9S_MB_2U(SCH_1):PAGE62_I18@PURE_QUANTA.SOCKET4677_AZIF0045P001C01CS(CHIPS)':
 'PE4_RX_DP7': CDS_PINID='PE4_RX_DP7';
NODE_NAME     J112 E8
 '@S9S_MB_2U_LIB.S9S_MB_2U(SCH_1):PAGE149_I75@PURE_QUANTA.CONN160_10131762101LF(CHIPS)':
 'E8': CDS_PINID='E8';
NET_NAME
'P5E_CPU1_PE4_RX_DP<8>'
 '@S9S_MB_2U_LIB.S9S_MB_2U(SCH_1):P5E_CPU1_PE4_RX_DP'<8>:
 C_SIGNAL='@s9s_mb_2u_lib.s9s_mb_2u(sch_1):p5e_cpu1_pe4_rx_dp(8)';
NODE_NAME     U1 AG90
 '@S9S_MB_2U_LIB.S9S_MB_2U(SCH_1):PAGE62_I18@PURE_QUANTA.SOCKET4677_AZIF0045P001C01CS(CHIPS)':
 'PE4_RX_DP8': CDS_PINID='PE4_RX_DP8';
NODE_NAME     J111 G1
 '@S9S_MB_2U_LIB.S9S_MB_2U(SCH_1):PAGE148_I75@PURE_QUANTA.CONN112_10137002101LF(CHIPS)':
 'G1': CDS_PINID='G1';
NET_NAME
'P5E_CPU1_PE4_RX_DP<9>'
 '@S9S_MB_2U_LIB.S9S_MB_2U(SCH_1):P5E_CPU1_PE4_RX_DP'<9>:
 C_SIGNAL='@s9s_mb_2u_lib.s9s_mb_2u(sch_1):p5e_cpu1_pe4_rx_dp(9)';
NODE_NAME     U1 AJ90
 '@S9S_MB_2U_LIB.S9S_MB_2U(SCH_1):PAGE62_I18@PURE_QUANTA.SOCKET4677_AZIF0045P001C01CS(CHIPS)':
 'PE4_RX_DP9': CDS_PINID='PE4_RX_DP9';
NODE_NAME     J111 E2
 '@S9S_MB_2U_LIB.S9S_MB_2U(SCH_1):PAGE148_I75@PURE_QUANTA.CONN112_10137002101LF(CHIPS)':
 'E2': CDS_PINID='E2';
NET_NAME
'P5E_CPU1_PE4_TX_C_DN<0>'
 '@S9S_MB_2U_LIB.S9S_MB_2U(SCH_1):P5E_CPU1_PE4_TX_C_DN'<0>:
 C_SIGNAL='@s9s_mb_2u_lib.s9s_mb_2u(sch_1):p5e_cpu1_pe4_tx_c_dn(0)';
NODE_NAME     C708 1
 '@S9S_MB_2U_LIB.S9S_MB_2U(SCH_1):PAGE168_I125@PURE_QUANTA.Q_CAP_DIFFBUS(CHIPS)':
 '1': CDS_PINID='\1\';
NODE_NAME     J112 L1
 '@S9S_MB_2U_LIB.S9S_MB_2U(SCH_1):PAGE149_I76@PURE_QUANTA.CONN160_10131762101LF(CHIPS)':
 'L1': CDS_PINID='L1';
NET_NAME
'P5E_CPU1_PE4_TX_C_DN<10>'
 '@S9S_MB_2U_LIB.S9S_MB_2U(SCH_1):P5E_CPU1_PE4_TX_C_DN'<10>:
 C_SIGNAL='@s9s_mb_2u_lib.s9s_mb_2u(sch_1):p5e_cpu1_pe4_tx_c_dn(10)';
NODE_NAME     C688 1
 '@S9S_MB_2U_LIB.S9S_MB_2U(SCH_1):PAGE168_I162@PURE_QUANTA.Q_CAP_DIFFBUS(CHIPS)':
 '1': CDS_PINID='\1\';
NODE_NAME     J111 L3
 '@S9S_MB_2U_LIB.S9S_MB_2U(SCH_1):PAGE148_I75@PURE_QUANTA.CONN112_10137002101LF(CHIPS)':
 'L3': CDS_PINID='L3';
NET_NAME
'P5E_CPU1_PE4_TX_C_DN<11>'
 '@S9S_MB_2U_LIB.S9S_MB_2U(SCH_1):P5E_CPU1_PE4_TX_C_DN'<11>:
 C_SIGNAL='@s9s_mb_2u_lib.s9s_mb_2u(sch_1):p5e_cpu1_pe4_tx_c_dn(11)';
NODE_NAME     C686 1
 '@S9S_MB_2U_LIB.S9S_MB_2U(SCH_1):PAGE168_I164@PURE_QUANTA.Q_CAP_DIFFBUS(CHIPS)':
 '1': CDS_PINID='\1\';
NODE_NAME     J111 L4
 '@S9S_MB_2U_LIB.S9S_MB_2U(SCH_1):PAGE148_I75@PURE_QUANTA.CONN112_10137002101LF(CHIPS)':
 'L4': CDS_PINID='L4';
NET_NAME
'P5E_CPU1_PE4_TX_C_DN<12>'
 '@S9S_MB_2U_LIB.S9S_MB_2U(SCH_1):P5E_CPU1_PE4_TX_C_DN'<12>:
 C_SIGNAL='@s9s_mb_2u_lib.s9s_mb_2u(sch_1):p5e_cpu1_pe4_tx_c_dn(12)';
NODE_NAME     C684 1
 '@S9S_MB_2U_LIB.S9S_MB_2U(SCH_1):PAGE168_I166@PURE_QUANTA.Q_CAP_DIFFBUS(CHIPS)':
 '1': CDS_PINID='\1\';
NODE_NAME     J111 L5
 '@S9S_MB_2U_LIB.S9S_MB_2U(SCH_1):PAGE148_I74@PURE_QUANTA.CONN112_10137002101LF(CHIPS)':
 'L5': CDS_PINID='L5';
NET_NAME
'P5E_CPU1_PE4_TX_C_DN<13>'
 '@S9S_MB_2U_LIB.S9S_MB_2U(SCH_1):P5E_CPU1_PE4_TX_C_DN'<13>:
 C_SIGNAL='@s9s_mb_2u_lib.s9s_mb_2u(sch_1):p5e_cpu1_pe4_tx_c_dn(13)';
NODE_NAME     C682 1
 '@S9S_MB_2U_LIB.S9S_MB_2U(SCH_1):PAGE168_I167@PURE_QUANTA.Q_CAP_DIFFBUS(CHIPS)':
 '1': CDS_PINID='\1\';
NODE_NAME     J111 K6
 '@S9S_MB_2U_LIB.S9S_MB_2U(SCH_1):PAGE148_I74@PURE_QUANTA.CONN112_10137002101LF(CHIPS)':
 'K6': CDS_PINID='K6';
NET_NAME
'P5E_CPU1_PE4_TX_C_DN<14>'
 '@S9S_MB_2U_LIB.S9S_MB_2U(SCH_1):P5E_CPU1_PE4_TX_C_DN'<14>:
 C_SIGNAL='@s9s_mb_2u_lib.s9s_mb_2u(sch_1):p5e_cpu1_pe4_tx_c_dn(14)';
NODE_NAME     C680 1
 '@S9S_MB_2U_LIB.S9S_MB_2U(SCH_1):PAGE168_I170@PURE_QUANTA.Q_CAP_DIFFBUS(CHIPS)':
 '1': CDS_PINID='\1\';
NODE_NAME     J111 L7
 '@S9S_MB_2U_LIB.S9S_MB_2U(SCH_1):PAGE148_I74@PURE_QUANTA.CONN112_10137002101LF(CHIPS)':
 'L7': CDS_PINID='L7';
NET_NAME
'P5E_CPU1_PE4_TX_C_DN<15>'
 '@S9S_MB_2U_LIB.S9S_MB_2U(SCH_1):P5E_CPU1_PE4_TX_C_DN'<15>:
 C_SIGNAL='@s9s_mb_2u_lib.s9s_mb_2u(sch_1):p5e_cpu1_pe4_tx_c_dn(15)';
NODE_NAME     C678 1
 '@S9S_MB_2U_LIB.S9S_MB_2U(SCH_1):PAGE168_I172@PURE_QUANTA.Q_CAP_DIFFBUS(CHIPS)':
 '1': CDS_PINID='\1\';
NODE_NAME     J111 K8
 '@S9S_MB_2U_LIB.S9S_MB_2U(SCH_1):PAGE148_I74@PURE_QUANTA.CONN112_10137002101LF(CHIPS)':
 'K8': CDS_PINID='K8';
NET_NAME
'P5E_CPU1_PE4_TX_C_DN<1>'
 '@S9S_MB_2U_LIB.S9S_MB_2U(SCH_1):P5E_CPU1_PE4_TX_C_DN'<1>:
 C_SIGNAL='@s9s_mb_2u_lib.s9s_mb_2u(sch_1):p5e_cpu1_pe4_tx_c_dn(1)';
NODE_NAME     C706 1
 '@S9S_MB_2U_LIB.S9S_MB_2U(SCH_1):PAGE168_I127@PURE_QUANTA.Q_CAP_DIFFBUS(CHIPS)':
 '1': CDS_PINID='\1\';
NODE_NAME     J112 L2
 '@S9S_MB_2U_LIB.S9S_MB_2U(SCH_1):PAGE149_I76@PURE_QUANTA.CONN160_10131762101LF(CHIPS)':
 'L2': CDS_PINID='L2';
NET_NAME
'P5E_CPU1_PE4_TX_C_DN<2>'
 '@S9S_MB_2U_LIB.S9S_MB_2U(SCH_1):P5E_CPU1_PE4_TX_C_DN'<2>:
 C_SIGNAL='@s9s_mb_2u_lib.s9s_mb_2u(sch_1):p5e_cpu1_pe4_tx_c_dn(2)';
NODE_NAME     C704 1
 '@S9S_MB_2U_LIB.S9S_MB_2U(SCH_1):PAGE168_I129@PURE_QUANTA.Q_CAP_DIFFBUS(CHIPS)':
 '1': CDS_PINID='\1\';
NODE_NAME     J112 L3
 '@S9S_MB_2U_LIB.S9S_MB_2U(SCH_1):PAGE149_I76@PURE_QUANTA.CONN160_10131762101LF(CHIPS)':
 'L3': CDS_PINID='L3';
NET_NAME
'P5E_CPU1_PE4_TX_C_DN<3>'
 '@S9S_MB_2U_LIB.S9S_MB_2U(SCH_1):P5E_CPU1_PE4_TX_C_DN'<3>:
 C_SIGNAL='@s9s_mb_2u_lib.s9s_mb_2u(sch_1):p5e_cpu1_pe4_tx_c_dn(3)';
NODE_NAME     C702 1
 '@S9S_MB_2U_LIB.S9S_MB_2U(SCH_1):PAGE168_I132@PURE_QUANTA.Q_CAP_DIFFBUS(CHIPS)':
 '1': CDS_PINID='\1\';
NODE_NAME     J112 K4
 '@S9S_MB_2U_LIB.S9S_MB_2U(SCH_1):PAGE149_I76@PURE_QUANTA.CONN160_10131762101LF(CHIPS)':
 'K4': CDS_PINID='K4';
NET_NAME
'P5E_CPU1_PE4_TX_C_DN<4>'
 '@S9S_MB_2U_LIB.S9S_MB_2U(SCH_1):P5E_CPU1_PE4_TX_C_DN'<4>:
 C_SIGNAL='@s9s_mb_2u_lib.s9s_mb_2u(sch_1):p5e_cpu1_pe4_tx_c_dn(4)';
NODE_NAME     C700 1
 '@S9S_MB_2U_LIB.S9S_MB_2U(SCH_1):PAGE168_I134@PURE_QUANTA.Q_CAP_DIFFBUS(CHIPS)':
 '1': CDS_PINID='\1\';
NODE_NAME     J112 L5
 '@S9S_MB_2U_LIB.S9S_MB_2U(SCH_1):PAGE149_I75@PURE_QUANTA.CONN160_10131762101LF(CHIPS)':
 'L5': CDS_PINID='L5';
NET_NAME
'P5E_CPU1_PE4_TX_C_DN<5>'
 '@S9S_MB_2U_LIB.S9S_MB_2U(SCH_1):P5E_CPU1_PE4_TX_C_DN'<5>:
 C_SIGNAL='@s9s_mb_2u_lib.s9s_mb_2u(sch_1):p5e_cpu1_pe4_tx_c_dn(5)';
NODE_NAME     C698 1
 '@S9S_MB_2U_LIB.S9S_MB_2U(SCH_1):PAGE168_I135@PURE_QUANTA.Q_CAP_DIFFBUS(CHIPS)':
 '1': CDS_PINID='\1\';
NODE_NAME     J112 K6
 '@S9S_MB_2U_LIB.S9S_MB_2U(SCH_1):PAGE149_I75@PURE_QUANTA.CONN160_10131762101LF(CHIPS)':
 'K6': CDS_PINID='K6';
NET_NAME
'P5E_CPU1_PE4_TX_C_DN<6>'
 '@S9S_MB_2U_LIB.S9S_MB_2U(SCH_1):P5E_CPU1_PE4_TX_C_DN'<6>:
 C_SIGNAL='@s9s_mb_2u_lib.s9s_mb_2u(sch_1):p5e_cpu1_pe4_tx_c_dn(6)';
NODE_NAME     C696 1
 '@S9S_MB_2U_LIB.S9S_MB_2U(SCH_1):PAGE168_I137@PURE_QUANTA.Q_CAP_DIFFBUS(CHIPS)':
 '1': CDS_PINID='\1\';
NODE_NAME     J112 L7
 '@S9S_MB_2U_LIB.S9S_MB_2U(SCH_1):PAGE149_I75@PURE_QUANTA.CONN160_10131762101LF(CHIPS)':
 'L7': CDS_PINID='L7';
NET_NAME
'P5E_CPU1_PE4_TX_C_DN<7>'
 '@S9S_MB_2U_LIB.S9S_MB_2U(SCH_1):P5E_CPU1_PE4_TX_C_DN'<7>:
 C_SIGNAL='@s9s_mb_2u_lib.s9s_mb_2u(sch_1):p5e_cpu1_pe4_tx_c_dn(7)';
NODE_NAME     C694 1
 '@S9S_MB_2U_LIB.S9S_MB_2U(SCH_1):PAGE168_I140@PURE_QUANTA.Q_CAP_DIFFBUS(CHIPS)':
 '1': CDS_PINID='\1\';
NODE_NAME     J112 K8
 '@S9S_MB_2U_LIB.S9S_MB_2U(SCH_1):PAGE149_I75@PURE_QUANTA.CONN160_10131762101LF(CHIPS)':
 'K8': CDS_PINID='K8';
NET_NAME
'P5E_CPU1_PE4_TX_C_DN<8>'
 '@S9S_MB_2U_LIB.S9S_MB_2U(SCH_1):P5E_CPU1_PE4_TX_C_DN'<8>:
 C_SIGNAL='@s9s_mb_2u_lib.s9s_mb_2u(sch_1):p5e_cpu1_pe4_tx_c_dn(8)';
NODE_NAME     C692 1
 '@S9S_MB_2U_LIB.S9S_MB_2U(SCH_1):PAGE168_I158@PURE_QUANTA.Q_CAP_DIFFBUS(CHIPS)':
 '1': CDS_PINID='\1\';
NODE_NAME     J111 L1
 '@S9S_MB_2U_LIB.S9S_MB_2U(SCH_1):PAGE148_I75@PURE_QUANTA.CONN112_10137002101LF(CHIPS)':
 'L1': CDS_PINID='L1';
NET_NAME
'P5E_CPU1_PE4_TX_C_DN<9>'
 '@S9S_MB_2U_LIB.S9S_MB_2U(SCH_1):P5E_CPU1_PE4_TX_C_DN'<9>:
 C_SIGNAL='@s9s_mb_2u_lib.s9s_mb_2u(sch_1):p5e_cpu1_pe4_tx_c_dn(9)';
NODE_NAME     C690 1
 '@S9S_MB_2U_LIB.S9S_MB_2U(SCH_1):PAGE168_I159@PURE_QUANTA.Q_CAP_DIFFBUS(CHIPS)':
 '1': CDS_PINID='\1\';
NODE_NAME     J111 K2
 '@S9S_MB_2U_LIB.S9S_MB_2U(SCH_1):PAGE148_I75@PURE_QUANTA.CONN112_10137002101LF(CHIPS)':
 'K2': CDS_PINID='K2';
NET_NAME
'P5E_CPU1_PE4_TX_C_DP<0>'
 '@S9S_MB_2U_LIB.S9S_MB_2U(SCH_1):P5E_CPU1_PE4_TX_C_DP'<0>:
 C_SIGNAL='@s9s_mb_2u_lib.s9s_mb_2u(sch_1):p5e_cpu1_pe4_tx_c_dp(0)';
NODE_NAME     C709 1
 '@S9S_MB_2U_LIB.S9S_MB_2U(SCH_1):PAGE168_I126@PURE_QUANTA.Q_CAP_DIFFBUS(CHIPS)':
 '1': CDS_PINID='\1\';
NODE_NAME     J112 M1
 '@S9S_MB_2U_LIB.S9S_MB_2U(SCH_1):PAGE149_I76@PURE_QUANTA.CONN160_10131762101LF(CHIPS)':
 'M1': CDS_PINID='M1';
NET_NAME
'P5E_CPU1_PE4_TX_C_DP<10>'
 '@S9S_MB_2U_LIB.S9S_MB_2U(SCH_1):P5E_CPU1_PE4_TX_C_DP'<10>:
 C_SIGNAL='@s9s_mb_2u_lib.s9s_mb_2u(sch_1):p5e_cpu1_pe4_tx_c_dp(10)';
NODE_NAME     C689 1
 '@S9S_MB_2U_LIB.S9S_MB_2U(SCH_1):PAGE168_I163@PURE_QUANTA.Q_CAP_DIFFBUS(CHIPS)':
 '1': CDS_PINID='\1\';
NODE_NAME     J111 M3
 '@S9S_MB_2U_LIB.S9S_MB_2U(SCH_1):PAGE148_I75@PURE_QUANTA.CONN112_10137002101LF(CHIPS)':
 'M3': CDS_PINID='M3';
NET_NAME
'P5E_CPU1_PE4_TX_C_DP<11>'
 '@S9S_MB_2U_LIB.S9S_MB_2U(SCH_1):P5E_CPU1_PE4_TX_C_DP'<11>:
 C_SIGNAL='@s9s_mb_2u_lib.s9s_mb_2u(sch_1):p5e_cpu1_pe4_tx_c_dp(11)';
NODE_NAME     C687 1
 '@S9S_MB_2U_LIB.S9S_MB_2U(SCH_1):PAGE168_I161@PURE_QUANTA.Q_CAP_DIFFBUS(CHIPS)':
 '1': CDS_PINID='\1\';
NODE_NAME     J111 K4
 '@S9S_MB_2U_LIB.S9S_MB_2U(SCH_1):PAGE148_I75@PURE_QUANTA.CONN112_10137002101LF(CHIPS)':
 'K4': CDS_PINID='K4';
NET_NAME
'P5E_CPU1_PE4_TX_C_DP<12>'
 '@S9S_MB_2U_LIB.S9S_MB_2U(SCH_1):P5E_CPU1_PE4_TX_C_DP'<12>:
 C_SIGNAL='@s9s_mb_2u_lib.s9s_mb_2u(sch_1):p5e_cpu1_pe4_tx_c_dp(12)';
NODE_NAME     C685 1
 '@S9S_MB_2U_LIB.S9S_MB_2U(SCH_1):PAGE168_I165@PURE_QUANTA.Q_CAP_DIFFBUS(CHIPS)':
 '1': CDS_PINID='\1\';
NODE_NAME     J111 M5
 '@S9S_MB_2U_LIB.S9S_MB_2U(SCH_1):PAGE148_I74@PURE_QUANTA.CONN112_10137002101LF(CHIPS)':
 'M5': CDS_PINID='M5';
NET_NAME
'P5E_CPU1_PE4_TX_C_DP<13>'
 '@S9S_MB_2U_LIB.S9S_MB_2U(SCH_1):P5E_CPU1_PE4_TX_C_DP'<13>:
 C_SIGNAL='@s9s_mb_2u_lib.s9s_mb_2u(sch_1):p5e_cpu1_pe4_tx_c_dp(13)';
NODE_NAME     C683 1
 '@S9S_MB_2U_LIB.S9S_MB_2U(SCH_1):PAGE168_I168@PURE_QUANTA.Q_CAP_DIFFBUS(CHIPS)':
 '1': CDS_PINID='\1\';
NODE_NAME     J111 L6
 '@S9S_MB_2U_LIB.S9S_MB_2U(SCH_1):PAGE148_I74@PURE_QUANTA.CONN112_10137002101LF(CHIPS)':
 'L6': CDS_PINID='L6';
NET_NAME
'P5E_CPU1_PE4_TX_C_DP<14>'
 '@S9S_MB_2U_LIB.S9S_MB_2U(SCH_1):P5E_CPU1_PE4_TX_C_DP'<14>:
 C_SIGNAL='@s9s_mb_2u_lib.s9s_mb_2u(sch_1):p5e_cpu1_pe4_tx_c_dp(14)';
NODE_NAME     C681 1
 '@S9S_MB_2U_LIB.S9S_MB_2U(SCH_1):PAGE168_I171@PURE_QUANTA.Q_CAP_DIFFBUS(CHIPS)':
 '1': CDS_PINID='\1\';
NODE_NAME     J111 M7
 '@S9S_MB_2U_LIB.S9S_MB_2U(SCH_1):PAGE148_I74@PURE_QUANTA.CONN112_10137002101LF(CHIPS)':
 'M7': CDS_PINID='M7';
NET_NAME
'P5E_CPU1_PE4_TX_C_DP<15>'
 '@S9S_MB_2U_LIB.S9S_MB_2U(SCH_1):P5E_CPU1_PE4_TX_C_DP'<15>:
 C_SIGNAL='@s9s_mb_2u_lib.s9s_mb_2u(sch_1):p5e_cpu1_pe4_tx_c_dp(15)';
NODE_NAME     C679 1
 '@S9S_MB_2U_LIB.S9S_MB_2U(SCH_1):PAGE168_I169@PURE_QUANTA.Q_CAP_DIFFBUS(CHIPS)':
 '1': CDS_PINID='\1\';
NODE_NAME     J111 L8
 '@S9S_MB_2U_LIB.S9S_MB_2U(SCH_1):PAGE148_I74@PURE_QUANTA.CONN112_10137002101LF(CHIPS)':
 'L8': CDS_PINID='L8';
NET_NAME
'P5E_CPU1_PE4_TX_C_DP<1>'
 '@S9S_MB_2U_LIB.S9S_MB_2U(SCH_1):P5E_CPU1_PE4_TX_C_DP'<1>:
 C_SIGNAL='@s9s_mb_2u_lib.s9s_mb_2u(sch_1):p5e_cpu1_pe4_tx_c_dp(1)';
NODE_NAME     C707 1
 '@S9S_MB_2U_LIB.S9S_MB_2U(SCH_1):PAGE168_I128@PURE_QUANTA.Q_CAP_DIFFBUS(CHIPS)':
 '1': CDS_PINID='\1\';
NODE_NAME     J112 K2
 '@S9S_MB_2U_LIB.S9S_MB_2U(SCH_1):PAGE149_I76@PURE_QUANTA.CONN160_10131762101LF(CHIPS)':
 'K2': CDS_PINID='K2';
NET_NAME
'P5E_CPU1_PE4_TX_C_DP<2>'
 '@S9S_MB_2U_LIB.S9S_MB_2U(SCH_1):P5E_CPU1_PE4_TX_C_DP'<2>:
 C_SIGNAL='@s9s_mb_2u_lib.s9s_mb_2u(sch_1):p5e_cpu1_pe4_tx_c_dp(2)';
NODE_NAME     C705 1
 '@S9S_MB_2U_LIB.S9S_MB_2U(SCH_1):PAGE168_I130@PURE_QUANTA.Q_CAP_DIFFBUS(CHIPS)':
 '1': CDS_PINID='\1\';
NODE_NAME     J112 M3
 '@S9S_MB_2U_LIB.S9S_MB_2U(SCH_1):PAGE149_I76@PURE_QUANTA.CONN160_10131762101LF(CHIPS)':
 'M3': CDS_PINID='M3';
NET_NAME
'P5E_CPU1_PE4_TX_C_DP<3>'
 '@S9S_MB_2U_LIB.S9S_MB_2U(SCH_1):P5E_CPU1_PE4_TX_C_DP'<3>:
 C_SIGNAL='@s9s_mb_2u_lib.s9s_mb_2u(sch_1):p5e_cpu1_pe4_tx_c_dp(3)';
NODE_NAME     C703 1
 '@S9S_MB_2U_LIB.S9S_MB_2U(SCH_1):PAGE168_I133@PURE_QUANTA.Q_CAP_DIFFBUS(CHIPS)':
 '1': CDS_PINID='\1\';
NODE_NAME     J112 L4
 '@S9S_MB_2U_LIB.S9S_MB_2U(SCH_1):PAGE149_I76@PURE_QUANTA.CONN160_10131762101LF(CHIPS)':
 'L4': CDS_PINID='L4';
NET_NAME
'P5E_CPU1_PE4_TX_C_DP<4>'
 '@S9S_MB_2U_LIB.S9S_MB_2U(SCH_1):P5E_CPU1_PE4_TX_C_DP'<4>:
 C_SIGNAL='@s9s_mb_2u_lib.s9s_mb_2u(sch_1):p5e_cpu1_pe4_tx_c_dp(4)';
NODE_NAME     C701 1
 '@S9S_MB_2U_LIB.S9S_MB_2U(SCH_1):PAGE168_I131@PURE_QUANTA.Q_CAP_DIFFBUS(CHIPS)':
 '1': CDS_PINID='\1\';
NODE_NAME     J112 M5
 '@S9S_MB_2U_LIB.S9S_MB_2U(SCH_1):PAGE149_I75@PURE_QUANTA.CONN160_10131762101LF(CHIPS)':
 'M5': CDS_PINID='M5';
NET_NAME
'P5E_CPU1_PE4_TX_C_DP<5>'
 '@S9S_MB_2U_LIB.S9S_MB_2U(SCH_1):P5E_CPU1_PE4_TX_C_DP'<5>:
 C_SIGNAL='@s9s_mb_2u_lib.s9s_mb_2u(sch_1):p5e_cpu1_pe4_tx_c_dp(5)';
NODE_NAME     C699 1
 '@S9S_MB_2U_LIB.S9S_MB_2U(SCH_1):PAGE168_I136@PURE_QUANTA.Q_CAP_DIFFBUS(CHIPS)':
 '1': CDS_PINID='\1\';
NODE_NAME     J112 L6
 '@S9S_MB_2U_LIB.S9S_MB_2U(SCH_1):PAGE149_I75@PURE_QUANTA.CONN160_10131762101LF(CHIPS)':
 'L6': CDS_PINID='L6';
NET_NAME
'P5E_CPU1_PE4_TX_C_DP<6>'
 '@S9S_MB_2U_LIB.S9S_MB_2U(SCH_1):P5E_CPU1_PE4_TX_C_DP'<6>:
 C_SIGNAL='@s9s_mb_2u_lib.s9s_mb_2u(sch_1):p5e_cpu1_pe4_tx_c_dp(6)';
NODE_NAME     C697 1
 '@S9S_MB_2U_LIB.S9S_MB_2U(SCH_1):PAGE168_I138@PURE_QUANTA.Q_CAP_DIFFBUS(CHIPS)':
 '1': CDS_PINID='\1\';
NODE_NAME     J112 M7
 '@S9S_MB_2U_LIB.S9S_MB_2U(SCH_1):PAGE149_I75@PURE_QUANTA.CONN160_10131762101LF(CHIPS)':
 'M7': CDS_PINID='M7';
NET_NAME
'P5E_CPU1_PE4_TX_C_DP<7>'
 '@S9S_MB_2U_LIB.S9S_MB_2U(SCH_1):P5E_CPU1_PE4_TX_C_DP'<7>:
 C_SIGNAL='@s9s_mb_2u_lib.s9s_mb_2u(sch_1):p5e_cpu1_pe4_tx_c_dp(7)';
NODE_NAME     C695 1
 '@S9S_MB_2U_LIB.S9S_MB_2U(SCH_1):PAGE168_I139@PURE_QUANTA.Q_CAP_DIFFBUS(CHIPS)':
 '1': CDS_PINID='\1\';
NODE_NAME     J112 L8
 '@S9S_MB_2U_LIB.S9S_MB_2U(SCH_1):PAGE149_I75@PURE_QUANTA.CONN160_10131762101LF(CHIPS)':
 'L8': CDS_PINID='L8';
NET_NAME
'P5E_CPU1_PE4_TX_C_DP<8>'
 '@S9S_MB_2U_LIB.S9S_MB_2U(SCH_1):P5E_CPU1_PE4_TX_C_DP'<8>:
 C_SIGNAL='@s9s_mb_2u_lib.s9s_mb_2u(sch_1):p5e_cpu1_pe4_tx_c_dp(8)';
NODE_NAME     C693 1
 '@S9S_MB_2U_LIB.S9S_MB_2U(SCH_1):PAGE168_I157@PURE_QUANTA.Q_CAP_DIFFBUS(CHIPS)':
 '1': CDS_PINID='\1\';
NODE_NAME     J111 M1
 '@S9S_MB_2U_LIB.S9S_MB_2U(SCH_1):PAGE148_I75@PURE_QUANTA.CONN112_10137002101LF(CHIPS)':
 'M1': CDS_PINID='M1';
NET_NAME
'P5E_CPU1_PE4_TX_C_DP<9>'
 '@S9S_MB_2U_LIB.S9S_MB_2U(SCH_1):P5E_CPU1_PE4_TX_C_DP'<9>:
 C_SIGNAL='@s9s_mb_2u_lib.s9s_mb_2u(sch_1):p5e_cpu1_pe4_tx_c_dp(9)';
NODE_NAME     C691 1
 '@S9S_MB_2U_LIB.S9S_MB_2U(SCH_1):PAGE168_I160@PURE_QUANTA.Q_CAP_DIFFBUS(CHIPS)':
 '1': CDS_PINID='\1\';
NODE_NAME     J111 L2
 '@S9S_MB_2U_LIB.S9S_MB_2U(SCH_1):PAGE148_I75@PURE_QUANTA.CONN112_10137002101LF(CHIPS)':
 'L2': CDS_PINID='L2';
NET_NAME
'P5E_CPU1_PE4_TX_DN<0>'
 '@S9S_MB_2U_LIB.S9S_MB_2U(SCH_1):P5E_CPU1_PE4_TX_DN'<0>:
 C_SIGNAL='@s9s_mb_2u_lib.s9s_mb_2u(sch_1):p5e_cpu1_pe4_tx_dn(0)';
NODE_NAME     U1 L86
 '@S9S_MB_2U_LIB.S9S_MB_2U(SCH_1):PAGE62_I18@PURE_QUANTA.SOCKET4677_AZIF0045P001C01CS(CHIPS)':
 'PE4_TX_DN0': CDS_PINID='PE4_TX_DN0';
NODE_NAME     C708 2
 '@S9S_MB_2U_LIB.S9S_MB_2U(SCH_1):PAGE168_I125@PURE_QUANTA.Q_CAP_DIFFBUS(CHIPS)':
 '2': CDS_PINID='\2\';
NET_NAME
'P5E_CPU1_PE4_TX_DN<10>'
 '@S9S_MB_2U_LIB.S9S_MB_2U(SCH_1):P5E_CPU1_PE4_TX_DN'<10>:
 C_SIGNAL='@s9s_mb_2u_lib.s9s_mb_2u(sch_1):p5e_cpu1_pe4_tx_dn(10)';
NODE_NAME     U1 AL86
 '@S9S_MB_2U_LIB.S9S_MB_2U(SCH_1):PAGE62_I18@PURE_QUANTA.SOCKET4677_AZIF0045P001C01CS(CHIPS)':
 'PE4_TX_DN10': CDS_PINID='PE4_TX_DN10';
NODE_NAME     C688 2
 '@S9S_MB_2U_LIB.S9S_MB_2U(SCH_1):PAGE168_I162@PURE_QUANTA.Q_CAP_DIFFBUS(CHIPS)':
 '2': CDS_PINID='\2\';
NET_NAME
'P5E_CPU1_PE4_TX_DN<11>'
 '@S9S_MB_2U_LIB.S9S_MB_2U(SCH_1):P5E_CPU1_PE4_TX_DN'<11>:
 C_SIGNAL='@s9s_mb_2u_lib.s9s_mb_2u(sch_1):p5e_cpu1_pe4_tx_dn(11)';
NODE_NAME     U1 AP85
 '@S9S_MB_2U_LIB.S9S_MB_2U(SCH_1):PAGE62_I18@PURE_QUANTA.SOCKET4677_AZIF0045P001C01CS(CHIPS)':
 'PE4_TX_DN11': CDS_PINID='PE4_TX_DN11';
NODE_NAME     C686 2
 '@S9S_MB_2U_LIB.S9S_MB_2U(SCH_1):PAGE168_I164@PURE_QUANTA.Q_CAP_DIFFBUS(CHIPS)':
 '2': CDS_PINID='\2\';
NET_NAME
'P5E_CPU1_PE4_TX_DN<12>'
 '@S9S_MB_2U_LIB.S9S_MB_2U(SCH_1):P5E_CPU1_PE4_TX_DN'<12>:
 C_SIGNAL='@s9s_mb_2u_lib.s9s_mb_2u(sch_1):p5e_cpu1_pe4_tx_dn(12)';
NODE_NAME     U1 AR86
 '@S9S_MB_2U_LIB.S9S_MB_2U(SCH_1):PAGE62_I18@PURE_QUANTA.SOCKET4677_AZIF0045P001C01CS(CHIPS)':
 'PE4_TX_DN12': CDS_PINID='PE4_TX_DN12';
NODE_NAME     C684 2
 '@S9S_MB_2U_LIB.S9S_MB_2U(SCH_1):PAGE168_I166@PURE_QUANTA.Q_CAP_DIFFBUS(CHIPS)':
 '2': CDS_PINID='\2\';
NET_NAME
'P5E_CPU1_PE4_TX_DN<13>'
 '@S9S_MB_2U_LIB.S9S_MB_2U(SCH_1):P5E_CPU1_PE4_TX_DN'<13>:
 C_SIGNAL='@s9s_mb_2u_lib.s9s_mb_2u(sch_1):p5e_cpu1_pe4_tx_dn(13)';
NODE_NAME     U1 AU86
 '@S9S_MB_2U_LIB.S9S_MB_2U(SCH_1):PAGE62_I18@PURE_QUANTA.SOCKET4677_AZIF0045P001C01CS(CHIPS)':
 'PE4_TX_DN13': CDS_PINID='PE4_TX_DN13';
NODE_NAME     C682 2
 '@S9S_MB_2U_LIB.S9S_MB_2U(SCH_1):PAGE168_I167@PURE_QUANTA.Q_CAP_DIFFBUS(CHIPS)':
 '2': CDS_PINID='\2\';
NET_NAME
'P5E_CPU1_PE4_TX_DN<14>'
 '@S9S_MB_2U_LIB.S9S_MB_2U(SCH_1):P5E_CPU1_PE4_TX_DN'<14>:
 C_SIGNAL='@s9s_mb_2u_lib.s9s_mb_2u(sch_1):p5e_cpu1_pe4_tx_dn(14)';
NODE_NAME     U1 AW86
 '@S9S_MB_2U_LIB.S9S_MB_2U(SCH_1):PAGE62_I18@PURE_QUANTA.SOCKET4677_AZIF0045P001C01CS(CHIPS)':
 'PE4_TX_DN14': CDS_PINID='PE4_TX_DN14';
NODE_NAME     C680 2
 '@S9S_MB_2U_LIB.S9S_MB_2U(SCH_1):PAGE168_I170@PURE_QUANTA.Q_CAP_DIFFBUS(CHIPS)':
 '2': CDS_PINID='\2\';
NET_NAME
'P5E_CPU1_PE4_TX_DN<15>'
 '@S9S_MB_2U_LIB.S9S_MB_2U(SCH_1):P5E_CPU1_PE4_TX_DN'<15>:
 C_SIGNAL='@s9s_mb_2u_lib.s9s_mb_2u(sch_1):p5e_cpu1_pe4_tx_dn(15)';
NODE_NAME     U1 BA86
 '@S9S_MB_2U_LIB.S9S_MB_2U(SCH_1):PAGE62_I18@PURE_QUANTA.SOCKET4677_AZIF0045P001C01CS(CHIPS)':
 'PE4_TX_DN15': CDS_PINID='PE4_TX_DN15';
NODE_NAME     C678 2
 '@S9S_MB_2U_LIB.S9S_MB_2U(SCH_1):PAGE168_I172@PURE_QUANTA.Q_CAP_DIFFBUS(CHIPS)':
 '2': CDS_PINID='\2\';
NET_NAME
'P5E_CPU1_PE4_TX_DN<1>'
 '@S9S_MB_2U_LIB.S9S_MB_2U(SCH_1):P5E_CPU1_PE4_TX_DN'<1>:
 C_SIGNAL='@s9s_mb_2u_lib.s9s_mb_2u(sch_1):p5e_cpu1_pe4_tx_dn(1)';
NODE_NAME     U1 P85
 '@S9S_MB_2U_LIB.S9S_MB_2U(SCH_1):PAGE62_I18@PURE_QUANTA.SOCKET4677_AZIF0045P001C01CS(CHIPS)':
 'PE4_TX_DN1': CDS_PINID='PE4_TX_DN1';
NODE_NAME     C706 2
 '@S9S_MB_2U_LIB.S9S_MB_2U(SCH_1):PAGE168_I127@PURE_QUANTA.Q_CAP_DIFFBUS(CHIPS)':
 '2': CDS_PINID='\2\';
NET_NAME
'P5E_CPU1_PE4_TX_DN<2>'
 '@S9S_MB_2U_LIB.S9S_MB_2U(SCH_1):P5E_CPU1_PE4_TX_DN'<2>:
 C_SIGNAL='@s9s_mb_2u_lib.s9s_mb_2u(sch_1):p5e_cpu1_pe4_tx_dn(2)';
NODE_NAME     U1 R86
 '@S9S_MB_2U_LIB.S9S_MB_2U(SCH_1):PAGE62_I18@PURE_QUANTA.SOCKET4677_AZIF0045P001C01CS(CHIPS)':
 'PE4_TX_DN2': CDS_PINID='PE4_TX_DN2';
NODE_NAME     C704 2
 '@S9S_MB_2U_LIB.S9S_MB_2U(SCH_1):PAGE168_I129@PURE_QUANTA.Q_CAP_DIFFBUS(CHIPS)':
 '2': CDS_PINID='\2\';
NET_NAME
'P5E_CPU1_PE4_TX_DN<3>'
 '@S9S_MB_2U_LIB.S9S_MB_2U(SCH_1):P5E_CPU1_PE4_TX_DN'<3>:
 C_SIGNAL='@s9s_mb_2u_lib.s9s_mb_2u(sch_1):p5e_cpu1_pe4_tx_dn(3)';
NODE_NAME     U1 U86
 '@S9S_MB_2U_LIB.S9S_MB_2U(SCH_1):PAGE62_I18@PURE_QUANTA.SOCKET4677_AZIF0045P001C01CS(CHIPS)':
 'PE4_TX_DN3': CDS_PINID='PE4_TX_DN3';
NODE_NAME     C702 2
 '@S9S_MB_2U_LIB.S9S_MB_2U(SCH_1):PAGE168_I132@PURE_QUANTA.Q_CAP_DIFFBUS(CHIPS)':
 '2': CDS_PINID='\2\';
NET_NAME
'P5E_CPU1_PE4_TX_DN<4>'
 '@S9S_MB_2U_LIB.S9S_MB_2U(SCH_1):P5E_CPU1_PE4_TX_DN'<4>:
 C_SIGNAL='@s9s_mb_2u_lib.s9s_mb_2u(sch_1):p5e_cpu1_pe4_tx_dn(4)';
NODE_NAME     U1 W86
 '@S9S_MB_2U_LIB.S9S_MB_2U(SCH_1):PAGE62_I18@PURE_QUANTA.SOCKET4677_AZIF0045P001C01CS(CHIPS)':
 'PE4_TX_DN4': CDS_PINID='PE4_TX_DN4';
NODE_NAME     C700 2
 '@S9S_MB_2U_LIB.S9S_MB_2U(SCH_1):PAGE168_I134@PURE_QUANTA.Q_CAP_DIFFBUS(CHIPS)':
 '2': CDS_PINID='\2\';
NET_NAME
'P5E_CPU1_PE4_TX_DN<5>'
 '@S9S_MB_2U_LIB.S9S_MB_2U(SCH_1):P5E_CPU1_PE4_TX_DN'<5>:
 C_SIGNAL='@s9s_mb_2u_lib.s9s_mb_2u(sch_1):p5e_cpu1_pe4_tx_dn(5)';
NODE_NAME     U1 AA86
 '@S9S_MB_2U_LIB.S9S_MB_2U(SCH_1):PAGE62_I18@PURE_QUANTA.SOCKET4677_AZIF0045P001C01CS(CHIPS)':
 'PE4_TX_DN5': CDS_PINID='PE4_TX_DN5';
NODE_NAME     C698 2
 '@S9S_MB_2U_LIB.S9S_MB_2U(SCH_1):PAGE168_I135@PURE_QUANTA.Q_CAP_DIFFBUS(CHIPS)':
 '2': CDS_PINID='\2\';
NET_NAME
'P5E_CPU1_PE4_TX_DN<6>'
 '@S9S_MB_2U_LIB.S9S_MB_2U(SCH_1):P5E_CPU1_PE4_TX_DN'<6>:
 C_SIGNAL='@s9s_mb_2u_lib.s9s_mb_2u(sch_1):p5e_cpu1_pe4_tx_dn(6)';
NODE_NAME     U1 AC86
 '@S9S_MB_2U_LIB.S9S_MB_2U(SCH_1):PAGE62_I18@PURE_QUANTA.SOCKET4677_AZIF0045P001C01CS(CHIPS)':
 'PE4_TX_DN6': CDS_PINID='PE4_TX_DN6';
NODE_NAME     C696 2
 '@S9S_MB_2U_LIB.S9S_MB_2U(SCH_1):PAGE168_I137@PURE_QUANTA.Q_CAP_DIFFBUS(CHIPS)':
 '2': CDS_PINID='\2\';
NET_NAME
'P5E_CPU1_PE4_TX_DN<7>'
 '@S9S_MB_2U_LIB.S9S_MB_2U(SCH_1):P5E_CPU1_PE4_TX_DN'<7>:
 C_SIGNAL='@s9s_mb_2u_lib.s9s_mb_2u(sch_1):p5e_cpu1_pe4_tx_dn(7)';
NODE_NAME     U1 AE86
 '@S9S_MB_2U_LIB.S9S_MB_2U(SCH_1):PAGE62_I18@PURE_QUANTA.SOCKET4677_AZIF0045P001C01CS(CHIPS)':
 'PE4_TX_DN7': CDS_PINID='PE4_TX_DN7';
NODE_NAME     C694 2
 '@S9S_MB_2U_LIB.S9S_MB_2U(SCH_1):PAGE168_I140@PURE_QUANTA.Q_CAP_DIFFBUS(CHIPS)':
 '2': CDS_PINID='\2\';
NET_NAME
'P5E_CPU1_PE4_TX_DN<8>'
 '@S9S_MB_2U_LIB.S9S_MB_2U(SCH_1):P5E_CPU1_PE4_TX_DN'<8>:
 C_SIGNAL='@s9s_mb_2u_lib.s9s_mb_2u(sch_1):p5e_cpu1_pe4_tx_dn(8)';
NODE_NAME     U1 AG86
 '@S9S_MB_2U_LIB.S9S_MB_2U(SCH_1):PAGE62_I18@PURE_QUANTA.SOCKET4677_AZIF0045P001C01CS(CHIPS)':
 'PE4_TX_DN8': CDS_PINID='PE4_TX_DN8';
NODE_NAME     C692 2
 '@S9S_MB_2U_LIB.S9S_MB_2U(SCH_1):PAGE168_I158@PURE_QUANTA.Q_CAP_DIFFBUS(CHIPS)':
 '2': CDS_PINID='\2\';
NET_NAME
'P5E_CPU1_PE4_TX_DN<9>'
 '@S9S_MB_2U_LIB.S9S_MB_2U(SCH_1):P5E_CPU1_PE4_TX_DN'<9>:
 C_SIGNAL='@s9s_mb_2u_lib.s9s_mb_2u(sch_1):p5e_cpu1_pe4_tx_dn(9)';
NODE_NAME     U1 AJ86
 '@S9S_MB_2U_LIB.S9S_MB_2U(SCH_1):PAGE62_I18@PURE_QUANTA.SOCKET4677_AZIF0045P001C01CS(CHIPS)':
 'PE4_TX_DN9': CDS_PINID='PE4_TX_DN9';
NODE_NAME     C690 2
 '@S9S_MB_2U_LIB.S9S_MB_2U(SCH_1):PAGE168_I159@PURE_QUANTA.Q_CAP_DIFFBUS(CHIPS)':
 '2': CDS_PINID='\2\';
NET_NAME
'P5E_CPU1_PE4_TX_DP<0>'
 '@S9S_MB_2U_LIB.S9S_MB_2U(SCH_1):P5E_CPU1_PE4_TX_DP'<0>:
 C_SIGNAL='@s9s_mb_2u_lib.s9s_mb_2u(sch_1):p5e_cpu1_pe4_tx_dp(0)';
NODE_NAME     U1 M87
 '@S9S_MB_2U_LIB.S9S_MB_2U(SCH_1):PAGE62_I18@PURE_QUANTA.SOCKET4677_AZIF0045P001C01CS(CHIPS)':
 'PE4_TX_DP0': CDS_PINID='PE4_TX_DP0';
NODE_NAME     C709 2
 '@S9S_MB_2U_LIB.S9S_MB_2U(SCH_1):PAGE168_I126@PURE_QUANTA.Q_CAP_DIFFBUS(CHIPS)':
 '2': CDS_PINID='\2\';
NET_NAME
'P5E_CPU1_PE4_TX_DP<10>'
 '@S9S_MB_2U_LIB.S9S_MB_2U(SCH_1):P5E_CPU1_PE4_TX_DP'<10>:
 C_SIGNAL='@s9s_mb_2u_lib.s9s_mb_2u(sch_1):p5e_cpu1_pe4_tx_dp(10)';
NODE_NAME     U1 AM87
 '@S9S_MB_2U_LIB.S9S_MB_2U(SCH_1):PAGE62_I18@PURE_QUANTA.SOCKET4677_AZIF0045P001C01CS(CHIPS)':
 'PE4_TX_DP10': CDS_PINID='PE4_TX_DP10';
NODE_NAME     C689 2
 '@S9S_MB_2U_LIB.S9S_MB_2U(SCH_1):PAGE168_I163@PURE_QUANTA.Q_CAP_DIFFBUS(CHIPS)':
 '2': CDS_PINID='\2\';
NET_NAME
'P5E_CPU1_PE4_TX_DP<11>'
 '@S9S_MB_2U_LIB.S9S_MB_2U(SCH_1):P5E_CPU1_PE4_TX_DP'<11>:
 C_SIGNAL='@s9s_mb_2u_lib.s9s_mb_2u(sch_1):p5e_cpu1_pe4_tx_dp(11)';
NODE_NAME     U1 AN86
 '@S9S_MB_2U_LIB.S9S_MB_2U(SCH_1):PAGE62_I18@PURE_QUANTA.SOCKET4677_AZIF0045P001C01CS(CHIPS)':
 'PE4_TX_DP11': CDS_PINID='PE4_TX_DP11';
NODE_NAME     C687 2
 '@S9S_MB_2U_LIB.S9S_MB_2U(SCH_1):PAGE168_I161@PURE_QUANTA.Q_CAP_DIFFBUS(CHIPS)':
 '2': CDS_PINID='\2\';
NET_NAME
'P5E_CPU1_PE4_TX_DP<12>'
 '@S9S_MB_2U_LIB.S9S_MB_2U(SCH_1):P5E_CPU1_PE4_TX_DP'<12>:
 C_SIGNAL='@s9s_mb_2u_lib.s9s_mb_2u(sch_1):p5e_cpu1_pe4_tx_dp(12)';
NODE_NAME     U1 AT87
 '@S9S_MB_2U_LIB.S9S_MB_2U(SCH_1):PAGE62_I18@PURE_QUANTA.SOCKET4677_AZIF0045P001C01CS(CHIPS)':
 'PE4_TX_DP12': CDS_PINID='PE4_TX_DP12';
NODE_NAME     C685 2
 '@S9S_MB_2U_LIB.S9S_MB_2U(SCH_1):PAGE168_I165@PURE_QUANTA.Q_CAP_DIFFBUS(CHIPS)':
 '2': CDS_PINID='\2\';
NET_NAME
'P5E_CPU1_PE4_TX_DP<13>'
 '@S9S_MB_2U_LIB.S9S_MB_2U(SCH_1):P5E_CPU1_PE4_TX_DP'<13>:
 C_SIGNAL='@s9s_mb_2u_lib.s9s_mb_2u(sch_1):p5e_cpu1_pe4_tx_dp(13)';
NODE_NAME     U1 AV85
 '@S9S_MB_2U_LIB.S9S_MB_2U(SCH_1):PAGE62_I18@PURE_QUANTA.SOCKET4677_AZIF0045P001C01CS(CHIPS)':
 'PE4_TX_DP13': CDS_PINID='PE4_TX_DP13';
NODE_NAME     C683 2
 '@S9S_MB_2U_LIB.S9S_MB_2U(SCH_1):PAGE168_I168@PURE_QUANTA.Q_CAP_DIFFBUS(CHIPS)':
 '2': CDS_PINID='\2\';
NET_NAME
'P5E_CPU1_PE4_TX_DP<14>'
 '@S9S_MB_2U_LIB.S9S_MB_2U(SCH_1):P5E_CPU1_PE4_TX_DP'<14>:
 C_SIGNAL='@s9s_mb_2u_lib.s9s_mb_2u(sch_1):p5e_cpu1_pe4_tx_dp(14)';
NODE_NAME     U1 AY87
 '@S9S_MB_2U_LIB.S9S_MB_2U(SCH_1):PAGE62_I18@PURE_QUANTA.SOCKET4677_AZIF0045P001C01CS(CHIPS)':
 'PE4_TX_DP14': CDS_PINID='PE4_TX_DP14';
NODE_NAME     C681 2
 '@S9S_MB_2U_LIB.S9S_MB_2U(SCH_1):PAGE168_I171@PURE_QUANTA.Q_CAP_DIFFBUS(CHIPS)':
 '2': CDS_PINID='\2\';
NET_NAME
'P5E_CPU1_PE4_TX_DP<15>'
 '@S9S_MB_2U_LIB.S9S_MB_2U(SCH_1):P5E_CPU1_PE4_TX_DP'<15>:
 C_SIGNAL='@s9s_mb_2u_lib.s9s_mb_2u(sch_1):p5e_cpu1_pe4_tx_dp(15)';
NODE_NAME     U1 BB85
 '@S9S_MB_2U_LIB.S9S_MB_2U(SCH_1):PAGE62_I18@PURE_QUANTA.SOCKET4677_AZIF0045P001C01CS(CHIPS)':
 'PE4_TX_DP15': CDS_PINID='PE4_TX_DP15';
NODE_NAME     C679 2
 '@S9S_MB_2U_LIB.S9S_MB_2U(SCH_1):PAGE168_I169@PURE_QUANTA.Q_CAP_DIFFBUS(CHIPS)':
 '2': CDS_PINID='\2\';
NET_NAME
'P5E_CPU1_PE4_TX_DP<1>'
 '@S9S_MB_2U_LIB.S9S_MB_2U(SCH_1):P5E_CPU1_PE4_TX_DP'<1>:
 C_SIGNAL='@s9s_mb_2u_lib.s9s_mb_2u(sch_1):p5e_cpu1_pe4_tx_dp(1)';
NODE_NAME     U1 N86
 '@S9S_MB_2U_LIB.S9S_MB_2U(SCH_1):PAGE62_I18@PURE_QUANTA.SOCKET4677_AZIF0045P001C01CS(CHIPS)':
 'PE4_TX_DP1': CDS_PINID='PE4_TX_DP1';
NODE_NAME     C707 2
 '@S9S_MB_2U_LIB.S9S_MB_2U(SCH_1):PAGE168_I128@PURE_QUANTA.Q_CAP_DIFFBUS(CHIPS)':
 '2': CDS_PINID='\2\';
NET_NAME
'P5E_CPU1_PE4_TX_DP<2>'
 '@S9S_MB_2U_LIB.S9S_MB_2U(SCH_1):P5E_CPU1_PE4_TX_DP'<2>:
 C_SIGNAL='@s9s_mb_2u_lib.s9s_mb_2u(sch_1):p5e_cpu1_pe4_tx_dp(2)';
NODE_NAME     U1 T87
 '@S9S_MB_2U_LIB.S9S_MB_2U(SCH_1):PAGE62_I18@PURE_QUANTA.SOCKET4677_AZIF0045P001C01CS(CHIPS)':
 'PE4_TX_DP2': CDS_PINID='PE4_TX_DP2';
NODE_NAME     C705 2
 '@S9S_MB_2U_LIB.S9S_MB_2U(SCH_1):PAGE168_I130@PURE_QUANTA.Q_CAP_DIFFBUS(CHIPS)':
 '2': CDS_PINID='\2\';
NET_NAME
'P5E_CPU1_PE4_TX_DP<3>'
 '@S9S_MB_2U_LIB.S9S_MB_2U(SCH_1):P5E_CPU1_PE4_TX_DP'<3>:
 C_SIGNAL='@s9s_mb_2u_lib.s9s_mb_2u(sch_1):p5e_cpu1_pe4_tx_dp(3)';
NODE_NAME     U1 V85
 '@S9S_MB_2U_LIB.S9S_MB_2U(SCH_1):PAGE62_I18@PURE_QUANTA.SOCKET4677_AZIF0045P001C01CS(CHIPS)':
 'PE4_TX_DP3': CDS_PINID='PE4_TX_DP3';
NODE_NAME     C703 2
 '@S9S_MB_2U_LIB.S9S_MB_2U(SCH_1):PAGE168_I133@PURE_QUANTA.Q_CAP_DIFFBUS(CHIPS)':
 '2': CDS_PINID='\2\';
NET_NAME
'P5E_CPU1_PE4_TX_DP<4>'
 '@S9S_MB_2U_LIB.S9S_MB_2U(SCH_1):P5E_CPU1_PE4_TX_DP'<4>:
 C_SIGNAL='@s9s_mb_2u_lib.s9s_mb_2u(sch_1):p5e_cpu1_pe4_tx_dp(4)';
NODE_NAME     U1 Y87
 '@S9S_MB_2U_LIB.S9S_MB_2U(SCH_1):PAGE62_I18@PURE_QUANTA.SOCKET4677_AZIF0045P001C01CS(CHIPS)':
 'PE4_TX_DP4': CDS_PINID='PE4_TX_DP4';
NODE_NAME     C701 2
 '@S9S_MB_2U_LIB.S9S_MB_2U(SCH_1):PAGE168_I131@PURE_QUANTA.Q_CAP_DIFFBUS(CHIPS)':
 '2': CDS_PINID='\2\';
NET_NAME
'P5E_CPU1_PE4_TX_DP<5>'
 '@S9S_MB_2U_LIB.S9S_MB_2U(SCH_1):P5E_CPU1_PE4_TX_DP'<5>:
 C_SIGNAL='@s9s_mb_2u_lib.s9s_mb_2u(sch_1):p5e_cpu1_pe4_tx_dp(5)';
NODE_NAME     U1 AB85
 '@S9S_MB_2U_LIB.S9S_MB_2U(SCH_1):PAGE62_I18@PURE_QUANTA.SOCKET4677_AZIF0045P001C01CS(CHIPS)':
 'PE4_TX_DP5': CDS_PINID='PE4_TX_DP5';
NODE_NAME     C699 2
 '@S9S_MB_2U_LIB.S9S_MB_2U(SCH_1):PAGE168_I136@PURE_QUANTA.Q_CAP_DIFFBUS(CHIPS)':
 '2': CDS_PINID='\2\';
NET_NAME
'P5E_CPU1_PE4_TX_DP<6>'
 '@S9S_MB_2U_LIB.S9S_MB_2U(SCH_1):P5E_CPU1_PE4_TX_DP'<6>:
 C_SIGNAL='@s9s_mb_2u_lib.s9s_mb_2u(sch_1):p5e_cpu1_pe4_tx_dp(6)';
NODE_NAME     U1 AD87
 '@S9S_MB_2U_LIB.S9S_MB_2U(SCH_1):PAGE62_I18@PURE_QUANTA.SOCKET4677_AZIF0045P001C01CS(CHIPS)':
 'PE4_TX_DP6': CDS_PINID='PE4_TX_DP6';
NODE_NAME     C697 2
 '@S9S_MB_2U_LIB.S9S_MB_2U(SCH_1):PAGE168_I138@PURE_QUANTA.Q_CAP_DIFFBUS(CHIPS)':
 '2': CDS_PINID='\2\';
NET_NAME
'P5E_CPU1_PE4_TX_DP<7>'
 '@S9S_MB_2U_LIB.S9S_MB_2U(SCH_1):P5E_CPU1_PE4_TX_DP'<7>:
 C_SIGNAL='@s9s_mb_2u_lib.s9s_mb_2u(sch_1):p5e_cpu1_pe4_tx_dp(7)';
NODE_NAME     U1 AF85
 '@S9S_MB_2U_LIB.S9S_MB_2U(SCH_1):PAGE62_I18@PURE_QUANTA.SOCKET4677_AZIF0045P001C01CS(CHIPS)':
 'PE4_TX_DP7': CDS_PINID='PE4_TX_DP7';
NODE_NAME     C695 2
 '@S9S_MB_2U_LIB.S9S_MB_2U(SCH_1):PAGE168_I139@PURE_QUANTA.Q_CAP_DIFFBUS(CHIPS)':
 '2': CDS_PINID='\2\';
NET_NAME
'P5E_CPU1_PE4_TX_DP<8>'
 '@S9S_MB_2U_LIB.S9S_MB_2U(SCH_1):P5E_CPU1_PE4_TX_DP'<8>:
 C_SIGNAL='@s9s_mb_2u_lib.s9s_mb_2u(sch_1):p5e_cpu1_pe4_tx_dp(8)';
NODE_NAME     U1 AH87
 '@S9S_MB_2U_LIB.S9S_MB_2U(SCH_1):PAGE62_I18@PURE_QUANTA.SOCKET4677_AZIF0045P001C01CS(CHIPS)':
 'PE4_TX_DP8': CDS_PINID='PE4_TX_DP8';
NODE_NAME     C693 2
 '@S9S_MB_2U_LIB.S9S_MB_2U(SCH_1):PAGE168_I157@PURE_QUANTA.Q_CAP_DIFFBUS(CHIPS)':
 '2': CDS_PINID='\2\';
NET_NAME
'P5E_CPU1_PE4_TX_DP<9>'
 '@S9S_MB_2U_LIB.S9S_MB_2U(SCH_1):P5E_CPU1_PE4_TX_DP'<9>:
 C_SIGNAL='@s9s_mb_2u_lib.s9s_mb_2u(sch_1):p5e_cpu1_pe4_tx_dp(9)';
NODE_NAME     U1 AK85
 '@S9S_MB_2U_LIB.S9S_MB_2U(SCH_1):PAGE62_I18@PURE_QUANTA.SOCKET4677_AZIF0045P001C01CS(CHIPS)':
 'PE4_TX_DP9': CDS_PINID='PE4_TX_DP9';
NODE_NAME     C691 2
 '@S9S_MB_2U_LIB.S9S_MB_2U(SCH_1):PAGE168_I160@PURE_QUANTA.Q_CAP_DIFFBUS(CHIPS)':
 '2': CDS_PINID='\2\';
NET_NAME
'P5V'
 '@S9S_MB_2U_LIB.S9S_MB_2U(SCH_1):P5V':
 C_SIGNAL='@s9s_mb_2u_lib.s9s_mb_2u(sch_1):p5v',
 CDS_GLOBAL_NET='TRUE';
NODE_NAME     R3102 2
 '@S9S_MB_2U_LIB.S9S_MB_2U(SCH_1):PAGE242_I61@PURE_QUANTA.Q_RES(CHIPS)':
 'B': CDS_PINID='B';
NODE_NAME     R3005 1
 '@S9S_MB_2U_LIB.S9S_MB_2U(SCH_1):PAGE239_I168@PURE_QUANTA.Q_RES(CHIPS)':
 'A': CDS_PINID='A';
NODE_NAME     C1172 1
 '@S9S_MB_2U_LIB.S9S_MB_2U(SCH_1):PAGE246_I2@PURE_QUANTA.Q_CAP(CHIPS)':
 'A': CDS_PINID='A';
NODE_NAME     U99 3
 '@S9S_MB_2U_LIB.S9S_MB_2U(SCH_1):PAGE246_I4@PURE_QUANTA.RT9818C44GV(CHIPS)':
 'VDD': CDS_PINID='VDD';
NODE_NAME     Q57 1
 '@S9S_MB_2U_LIB.S9S_MB_2U(SCH_1):PAGE246_I30@PURE_QUANTA.MOSFET_NCH_1D3S(CHIPS)':
 '1': CDS_PINID='\1\';
NODE_NAME     Q57 2
 '@S9S_MB_2U_LIB.S9S_MB_2U(SCH_1):PAGE246_I30@PURE_QUANTA.MOSFET_NCH_1D3S(CHIPS)':
 '2': CDS_PINID='\2\';
NODE_NAME     Q57 3
 '@S9S_MB_2U_LIB.S9S_MB_2U(SCH_1):PAGE246_I30@PURE_QUANTA.MOSFET_NCH_1D3S(CHIPS)':
 '3': CDS_PINID='\3\';
NODE_NAME     D7 3
 '@S9S_MB_2U_LIB.S9S_MB_2U(SCH_1):PAGE246_I32@PURE_QUANTA.BAT547F(CHIPS)':
 '3': CDS_PINID='\3\';
NODE_NAME     C1227 1
 '@S9S_MB_2U_LIB.S9S_MB_2U(SCH_1):PAGE246_I44@PURE_QUANTA.Q_CAP(CHIPS)':
 'A': CDS_PINID='A';
NODE_NAME     C1331 1
 '@S9S_MB_2U_LIB.S9S_MB_2U(SCH_1):PAGE246_I45@PURE_QUANTA.Q_CAP(CHIPS)':
 'A': CDS_PINID='A';
NODE_NAME     PR678 1
 '@S9S_MB_2U_LIB.S9S_MB_2U(SCH_1):PAGE280_I4@PURE_QUANTA.Q_RES(CHIPS)':
 'A': CDS_PINID='A';
NODE_NAME     PR402 1
 '@S9S_MB_2U_LIB.S9S_MB_2U(SCH_1):PAGE253_I26@PURE_QUANTA.Q_RES(CHIPS)':
 'A': CDS_PINID='A';
NODE_NAME     PR442 1
 '@S9S_MB_2U_LIB.S9S_MB_2U(SCH_1):PAGE262_I8@PURE_QUANTA.Q_RES(CHIPS)':
 'A': CDS_PINID='A';
NODE_NAME     PR701 1
 '@S9S_MB_2U_LIB.S9S_MB_2U(SCH_1):PAGE275_I32@PURE_QUANTA.Q_RES(CHIPS)':
 'A': CDS_PINID='A';
NODE_NAME     PR702 1
 '@S9S_MB_2U_LIB.S9S_MB_2U(SCH_1):PAGE275_I13@PURE_QUANTA.Q_RES(CHIPS)':
 'A': CDS_PINID='A';
NODE_NAME     PR447 1
 '@S9S_MB_2U_LIB.S9S_MB_2U(SCH_1):PAGE257_I4@PURE_QUANTA.Q_RES(CHIPS)':
 'A': CDS_PINID='A';
NODE_NAME     PR444 1
 '@S9S_MB_2U_LIB.S9S_MB_2U(SCH_1):PAGE257_I9@PURE_QUANTA.Q_RES(CHIPS)':
 'A': CDS_PINID='A';
NODE_NAME     PR639 1
 '@S9S_MB_2U_LIB.S9S_MB_2U(SCH_1):PAGE271_I26@PURE_QUANTA.Q_RES(CHIPS)':
 'A': CDS_PINID='A';
NODE_NAME     R4638 1
 '@S9S_MB_2U_LIB.S9S_MB_2U(SCH_1):PAGE246_I77@PURE_QUANTA.Q_RES(CHIPS)':
 'A': CDS_PINID='A';
NODE_NAME     R4639 1
 '@S9S_MB_2U_LIB.S9S_MB_2U(SCH_1):PAGE246_I78@PURE_QUANTA.Q_RES(CHIPS)':
 'A': CDS_PINID='A';
NODE_NAME     R4640 1
 '@S9S_MB_2U_LIB.S9S_MB_2U(SCH_1):PAGE246_I79@PURE_QUANTA.Q_RES(CHIPS)':
 'A': CDS_PINID='A';
NODE_NAME     R4641 1
 '@S9S_MB_2U_LIB.S9S_MB_2U(SCH_1):PAGE246_I80@PURE_QUANTA.Q_RES(CHIPS)':
 'A': CDS_PINID='A';
NODE_NAME     R4679 1
 '@S9S_MB_2U_LIB.S9S_MB_2U(SCH_1):PAGE246_I96@PURE_QUANTA.Q_RES(CHIPS)':
 'A': CDS_PINID='A';
NET_NAME
'P5V_ADC'
 '@S9S_MB_2U_LIB.S9S_MB_2U(SCH_1):P5V_ADC':
 C_SIGNAL='@s9s_mb_2u_lib.s9s_mb_2u(sch_1):p5v_adc';
NODE_NAME     R1791 1
 '@S9S_MB_2U_LIB.S9S_MB_2U(SCH_1):PAGE239_I163@PURE_QUANTA.Q_RES(CHIPS)':
 'A': CDS_PINID='A';
NODE_NAME     R3005 2
 '@S9S_MB_2U_LIB.S9S_MB_2U(SCH_1):PAGE239_I168@PURE_QUANTA.Q_RES(CHIPS)':
 'B': CDS_PINID='B';
NODE_NAME     R3685 1
 '@S9S_MB_2U_LIB.S9S_MB_2U(SCH_1):PAGE239_I190@PURE_QUANTA.Q_RES(CHIPS)':
 'A': CDS_PINID='A';
NODE_NAME     R3686 1
 '@S9S_MB_2U_LIB.S9S_MB_2U(SCH_1):PAGE239_I191@PURE_QUANTA.Q_RES(CHIPS)':
 'A': CDS_PINID='A';
NET_NAME
'P5V_ADC_MAM'
 '@S9S_MB_2U_LIB.S9S_MB_2U(SCH_1):P5V_ADC_MAM':
 C_SIGNAL='@s9s_mb_2u_lib.s9s_mb_2u(sch_1):p5v_adc_mam';
NODE_NAME     U193 8
 '@S9S_MB_2U_LIB.S9S_MB_2U(SCH_1):PAGE239_I57@PURE_QUANTA.MAX11617EEET(CHIPS)':
 'AIN3': CDS_PINID='AIN3';
NODE_NAME     C2044 1
 '@S9S_MB_2U_LIB.S9S_MB_2U(SCH_1):PAGE239_I187@PURE_QUANTA.Q_CAP(CHIPS)':
 'A': CDS_PINID='A';
NODE_NAME     R3685 2
 '@S9S_MB_2U_LIB.S9S_MB_2U(SCH_1):PAGE239_I190@PURE_QUANTA.Q_RES(CHIPS)':
 'B': CDS_PINID='B';
NET_NAME
'P5V_ADC_TIC'
 '@S9S_MB_2U_LIB.S9S_MB_2U(SCH_1):P5V_ADC_TIC':
 C_SIGNAL='@s9s_mb_2u_lib.s9s_mb_2u(sch_1):p5v_adc_tic';
NODE_NAME     U269 13
 '@S9S_MB_2U_LIB.S9S_MB_2U(SCH_1):PAGE239_I103@PURE_QUANTA.ADC128D818CIMTXNOPB(CHIPS)':
 'IN3': CDS_PINID='IN3';
NODE_NAME     C2049 1
 '@S9S_MB_2U_LIB.S9S_MB_2U(SCH_1):PAGE239_I188@PURE_QUANTA.Q_CAP(CHIPS)':
 'A': CDS_PINID='A';
NODE_NAME     R3686 2
 '@S9S_MB_2U_LIB.S9S_MB_2U(SCH_1):PAGE239_I191@PURE_QUANTA.Q_RES(CHIPS)':
 'B': CDS_PINID='B';
NET_NAME
'P5V_AUX'
 '@S9S_MB_2U_LIB.S9S_MB_2U(SCH_1):P5V_AUX':
 C_SIGNAL='@s9s_mb_2u_lib.s9s_mb_2u(sch_1):p5v_aux',
 CDS_GLOBAL_NET='TRUE';
NODE_NAME     PC1856 1
 '@S9S_MB_2U_LIB.S9S_MB_2U(SCH_1):PAGE244_I34@PURE_QUANTA.Q_CAP(CHIPS)':
 'A': CDS_PINID='A';
NODE_NAME     R3101 2
 '@S9S_MB_2U_LIB.S9S_MB_2U(SCH_1):PAGE242_I62@PURE_QUANTA.Q_RES(CHIPS)':
 'B': CDS_PINID='B';
NODE_NAME     PL65 2
 '@S9S_MB_2U_LIB.S9S_MB_2U(SCH_1):PAGE244_I30@PURE_QUANTA.Q_INDUCTOR(CHIPS)':
 '2': CDS_PINID='\2\';
NODE_NAME     C1042 1
 '@S9S_MB_2U_LIB.S9S_MB_2U(SCH_1):PAGE246_I11@PURE_QUANTA.Q_CAP(CHIPS)':
 'A': CDS_PINID='A';
NODE_NAME     C1170 1
 '@S9S_MB_2U_LIB.S9S_MB_2U(SCH_1):PAGE246_I24@PURE_QUANTA.Q_CAP(CHIPS)':
 'A': CDS_PINID='A';
NODE_NAME     C1171 1
 '@S9S_MB_2U_LIB.S9S_MB_2U(SCH_1):PAGE246_I25@PURE_QUANTA.Q_CAP(CHIPS)':
 'A': CDS_PINID='A';
NODE_NAME     Q57 5
 '@S9S_MB_2U_LIB.S9S_MB_2U(SCH_1):PAGE246_I30@PURE_QUANTA.MOSFET_NCH_1D3S(CHIPS)':
 '5': CDS_PINID='\5\';
NODE_NAME     PC1877 2
 '@S9S_MB_2U_LIB.S9S_MB_2U(SCH_1):PAGE244_I22@PURE_QUANTA.Q_CAP(CHIPS)':
 'B': CDS_PINID='B';
NODE_NAME     PC1845 1
 '@S9S_MB_2U_LIB.S9S_MB_2U(SCH_1):PAGE244_I32@PURE_QUANTA.Q_CAPP(CHIPS)':
 'A': CDS_PINID='A';
NODE_NAME     PC1855 1
 '@S9S_MB_2U_LIB.S9S_MB_2U(SCH_1):PAGE244_I33@PURE_QUANTA.Q_CAP(CHIPS)':
 'A': CDS_PINID='A';
NODE_NAME     PC1852 1
 '@S9S_MB_2U_LIB.S9S_MB_2U(SCH_1):PAGE244_I36@PURE_QUANTA.Q_CAP(CHIPS)':
 'A': CDS_PINID='A';
NODE_NAME     PR396 1
 '@S9S_MB_2U_LIB.S9S_MB_2U(SCH_1):PAGE249_I2@PURE_QUANTA.Q_RES(CHIPS)':
 'A': CDS_PINID='A';
NODE_NAME     PR92 2
 '@S9S_MB_2U_LIB.S9S_MB_2U(SCH_1):PAGE244_I39@PURE_QUANTA.Q_RES(CHIPS)':
 'B': CDS_PINID='B';
NET_NAME
'P5V_AUX_CS'
 '@S9S_MB_2U_LIB.S9S_MB_2U(SCH_1):P5V_AUX_CS':
 C_SIGNAL='@s9s_mb_2u_lib.s9s_mb_2u(sch_1):p5v_aux_cs';
NODE_NAME     PR89 1
 '@S9S_MB_2U_LIB.S9S_MB_2U(SCH_1):PAGE244_I16@PURE_QUANTA.Q_RES(CHIPS)':
 'A': CDS_PINID='A';
NODE_NAME     PU181 3
 '@S9S_MB_2U_LIB.S9S_MB_2U(SCH_1):PAGE244_I20@PURE_QUANTA.RS53318LR(CHIPS)':
 'CS': CDS_PINID='CS';
NET_NAME
'P5V_AUX_FB'
 '@S9S_MB_2U_LIB.S9S_MB_2U(SCH_1):P5V_AUX_FB':
 C_SIGNAL='@s9s_mb_2u_lib.s9s_mb_2u(sch_1):p5v_aux_fb';
NODE_NAME     PR91 1
 '@S9S_MB_2U_LIB.S9S_MB_2U(SCH_1):PAGE244_I25@PURE_QUANTA.Q_RES(CHIPS)':
 'A': CDS_PINID='A';
NODE_NAME     PU181 7
 '@S9S_MB_2U_LIB.S9S_MB_2U(SCH_1):PAGE244_I20@PURE_QUANTA.RS53318LR(CHIPS)':
 'FB': CDS_PINID='FB';
NODE_NAME     PC1877 1
 '@S9S_MB_2U_LIB.S9S_MB_2U(SCH_1):PAGE244_I22@PURE_QUANTA.Q_CAP(CHIPS)':
 'A': CDS_PINID='A';
NODE_NAME     PR92 1
 '@S9S_MB_2U_LIB.S9S_MB_2U(SCH_1):PAGE244_I39@PURE_QUANTA.Q_RES(CHIPS)':
 'A': CDS_PINID='A';
NET_NAME
'P5V_AUX_MODE'
 '@S9S_MB_2U_LIB.S9S_MB_2U(SCH_1):P5V_AUX_MODE':
 C_SIGNAL='@s9s_mb_2u_lib.s9s_mb_2u(sch_1):p5v_aux_mode';
NODE_NAME     PR3337 1
 '@S9S_MB_2U_LIB.S9S_MB_2U(SCH_1):PAGE244_I10@PURE_QUANTA.Q_RES(CHIPS)':
 'A': CDS_PINID='A';
NODE_NAME     PU181 4
 '@S9S_MB_2U_LIB.S9S_MB_2U(SCH_1):PAGE244_I20@PURE_QUANTA.RS53318LR(CHIPS)':
 'MODE': CDS_PINID='MODE';
NET_NAME
'P5V_AUX_REF'
 '@S9S_MB_2U_LIB.S9S_MB_2U(SCH_1):P5V_AUX_REF':
 C_SIGNAL='@s9s_mb_2u_lib.s9s_mb_2u(sch_1):p5v_aux_ref';
NODE_NAME     PU181 5
 '@S9S_MB_2U_LIB.S9S_MB_2U(SCH_1):PAGE244_I20@PURE_QUANTA.RS53318LR(CHIPS)':
 'REF': CDS_PINID='REF';
NODE_NAME     PC1853 1
 '@S9S_MB_2U_LIB.S9S_MB_2U(SCH_1):PAGE244_I21@PURE_QUANTA.Q_CAP(CHIPS)':
 'A': CDS_PINID='A';
NET_NAME
'P5V_AUX_VCC'
 '@S9S_MB_2U_LIB.S9S_MB_2U(SCH_1):P5V_AUX_VCC':
 C_SIGNAL='@s9s_mb_2u_lib.s9s_mb_2u(sch_1):p5v_aux_vcc',
 CDS_GLOBAL_NET='TRUE';
NODE_NAME     R2356 1
 '@S9S_MB_2U_LIB.S9S_MB_2U(SCH_1):PAGE244_I27@PURE_QUANTA.Q_RES(CHIPS)':
 'A': CDS_PINID='A';
NODE_NAME     R2343 1
 '@S9S_MB_2U_LIB.S9S_MB_2U(SCH_1):PAGE314_I41@PURE_QUANTA.Q_RES(CHIPS)':
 'A': CDS_PINID='A';
NODE_NAME     PC1848 1
 '@S9S_MB_2U_LIB.S9S_MB_2U(SCH_1):PAGE244_I8@PURE_QUANTA.Q_CAP(CHIPS)':
 'A': CDS_PINID='A';
NODE_NAME     PU181 19
 '@S9S_MB_2U_LIB.S9S_MB_2U(SCH_1):PAGE244_I20@PURE_QUANTA.RS53318LR(CHIPS)':
 'VCC': CDS_PINID='VCC';
NET_NAME
'PCA9543_S3M_ADDR0'
 '@S9S_MB_2U_LIB.S9S_MB_2U(SCH_1):PCA9543_S3M_ADDR0':
 C_SIGNAL='@s9s_mb_2u_lib.s9s_mb_2u(sch_1):pca9543_s3m_addr0';
NODE_NAME     R2310 2
 '@S9S_MB_2U_LIB.S9S_MB_2U(SCH_1):PAGE224_I83@PURE_QUANTA.Q_RES(CHIPS)':
 'B': CDS_PINID='B';
NODE_NAME     R2311 1
 '@S9S_MB_2U_LIB.S9S_MB_2U(SCH_1):PAGE224_I86@PURE_QUANTA.Q_RES(CHIPS)':
 'A': CDS_PINID='A';
NODE_NAME     U143 1
 '@S9S_MB_2U_LIB.S9S_MB_2U(SCH_1):PAGE224_I106@PURE_QUANTA.PCA9545APW(CHIPS)':
 'A0': CDS_PINID='A0';
NET_NAME
'PCA9543_S3M_ADDR1'
 '@S9S_MB_2U_LIB.S9S_MB_2U(SCH_1):PCA9543_S3M_ADDR1':
 C_SIGNAL='@s9s_mb_2u_lib.s9s_mb_2u(sch_1):pca9543_s3m_addr1';
NODE_NAME     R2308 2
 '@S9S_MB_2U_LIB.S9S_MB_2U(SCH_1):PAGE224_I84@PURE_QUANTA.Q_RES(CHIPS)':
 'B': CDS_PINID='B';
NODE_NAME     R2309 1
 '@S9S_MB_2U_LIB.S9S_MB_2U(SCH_1):PAGE224_I85@PURE_QUANTA.Q_RES(CHIPS)':
 'A': CDS_PINID='A';
NODE_NAME     U143 2
 '@S9S_MB_2U_LIB.S9S_MB_2U(SCH_1):PAGE224_I106@PURE_QUANTA.PCA9545APW(CHIPS)':
 'A1': CDS_PINID='A1';
NET_NAME
'PCA9543_S3M_INT0_N'
 '@S9S_MB_2U_LIB.S9S_MB_2U(SCH_1):PCA9543_S3M_INT0_N':
 C_SIGNAL='@s9s_mb_2u_lib.s9s_mb_2u(sch_1):pca9543_s3m_int0_n';
NODE_NAME     R2315 2
 '@S9S_MB_2U_LIB.S9S_MB_2U(SCH_1):PAGE224_I103@PURE_QUANTA.Q_RES(CHIPS)':
 'B': CDS_PINID='B';
NODE_NAME     U143 4
 '@S9S_MB_2U_LIB.S9S_MB_2U(SCH_1):PAGE224_I106@PURE_QUANTA.PCA9545APW(CHIPS)':
 'INT0#': CDS_PINID='\int0#\';
NET_NAME
'PCA9543_S3M_INT1_N'
 '@S9S_MB_2U_LIB.S9S_MB_2U(SCH_1):PCA9543_S3M_INT1_N':
 C_SIGNAL='@s9s_mb_2u_lib.s9s_mb_2u(sch_1):pca9543_s3m_int1_n';
NODE_NAME     U143 7
 '@S9S_MB_2U_LIB.S9S_MB_2U(SCH_1):PAGE224_I106@PURE_QUANTA.PCA9545APW(CHIPS)':
 'INT1#': CDS_PINID='\int1#\';
NODE_NAME     R3127 2
 '@S9S_MB_2U_LIB.S9S_MB_2U(SCH_1):PAGE224_I109@PURE_QUANTA.Q_RES(CHIPS)':
 'B': CDS_PINID='B';
NET_NAME
'PCA9543_S3M_INT2_N'
 '@S9S_MB_2U_LIB.S9S_MB_2U(SCH_1):PCA9543_S3M_INT2_N':
 C_SIGNAL='@s9s_mb_2u_lib.s9s_mb_2u(sch_1):pca9543_s3m_int2_n';
NODE_NAME     U143 11
 '@S9S_MB_2U_LIB.S9S_MB_2U(SCH_1):PAGE224_I106@PURE_QUANTA.PCA9545APW(CHIPS)':
 'INT2#': CDS_PINID='\int2#\';
NODE_NAME     R3130 2
 '@S9S_MB_2U_LIB.S9S_MB_2U(SCH_1):PAGE224_I110@PURE_QUANTA.Q_RES(CHIPS)':
 'B': CDS_PINID='B';
NET_NAME
'PCA9543_S3M_INT3_N'
 '@S9S_MB_2U_LIB.S9S_MB_2U(SCH_1):PCA9543_S3M_INT3_N':
 C_SIGNAL='@s9s_mb_2u_lib.s9s_mb_2u(sch_1):pca9543_s3m_int3_n';
NODE_NAME     U143 14
 '@S9S_MB_2U_LIB.S9S_MB_2U(SCH_1):PAGE224_I106@PURE_QUANTA.PCA9545APW(CHIPS)':
 'INT3#': CDS_PINID='\int3#\';
NODE_NAME     R3131 2
 '@S9S_MB_2U_LIB.S9S_MB_2U(SCH_1):PAGE224_I111@PURE_QUANTA.Q_RES(CHIPS)':
 'B': CDS_PINID='B';
NET_NAME
'PCA9545_S3M_INT_N'
 '@S9S_MB_2U_LIB.S9S_MB_2U(SCH_1):PCA9545_S3M_INT_N':
 C_SIGNAL='@s9s_mb_2u_lib.s9s_mb_2u(sch_1):pca9545_s3m_int_n';
NODE_NAME     R2312 2
 '@S9S_MB_2U_LIB.S9S_MB_2U(SCH_1):PAGE224_I101@PURE_QUANTA.Q_RES(CHIPS)':
 'B': CDS_PINID='B';
NODE_NAME     U143 17
 '@S9S_MB_2U_LIB.S9S_MB_2U(SCH_1):PAGE224_I106@PURE_QUANTA.PCA9545APW(CHIPS)':
 'INT#': CDS_PINID='\int#\';
NET_NAME
'PCA9548_PCIE0_ADDR0'
 '@S9S_MB_2U_LIB.S9S_MB_2U(SCH_1):PCA9548_PCIE0_ADDR0':
 C_SIGNAL='@s9s_mb_2u_lib.s9s_mb_2u(sch_1):pca9548_pcie0_addr0';
NODE_NAME     R3709 1
 '@S9S_MB_2U_LIB.S9S_MB_2U(SCH_1):PAGE221_I8@PURE_QUANTA.Q_RES(CHIPS)':
 'A': CDS_PINID='A';
NODE_NAME     R3708 2
 '@S9S_MB_2U_LIB.S9S_MB_2U(SCH_1):PAGE221_I10@PURE_QUANTA.Q_RES(CHIPS)':
 'B': CDS_PINID='B';
NODE_NAME     U39 1
 '@S9S_MB_2U_LIB.S9S_MB_2U(SCH_1):PAGE221_I103@PURE_QUANTA.TCA9548APWR(CHIPS)':
 'A0': CDS_PINID='A0';
NET_NAME
'PCA9548_PCIE0_ADDR1'
 '@S9S_MB_2U_LIB.S9S_MB_2U(SCH_1):PCA9548_PCIE0_ADDR1':
 C_SIGNAL='@s9s_mb_2u_lib.s9s_mb_2u(sch_1):pca9548_pcie0_addr1';
NODE_NAME     R3707 1
 '@S9S_MB_2U_LIB.S9S_MB_2U(SCH_1):PAGE221_I6@PURE_QUANTA.Q_RES(CHIPS)':
 'A': CDS_PINID='A';
NODE_NAME     R3706 2
 '@S9S_MB_2U_LIB.S9S_MB_2U(SCH_1):PAGE221_I9@PURE_QUANTA.Q_RES(CHIPS)':
 'B': CDS_PINID='B';
NODE_NAME     U39 2
 '@S9S_MB_2U_LIB.S9S_MB_2U(SCH_1):PAGE221_I103@PURE_QUANTA.TCA9548APWR(CHIPS)':
 'A1': CDS_PINID='A1';
NET_NAME
'PCA9548_PCIE0_ADDR2'
 '@S9S_MB_2U_LIB.S9S_MB_2U(SCH_1):PCA9548_PCIE0_ADDR2':
 C_SIGNAL='@s9s_mb_2u_lib.s9s_mb_2u(sch_1):pca9548_pcie0_addr2';
NODE_NAME     R3704 1
 '@S9S_MB_2U_LIB.S9S_MB_2U(SCH_1):PAGE221_I2@PURE_QUANTA.Q_RES(CHIPS)':
 'A': CDS_PINID='A';
NODE_NAME     R3703 2
 '@S9S_MB_2U_LIB.S9S_MB_2U(SCH_1):PAGE221_I3@PURE_QUANTA.Q_RES(CHIPS)':
 'B': CDS_PINID='B';
NODE_NAME     U39 21
 '@S9S_MB_2U_LIB.S9S_MB_2U(SCH_1):PAGE221_I103@PURE_QUANTA.TCA9548APWR(CHIPS)':
 'A2': CDS_PINID='A2';
NET_NAME
'PCA9548_PCIE3_ADDR0'
 '@S9S_MB_2U_LIB.S9S_MB_2U(SCH_1):PCA9548_PCIE3_ADDR0':
 C_SIGNAL='@s9s_mb_2u_lib.s9s_mb_2u(sch_1):pca9548_pcie3_addr0';
NODE_NAME     R540 2
 '@S9S_MB_2U_LIB.S9S_MB_2U(SCH_1):PAGE219_I10@PURE_QUANTA.Q_RES(CHIPS)':
 'B': CDS_PINID='B';
NODE_NAME     R587 1
 '@S9S_MB_2U_LIB.S9S_MB_2U(SCH_1):PAGE219_I8@PURE_QUANTA.Q_RES(CHIPS)':
 'A': CDS_PINID='A';
NODE_NAME     U36 1
 '@S9S_MB_2U_LIB.S9S_MB_2U(SCH_1):PAGE219_I45@PURE_QUANTA.TCA9548APWR(CHIPS)':
 'A0': CDS_PINID='A0';
NET_NAME
'PCA9548_PCIE3_ADDR1'
 '@S9S_MB_2U_LIB.S9S_MB_2U(SCH_1):PCA9548_PCIE3_ADDR1':
 C_SIGNAL='@s9s_mb_2u_lib.s9s_mb_2u(sch_1):pca9548_pcie3_addr1';
NODE_NAME     R539 1
 '@S9S_MB_2U_LIB.S9S_MB_2U(SCH_1):PAGE219_I6@PURE_QUANTA.Q_RES(CHIPS)':
 'A': CDS_PINID='A';
NODE_NAME     R538 2
 '@S9S_MB_2U_LIB.S9S_MB_2U(SCH_1):PAGE219_I9@PURE_QUANTA.Q_RES(CHIPS)':
 'B': CDS_PINID='B';
NODE_NAME     U36 2
 '@S9S_MB_2U_LIB.S9S_MB_2U(SCH_1):PAGE219_I45@PURE_QUANTA.TCA9548APWR(CHIPS)':
 'A1': CDS_PINID='A1';
NET_NAME
'PCA9548_PCIE3_ADDR2'
 '@S9S_MB_2U_LIB.S9S_MB_2U(SCH_1):PCA9548_PCIE3_ADDR2':
 C_SIGNAL='@s9s_mb_2u_lib.s9s_mb_2u(sch_1):pca9548_pcie3_addr2';
NODE_NAME     R537 1
 '@S9S_MB_2U_LIB.S9S_MB_2U(SCH_1):PAGE219_I2@PURE_QUANTA.Q_RES(CHIPS)':
 'A': CDS_PINID='A';
NODE_NAME     R536 2
 '@S9S_MB_2U_LIB.S9S_MB_2U(SCH_1):PAGE219_I3@PURE_QUANTA.Q_RES(CHIPS)':
 'B': CDS_PINID='B';
NODE_NAME     U36 21
 '@S9S_MB_2U_LIB.S9S_MB_2U(SCH_1):PAGE219_I45@PURE_QUANTA.TCA9548APWR(CHIPS)':
 'A2': CDS_PINID='A2';
NET_NAME
'PCH_PCIEUP_RCOMPN'
 '@S9S_MB_2U_LIB.S9S_MB_2U(SCH_1):PCH_PCIEUP_RCOMPN':
 C_SIGNAL='@s9s_mb_2u_lib.s9s_mb_2u(sch_1):pch_pcieup_rcompn';
NODE_NAME     R495 2
 '@S9S_MB_2U_LIB.S9S_MB_2U(SCH_1):PAGE173_I1@PURE_QUANTA.Q_RES(CHIPS)':
 'B': CDS_PINID='B';
NODE_NAME     U4 AP31
 '@S9S_MB_2U_LIB.S9S_MB_2U(SCH_1):PAGE173_I110@PURE_QUANTA.EMMITSBURG_REV0P9(CHIPS)':
 'PHY_PCIE3_RCOMPN': CDS_PINID='PHY_PCIE3_RCOMPN';
NET_NAME
'PCH_PCIEUP_RCOMPP'
 '@S9S_MB_2U_LIB.S9S_MB_2U(SCH_1):PCH_PCIEUP_RCOMPP':
 C_SIGNAL='@s9s_mb_2u_lib.s9s_mb_2u(sch_1):pch_pcieup_rcompp';
NODE_NAME     R495 1
 '@S9S_MB_2U_LIB.S9S_MB_2U(SCH_1):PAGE173_I1@PURE_QUANTA.Q_RES(CHIPS)':
 'A': CDS_PINID='A';
NODE_NAME     U4 AR29
 '@S9S_MB_2U_LIB.S9S_MB_2U(SCH_1):PAGE173_I110@PURE_QUANTA.EMMITSBURG_REV0P9(CHIPS)':
 'PHY_PCIE3_RCOMPP': CDS_PINID='PHY_PCIE3_RCOMPP';
NET_NAME
'PCIE_M2_SSD0_PRSNT_N'
 '@S9S_MB_2U_LIB.S9S_MB_2U(SCH_1):PCIE_M2_SSD0_PRSNT_N':
 C_SIGNAL='@s9s_mb_2u_lib.s9s_mb_2u(sch_1):pcie_m2_ssd0_prsnt_n';
NODE_NAME     R478 2
 '@S9S_MB_2U_LIB.S9S_MB_2U(SCH_1):PAGE182_I176@PURE_QUANTA.Q_RES(CHIPS)':
 'B': CDS_PINID='B';
NODE_NAME     J59 1
 '@S9S_MB_2U_LIB.S9S_MB_2U(SCH_1):PAGE182_I178@PURE_QUANTA.SCONN75K_APCI0155P004A(CHIPS)':
 'GND1': CDS_PINID='GND1';
NODE_NAME     U249 Y5
 '@S9S_MB_2U_LIB.S9S_MB_2U(SCH_1):PAGE312_I1@PURE_QUANTA.LCMXO3LF9400C5BG484C(CHIPS)':
 'PB10C': CDS_PINID='PB10C';
NET_NAME
'PDB_PRSNT_N'
 '@S9S_MB_2U_LIB.S9S_MB_2U(SCH_1):PDB_PRSNT_N':
 C_SIGNAL='@s9s_mb_2u_lib.s9s_mb_2u(sch_1):pdb_prsnt_n';
NODE_NAME     R3907 1
 '@S9S_MB_2U_LIB.S9S_MB_2U(SCH_1):PAGE303_I4@PURE_QUANTA.Q_RES(CHIPS)':
 'A': CDS_PINID='A';
NODE_NAME     U290 G
 '@S9S_MB_2U_LIB.S9S_MB_2U(SCH_1):PAGE303_I5@PURE_QUANTA.MOSFET_NCH_GDS_ESD_PROTECTED(CHIPS)':
 'G': CDS_PINID='G';
NODE_NAME     R3923 2
 '@S9S_MB_2U_LIB.S9S_MB_2U(SCH_1):PAGE303_I10@PURE_QUANTA.Q_RES(CHIPS)':
 'B': CDS_PINID='B';
NODE_NAME     C1797 1
 '@S9S_MB_2U_LIB.S9S_MB_2U(SCH_1):PAGE303_I3@PURE_QUANTA.Q_CAP(CHIPS)':
 'A': CDS_PINID='A';
NODE_NAME     JP4003 2
 '@S9S_MB_2U_LIB.S9S_MB_2U(SCH_1):PAGE303_I12@PURE_QUANTA.CONN3_210HP1030BR1(CHIPS)':
 '2': CDS_PINID='\2\';
NODE_NAME     J45 D3
 '@S9S_MB_2U_LIB.S9S_MB_2U(SCH_1):PAGE233_I12@PURE_QUANTA.CONN60_101062636003K02LF(CHIPS)':
 'D3': CDS_PINID='D3';
NODE_NAME     C2294 1
 '@S9S_MB_2U_LIB.S9S_MB_2U(SCH_1):PAGE233_I55@PURE_QUANTA.Q_CAP(CHIPS)':
 'A': CDS_PINID='A';
NET_NAME
'PD_74CB_A9'
 '@S9S_MB_2U_LIB.S9S_MB_2U(SCH_1):PD_74CB_A9':
 C_SIGNAL='@s9s_mb_2u_lib.s9s_mb_2u(sch_1):pd_74cb_a9';
NODE_NAME     U17 9
 '@S9S_MB_2U_LIB.S9S_MB_2U(SCH_1):PAGE134_I80@PURE_QUANTA.74CBTLV3126PW(CHIPS)':
 '3A': CDS_PINID='\3a\';
NODE_NAME     R746 1
 '@S9S_MB_2U_LIB.S9S_MB_2U(SCH_1):PAGE134_I90@PURE_QUANTA.Q_RES(CHIPS)':
 'A': CDS_PINID='A';
NET_NAME
'PD_BIOS_IMAGE_SWAP_N'
 '@S9S_MB_2U_LIB.S9S_MB_2U(SCH_1):PD_BIOS_IMAGE_SWAP_N':
 C_SIGNAL='@s9s_mb_2u_lib.s9s_mb_2u(sch_1):pd_bios_image_swap_n';
NODE_NAME     R1324 2
 '@S9S_MB_2U_LIB.S9S_MB_2U(SCH_1):PAGE189_I87@PURE_QUANTA.Q_RES(CHIPS)':
 'B': CDS_PINID='B';
NODE_NAME     J104 7
 '@S9S_MB_2U_LIB.S9S_MB_2U(SCH_1):PAGE189_I134@PURE_QUANTA.CONN14_210HP207GBR1(CHIPS)':
 '7': CDS_PINID='\7\';
NET_NAME
'PD_CHA_CPU0_DIMM1_SAA'
 '@S9S_MB_2U_LIB.S9S_MB_2U(SCH_1):PD_CHA_CPU0_DIMM1_SAA':
 C_SIGNAL='@s9s_mb_2u_lib.s9s_mb_2u(sch_1):pd_cha_cpu0_dimm1_saa';
NODE_NAME     R26 1
 '@S9S_MB_2U_LIB.S9S_MB_2U(SCH_1):PAGE82_I196@PURE_QUANTA.Q_RES(CHIPS)':
 'A': CDS_PINID='A';
NODE_NAME     J1 148
 '@S9S_MB_2U_LIB.S9S_MB_2U(SCH_1):PAGE82_I198@PURE_QUANTA.SCONN288_ADR50017P130CC(CHIPS)':
 'HSA': CDS_PINID='HSA';
NET_NAME
'PD_CHA_CPU0_DIMM2_SAA'
 '@S9S_MB_2U_LIB.S9S_MB_2U(SCH_1):PD_CHA_CPU0_DIMM2_SAA':
 C_SIGNAL='@s9s_mb_2u_lib.s9s_mb_2u(sch_1):pd_cha_cpu0_dimm2_saa';
NODE_NAME     R27 1
 '@S9S_MB_2U_LIB.S9S_MB_2U(SCH_1):PAGE83_I10@PURE_QUANTA.Q_RES(CHIPS)':
 'A': CDS_PINID='A';
NODE_NAME     J2 148
 '@S9S_MB_2U_LIB.S9S_MB_2U(SCH_1):PAGE83_I177@PURE_QUANTA.SCONN288_ADR50017P087CC(CHIPS)':
 'HSA': CDS_PINID='HSA';
NET_NAME
'PD_CHA_CPU1_DIMM1_SAA'
 '@S9S_MB_2U_LIB.S9S_MB_2U(SCH_1):PD_CHA_CPU1_DIMM1_SAA':
 C_SIGNAL='@s9s_mb_2u_lib.s9s_mb_2u(sch_1):pd_cha_cpu1_dimm1_saa';
NODE_NAME     R42 1
 '@S9S_MB_2U_LIB.S9S_MB_2U(SCH_1):PAGE98_I11@PURE_QUANTA.Q_RES(CHIPS)':
 'A': CDS_PINID='A';
NODE_NAME     J17 148
 '@S9S_MB_2U_LIB.S9S_MB_2U(SCH_1):PAGE98_I12@PURE_QUANTA.SCONN288_ADR50017P130CC(CHIPS)':
 'HSA': CDS_PINID='HSA';
NET_NAME
'PD_CHA_CPU1_DIMM2_SAA'
 '@S9S_MB_2U_LIB.S9S_MB_2U(SCH_1):PD_CHA_CPU1_DIMM2_SAA':
 C_SIGNAL='@s9s_mb_2u_lib.s9s_mb_2u(sch_1):pd_cha_cpu1_dimm2_saa';
NODE_NAME     R43 1
 '@S9S_MB_2U_LIB.S9S_MB_2U(SCH_1):PAGE99_I2@PURE_QUANTA.Q_RES(CHIPS)':
 'A': CDS_PINID='A';
NODE_NAME     J18 148
 '@S9S_MB_2U_LIB.S9S_MB_2U(SCH_1):PAGE99_I24@PURE_QUANTA.SCONN288_ADR50017P087CC(CHIPS)':
 'HSA': CDS_PINID='HSA';
NET_NAME
'PD_CHB_CPU0_DIMM1_SAA'
 '@S9S_MB_2U_LIB.S9S_MB_2U(SCH_1):PD_CHB_CPU0_DIMM1_SAA':
 C_SIGNAL='@s9s_mb_2u_lib.s9s_mb_2u(sch_1):pd_chb_cpu0_dimm1_saa';
NODE_NAME     R28 1
 '@S9S_MB_2U_LIB.S9S_MB_2U(SCH_1):PAGE84_I10@PURE_QUANTA.Q_RES(CHIPS)':
 'A': CDS_PINID='A';
NODE_NAME     J3 148
 '@S9S_MB_2U_LIB.S9S_MB_2U(SCH_1):PAGE84_I180@PURE_QUANTA.SCONN288_ADR50017P130CC(CHIPS)':
 'HSA': CDS_PINID='HSA';
NET_NAME
'PD_CHB_CPU0_DIMM2_SAA'
 '@S9S_MB_2U_LIB.S9S_MB_2U(SCH_1):PD_CHB_CPU0_DIMM2_SAA':
 C_SIGNAL='@s9s_mb_2u_lib.s9s_mb_2u(sch_1):pd_chb_cpu0_dimm2_saa';
NODE_NAME     R29 1
 '@S9S_MB_2U_LIB.S9S_MB_2U(SCH_1):PAGE85_I1@PURE_QUANTA.Q_RES(CHIPS)':
 'A': CDS_PINID='A';
NODE_NAME     J4 148
 '@S9S_MB_2U_LIB.S9S_MB_2U(SCH_1):PAGE85_I23@PURE_QUANTA.SCONN288_ADR50017P087CC(CHIPS)':
 'HSA': CDS_PINID='HSA';
NET_NAME
'PD_CHB_CPU1_DIMM1_SAA'
 '@S9S_MB_2U_LIB.S9S_MB_2U(SCH_1):PD_CHB_CPU1_DIMM1_SAA':
 C_SIGNAL='@s9s_mb_2u_lib.s9s_mb_2u(sch_1):pd_chb_cpu1_dimm1_saa';
NODE_NAME     R44 1
 '@S9S_MB_2U_LIB.S9S_MB_2U(SCH_1):PAGE100_I3@PURE_QUANTA.Q_RES(CHIPS)':
 'A': CDS_PINID='A';
NODE_NAME     J19 148
 '@S9S_MB_2U_LIB.S9S_MB_2U(SCH_1):PAGE100_I25@PURE_QUANTA.SCONN288_ADR50017P130CC(CHIPS)':
 'HSA': CDS_PINID='HSA';
NET_NAME
'PD_CHB_CPU1_DIMM2_SAA'
 '@S9S_MB_2U_LIB.S9S_MB_2U(SCH_1):PD_CHB_CPU1_DIMM2_SAA':
 C_SIGNAL='@s9s_mb_2u_lib.s9s_mb_2u(sch_1):pd_chb_cpu1_dimm2_saa';
NODE_NAME     R45 1
 '@S9S_MB_2U_LIB.S9S_MB_2U(SCH_1):PAGE101_I46@PURE_QUANTA.Q_RES(CHIPS)':
 'A': CDS_PINID='A';
NODE_NAME     J20 148
 '@S9S_MB_2U_LIB.S9S_MB_2U(SCH_1):PAGE101_I47@PURE_QUANTA.SCONN288_ADR50017P087CC(CHIPS)':
 'HSA': CDS_PINID='HSA';
NET_NAME
'PD_CHC_CPU0_DIMM1_SAA'
 '@S9S_MB_2U_LIB.S9S_MB_2U(SCH_1):PD_CHC_CPU0_DIMM1_SAA':
 C_SIGNAL='@s9s_mb_2u_lib.s9s_mb_2u(sch_1):pd_chc_cpu0_dimm1_saa';
NODE_NAME     R30 1
 '@S9S_MB_2U_LIB.S9S_MB_2U(SCH_1):PAGE86_I3@PURE_QUANTA.Q_RES(CHIPS)':
 'A': CDS_PINID='A';
NODE_NAME     J5 148
 '@S9S_MB_2U_LIB.S9S_MB_2U(SCH_1):PAGE86_I24@PURE_QUANTA.SCONN288_ADR50017P130CC(CHIPS)':
 'HSA': CDS_PINID='HSA';
NET_NAME
'PD_CHC_CPU0_DIMM2_SAA'
 '@S9S_MB_2U_LIB.S9S_MB_2U(SCH_1):PD_CHC_CPU0_DIMM2_SAA':
 C_SIGNAL='@s9s_mb_2u_lib.s9s_mb_2u(sch_1):pd_chc_cpu0_dimm2_saa';
NODE_NAME     R31 1
 '@S9S_MB_2U_LIB.S9S_MB_2U(SCH_1):PAGE87_I45@PURE_QUANTA.Q_RES(CHIPS)':
 'A': CDS_PINID='A';
NODE_NAME     J6 148
 '@S9S_MB_2U_LIB.S9S_MB_2U(SCH_1):PAGE87_I46@PURE_QUANTA.SCONN288_ADR50017P087CC(CHIPS)':
 'HSA': CDS_PINID='HSA';
NET_NAME
'PD_CHC_CPU1_DIMM1_SAA'
 '@S9S_MB_2U_LIB.S9S_MB_2U(SCH_1):PD_CHC_CPU1_DIMM1_SAA':
 C_SIGNAL='@s9s_mb_2u_lib.s9s_mb_2u(sch_1):pd_chc_cpu1_dimm1_saa';
NODE_NAME     R46 1
 '@S9S_MB_2U_LIB.S9S_MB_2U(SCH_1):PAGE102_I2@PURE_QUANTA.Q_RES(CHIPS)':
 'A': CDS_PINID='A';
NODE_NAME     J21 148
 '@S9S_MB_2U_LIB.S9S_MB_2U(SCH_1):PAGE102_I13@PURE_QUANTA.SCONN288_ADR50017P130CC(CHIPS)':
 'HSA': CDS_PINID='HSA';
NET_NAME
'PD_CHC_CPU1_DIMM2_SAA'
 '@S9S_MB_2U_LIB.S9S_MB_2U(SCH_1):PD_CHC_CPU1_DIMM2_SAA':
 C_SIGNAL='@s9s_mb_2u_lib.s9s_mb_2u(sch_1):pd_chc_cpu1_dimm2_saa';
NODE_NAME     R47 1
 '@S9S_MB_2U_LIB.S9S_MB_2U(SCH_1):PAGE103_I2@PURE_QUANTA.Q_RES(CHIPS)':
 'A': CDS_PINID='A';
NODE_NAME     J22 148
 '@S9S_MB_2U_LIB.S9S_MB_2U(SCH_1):PAGE103_I51@PURE_QUANTA.SCONN288_ADR50017P087CC(CHIPS)':
 'HSA': CDS_PINID='HSA';
NET_NAME
'PD_CHD_CPU0_DIMM1_SAA'
 '@S9S_MB_2U_LIB.S9S_MB_2U(SCH_1):PD_CHD_CPU0_DIMM1_SAA':
 C_SIGNAL='@s9s_mb_2u_lib.s9s_mb_2u(sch_1):pd_chd_cpu0_dimm1_saa';
NODE_NAME     R32 1
 '@S9S_MB_2U_LIB.S9S_MB_2U(SCH_1):PAGE88_I2@PURE_QUANTA.Q_RES(CHIPS)':
 'A': CDS_PINID='A';
NODE_NAME     J7 148
 '@S9S_MB_2U_LIB.S9S_MB_2U(SCH_1):PAGE88_I12@PURE_QUANTA.SCONN288_ADR50017P130CC(CHIPS)':
 'HSA': CDS_PINID='HSA';
NET_NAME
'PD_CHD_CPU0_DIMM2_SAA'
 '@S9S_MB_2U_LIB.S9S_MB_2U(SCH_1):PD_CHD_CPU0_DIMM2_SAA':
 C_SIGNAL='@s9s_mb_2u_lib.s9s_mb_2u(sch_1):pd_chd_cpu0_dimm2_saa';
NODE_NAME     R33 1
 '@S9S_MB_2U_LIB.S9S_MB_2U(SCH_1):PAGE89_I2@PURE_QUANTA.Q_RES(CHIPS)':
 'A': CDS_PINID='A';
NODE_NAME     J8 148
 '@S9S_MB_2U_LIB.S9S_MB_2U(SCH_1):PAGE89_I50@PURE_QUANTA.SCONN288_ADR50017P087CC(CHIPS)':
 'HSA': CDS_PINID='HSA';
NET_NAME
'PD_CHD_CPU1_DIMM1_SAA'
 '@S9S_MB_2U_LIB.S9S_MB_2U(SCH_1):PD_CHD_CPU1_DIMM1_SAA':
 C_SIGNAL='@s9s_mb_2u_lib.s9s_mb_2u(sch_1):pd_chd_cpu1_dimm1_saa';
NODE_NAME     R48 1
 '@S9S_MB_2U_LIB.S9S_MB_2U(SCH_1):PAGE104_I2@PURE_QUANTA.Q_RES(CHIPS)':
 'A': CDS_PINID='A';
NODE_NAME     J23 148
 '@S9S_MB_2U_LIB.S9S_MB_2U(SCH_1):PAGE104_I25@PURE_QUANTA.SCONN288_ADR50017P130CC(CHIPS)':
 'HSA': CDS_PINID='HSA';
NET_NAME
'PD_CHD_CPU1_DIMM2_SAA'
 '@S9S_MB_2U_LIB.S9S_MB_2U(SCH_1):PD_CHD_CPU1_DIMM2_SAA':
 C_SIGNAL='@s9s_mb_2u_lib.s9s_mb_2u(sch_1):pd_chd_cpu1_dimm2_saa';
NODE_NAME     R80 1
 '@S9S_MB_2U_LIB.S9S_MB_2U(SCH_1):PAGE105_I2@PURE_QUANTA.Q_RES(CHIPS)':
 'A': CDS_PINID='A';
NODE_NAME     J24 148
 '@S9S_MB_2U_LIB.S9S_MB_2U(SCH_1):PAGE105_I178@PURE_QUANTA.SCONN288_ADR50017P087CC(CHIPS)':
 'HSA': CDS_PINID='HSA';
NET_NAME
'PD_CHE_CPU0_DIMM1_SAA'
 '@S9S_MB_2U_LIB.S9S_MB_2U(SCH_1):PD_CHE_CPU0_DIMM1_SAA':
 C_SIGNAL='@s9s_mb_2u_lib.s9s_mb_2u(sch_1):pd_che_cpu0_dimm1_saa';
NODE_NAME     R34 1
 '@S9S_MB_2U_LIB.S9S_MB_2U(SCH_1):PAGE90_I11@PURE_QUANTA.Q_RES(CHIPS)':
 'A': CDS_PINID='A';
NODE_NAME     J9 148
 '@S9S_MB_2U_LIB.S9S_MB_2U(SCH_1):PAGE90_I12@PURE_QUANTA.SCONN288_ADR50017P130CC(CHIPS)':
 'HSA': CDS_PINID='HSA';
NET_NAME
'PD_CHE_CPU0_DIMM2_SAA'
 '@S9S_MB_2U_LIB.S9S_MB_2U(SCH_1):PD_CHE_CPU0_DIMM2_SAA':
 C_SIGNAL='@s9s_mb_2u_lib.s9s_mb_2u(sch_1):pd_che_cpu0_dimm2_saa';
NODE_NAME     R35 1
 '@S9S_MB_2U_LIB.S9S_MB_2U(SCH_1):PAGE91_I2@PURE_QUANTA.Q_RES(CHIPS)':
 'A': CDS_PINID='A';
NODE_NAME     J10 148
 '@S9S_MB_2U_LIB.S9S_MB_2U(SCH_1):PAGE91_I13@PURE_QUANTA.SCONN288_ADR50017P087CC(CHIPS)':
 'HSA': CDS_PINID='HSA';
NET_NAME
'PD_CHE_CPU1_DIMM1_SAA'
 '@S9S_MB_2U_LIB.S9S_MB_2U(SCH_1):PD_CHE_CPU1_DIMM1_SAA':
 C_SIGNAL='@s9s_mb_2u_lib.s9s_mb_2u(sch_1):pd_che_cpu1_dimm1_saa';
NODE_NAME     R79 1
 '@S9S_MB_2U_LIB.S9S_MB_2U(SCH_1):PAGE106_I2@PURE_QUANTA.Q_RES(CHIPS)':
 'A': CDS_PINID='A';
NODE_NAME     J25 148
 '@S9S_MB_2U_LIB.S9S_MB_2U(SCH_1):PAGE106_I180@PURE_QUANTA.SCONN288_ADR50017P130CC(CHIPS)':
 'HSA': CDS_PINID='HSA';
NET_NAME
'PD_CHE_CPU1_DIMM2_SAA'
 '@S9S_MB_2U_LIB.S9S_MB_2U(SCH_1):PD_CHE_CPU1_DIMM2_SAA':
 C_SIGNAL='@s9s_mb_2u_lib.s9s_mb_2u(sch_1):pd_che_cpu1_dimm2_saa';
NODE_NAME     R78 1
 '@S9S_MB_2U_LIB.S9S_MB_2U(SCH_1):PAGE107_I2@PURE_QUANTA.Q_RES(CHIPS)':
 'A': CDS_PINID='A';
NODE_NAME     J26 148
 '@S9S_MB_2U_LIB.S9S_MB_2U(SCH_1):PAGE107_I180@PURE_QUANTA.SCONN288_ADR50017P087CC(CHIPS)':
 'HSA': CDS_PINID='HSA';
NET_NAME
'PD_CHF_CPU0_DIMM1_SAA'
 '@S9S_MB_2U_LIB.S9S_MB_2U(SCH_1):PD_CHF_CPU0_DIMM1_SAA':
 C_SIGNAL='@s9s_mb_2u_lib.s9s_mb_2u(sch_1):pd_chf_cpu0_dimm1_saa';
NODE_NAME     R36 1
 '@S9S_MB_2U_LIB.S9S_MB_2U(SCH_1):PAGE92_I2@PURE_QUANTA.Q_RES(CHIPS)':
 'A': CDS_PINID='A';
NODE_NAME     J11 148
 '@S9S_MB_2U_LIB.S9S_MB_2U(SCH_1):PAGE92_I25@PURE_QUANTA.SCONN288_ADR50017P130CC(CHIPS)':
 'HSA': CDS_PINID='HSA';
NET_NAME
'PD_CHF_CPU0_DIMM2_SAA'
 '@S9S_MB_2U_LIB.S9S_MB_2U(SCH_1):PD_CHF_CPU0_DIMM2_SAA':
 C_SIGNAL='@s9s_mb_2u_lib.s9s_mb_2u(sch_1):pd_chf_cpu0_dimm2_saa';
NODE_NAME     R37 1
 '@S9S_MB_2U_LIB.S9S_MB_2U(SCH_1):PAGE93_I2@PURE_QUANTA.Q_RES(CHIPS)':
 'A': CDS_PINID='A';
NODE_NAME     J12 148
 '@S9S_MB_2U_LIB.S9S_MB_2U(SCH_1):PAGE93_I24@PURE_QUANTA.SCONN288_ADR50017P087CC(CHIPS)':
 'HSA': CDS_PINID='HSA';
NET_NAME
'PD_CHF_CPU1_DIMM1_SAA'
 '@S9S_MB_2U_LIB.S9S_MB_2U(SCH_1):PD_CHF_CPU1_DIMM1_SAA':
 C_SIGNAL='@s9s_mb_2u_lib.s9s_mb_2u(sch_1):pd_chf_cpu1_dimm1_saa';
NODE_NAME     R77 1
 '@S9S_MB_2U_LIB.S9S_MB_2U(SCH_1):PAGE108_I10@PURE_QUANTA.Q_RES(CHIPS)':
 'A': CDS_PINID='A';
NODE_NAME     J27 148
 '@S9S_MB_2U_LIB.S9S_MB_2U(SCH_1):PAGE108_I179@PURE_QUANTA.SCONN288_ADR50017P130CC(CHIPS)':
 'HSA': CDS_PINID='HSA';
NET_NAME
'PD_CHF_CPU1_DIMM2_SAA'
 '@S9S_MB_2U_LIB.S9S_MB_2U(SCH_1):PD_CHF_CPU1_DIMM2_SAA':
 C_SIGNAL='@s9s_mb_2u_lib.s9s_mb_2u(sch_1):pd_chf_cpu1_dimm2_saa';
NODE_NAME     R76 1
 '@S9S_MB_2U_LIB.S9S_MB_2U(SCH_1):PAGE109_I46@PURE_QUANTA.Q_RES(CHIPS)':
 'A': CDS_PINID='A';
NODE_NAME     J28 148
 '@S9S_MB_2U_LIB.S9S_MB_2U(SCH_1):PAGE109_I47@PURE_QUANTA.SCONN288_ADR50017P087CC(CHIPS)':
 'HSA': CDS_PINID='HSA';
NET_NAME
'PD_CHG_CPU0_DIMM1_SAA'
 '@S9S_MB_2U_LIB.S9S_MB_2U(SCH_1):PD_CHG_CPU0_DIMM1_SAA':
 C_SIGNAL='@s9s_mb_2u_lib.s9s_mb_2u(sch_1):pd_chg_cpu0_dimm1_saa';
NODE_NAME     R38 1
 '@S9S_MB_2U_LIB.S9S_MB_2U(SCH_1):PAGE94_I10@PURE_QUANTA.Q_RES(CHIPS)':
 'A': CDS_PINID='A';
NODE_NAME     J13 148
 '@S9S_MB_2U_LIB.S9S_MB_2U(SCH_1):PAGE94_I11@PURE_QUANTA.SCONN288_ADR50017P130CC(CHIPS)':
 'HSA': CDS_PINID='HSA';
NET_NAME
'PD_CHG_CPU0_DIMM2_SAA'
 '@S9S_MB_2U_LIB.S9S_MB_2U(SCH_1):PD_CHG_CPU0_DIMM2_SAA':
 C_SIGNAL='@s9s_mb_2u_lib.s9s_mb_2u(sch_1):pd_chg_cpu0_dimm2_saa';
NODE_NAME     R39 1
 '@S9S_MB_2U_LIB.S9S_MB_2U(SCH_1):PAGE95_I46@PURE_QUANTA.Q_RES(CHIPS)':
 'A': CDS_PINID='A';
NODE_NAME     J14 148
 '@S9S_MB_2U_LIB.S9S_MB_2U(SCH_1):PAGE95_I47@PURE_QUANTA.SCONN288_ADR50017P087CC(CHIPS)':
 'HSA': CDS_PINID='HSA';
NET_NAME
'PD_CHG_CPU1_DIMM1_SAA'
 '@S9S_MB_2U_LIB.S9S_MB_2U(SCH_1):PD_CHG_CPU1_DIMM1_SAA':
 C_SIGNAL='@s9s_mb_2u_lib.s9s_mb_2u(sch_1):pd_chg_cpu1_dimm1_saa';
NODE_NAME     R75 1
 '@S9S_MB_2U_LIB.S9S_MB_2U(SCH_1):PAGE110_I47@PURE_QUANTA.Q_RES(CHIPS)':
 'A': CDS_PINID='A';
NODE_NAME     J29 148
 '@S9S_MB_2U_LIB.S9S_MB_2U(SCH_1):PAGE110_I179@PURE_QUANTA.SCONN288_ADR50017P130CC(CHIPS)':
 'HSA': CDS_PINID='HSA';
NET_NAME
'PD_CHG_CPU1_DIMM2_SAA'
 '@S9S_MB_2U_LIB.S9S_MB_2U(SCH_1):PD_CHG_CPU1_DIMM2_SAA':
 C_SIGNAL='@s9s_mb_2u_lib.s9s_mb_2u(sch_1):pd_chg_cpu1_dimm2_saa';
NODE_NAME     R74 1
 '@S9S_MB_2U_LIB.S9S_MB_2U(SCH_1):PAGE111_I5@PURE_QUANTA.Q_RES(CHIPS)':
 'A': CDS_PINID='A';
NODE_NAME     J30 148
 '@S9S_MB_2U_LIB.S9S_MB_2U(SCH_1):PAGE111_I179@PURE_QUANTA.SCONN288_ADR50017P087CC(CHIPS)':
 'HSA': CDS_PINID='HSA';
NET_NAME
'PD_CHH_CPU0_DIMM1_SAA'
 '@S9S_MB_2U_LIB.S9S_MB_2U(SCH_1):PD_CHH_CPU0_DIMM1_SAA':
 C_SIGNAL='@s9s_mb_2u_lib.s9s_mb_2u(sch_1):pd_chh_cpu0_dimm1_saa';
NODE_NAME     R40 1
 '@S9S_MB_2U_LIB.S9S_MB_2U(SCH_1):PAGE96_I47@PURE_QUANTA.Q_RES(CHIPS)':
 'A': CDS_PINID='A';
NODE_NAME     J15 148
 '@S9S_MB_2U_LIB.S9S_MB_2U(SCH_1):PAGE96_I48@PURE_QUANTA.SCONN288_ADR50017P130CC(CHIPS)':
 'HSA': CDS_PINID='HSA';
NET_NAME
'PD_CHH_CPU0_DIMM2_SAA'
 '@S9S_MB_2U_LIB.S9S_MB_2U(SCH_1):PD_CHH_CPU0_DIMM2_SAA':
 C_SIGNAL='@s9s_mb_2u_lib.s9s_mb_2u(sch_1):pd_chh_cpu0_dimm2_saa';
NODE_NAME     R41 1
 '@S9S_MB_2U_LIB.S9S_MB_2U(SCH_1):PAGE97_I5@PURE_QUANTA.Q_RES(CHIPS)':
 'A': CDS_PINID='A';
NODE_NAME     J16 148
 '@S9S_MB_2U_LIB.S9S_MB_2U(SCH_1):PAGE97_I6@PURE_QUANTA.SCONN288_ADR50017P087CC(CHIPS)':
 'HSA': CDS_PINID='HSA';
NET_NAME
'PD_CHH_CPU1_DIMM1_SAA'
 '@S9S_MB_2U_LIB.S9S_MB_2U(SCH_1):PD_CHH_CPU1_DIMM1_SAA':
 C_SIGNAL='@s9s_mb_2u_lib.s9s_mb_2u(sch_1):pd_chh_cpu1_dimm1_saa';
NODE_NAME     R73 1
 '@S9S_MB_2U_LIB.S9S_MB_2U(SCH_1):PAGE112_I3@PURE_QUANTA.Q_RES(CHIPS)':
 'A': CDS_PINID='A';
NODE_NAME     J31 148
 '@S9S_MB_2U_LIB.S9S_MB_2U(SCH_1):PAGE112_I180@PURE_QUANTA.SCONN288_ADR50017P130CC(CHIPS)':
 'HSA': CDS_PINID='HSA';
NET_NAME
'PD_CHH_CPU1_DIMM2_SAA'
 '@S9S_MB_2U_LIB.S9S_MB_2U(SCH_1):PD_CHH_CPU1_DIMM2_SAA':
 C_SIGNAL='@s9s_mb_2u_lib.s9s_mb_2u(sch_1):pd_chh_cpu1_dimm2_saa';
NODE_NAME     R72 1
 '@S9S_MB_2U_LIB.S9S_MB_2U(SCH_1):PAGE113_I2@PURE_QUANTA.Q_RES(CHIPS)':
 'A': CDS_PINID='A';
NODE_NAME     J32 148
 '@S9S_MB_2U_LIB.S9S_MB_2U(SCH_1):PAGE113_I179@PURE_QUANTA.SCONN288_ADR50017P087CC(CHIPS)':
 'HSA': CDS_PINID='HSA';
NET_NAME
'PD_CK440_SBI_CLK'
 '@S9S_MB_2U_LIB.S9S_MB_2U(SCH_1):PD_CK440_SBI_CLK':
 C_SIGNAL='@s9s_mb_2u_lib.s9s_mb_2u(sch_1):pd_ck440_sbi_clk';
NODE_NAME     U13 A54
 '@S9S_MB_2U_LIB.S9S_MB_2U(SCH_1):PAGE197_I180@PURE_QUANTA.9SQ440NQQI8(CHIPS)':
 'SBI_CLK': CDS_PINID='SBI_CLK';
NODE_NAME     R1462 1
 '@S9S_MB_2U_LIB.S9S_MB_2U(SCH_1):PAGE197_I274@PURE_QUANTA.Q_RES(CHIPS)':
 'A': CDS_PINID='A';
NET_NAME
'PD_CK440_SBI_DATA_IN'
 '@S9S_MB_2U_LIB.S9S_MB_2U(SCH_1):PD_CK440_SBI_DATA_IN':
 C_SIGNAL='@s9s_mb_2u_lib.s9s_mb_2u(sch_1):pd_ck440_sbi_data_in';
NODE_NAME     U13 B43
 '@S9S_MB_2U_LIB.S9S_MB_2U(SCH_1):PAGE197_I180@PURE_QUANTA.9SQ440NQQI8(CHIPS)':
 'SBI_IN': CDS_PINID='SBI_IN';
NODE_NAME     R1500 1
 '@S9S_MB_2U_LIB.S9S_MB_2U(SCH_1):PAGE197_I271@PURE_QUANTA.Q_RES(CHIPS)':
 'A': CDS_PINID='A';
NET_NAME
'PD_CPU0_BIST_ENABLE'
 '@S9S_MB_2U_LIB.S9S_MB_2U(SCH_1):PD_CPU0_BIST_ENABLE':
 C_SIGNAL='@s9s_mb_2u_lib.s9s_mb_2u(sch_1):pd_cpu0_bist_enable';
NODE_NAME     U2 AT18
 '@S9S_MB_2U_LIB.S9S_MB_2U(SCH_1):PAGE13_I57@PURE_QUANTA.SOCKET4677_AZIF0045P001C01CS(CHIPS)':
 'BIST_ENABLE': CDS_PINID='BIST_ENABLE';
NODE_NAME     R4262 2
 '@S9S_MB_2U_LIB.S9S_MB_2U(SCH_1):PAGE119_I215@PURE_QUANTA.Q_RES(CHIPS)':
 'B': CDS_PINID='B';
NODE_NAME     R4263 1
 '@S9S_MB_2U_LIB.S9S_MB_2U(SCH_1):PAGE119_I216@PURE_QUANTA.Q_RES(CHIPS)':
 'A': CDS_PINID='A';
NET_NAME
'PD_CPU0_DMIMODE_OVERRIDE'
 '@S9S_MB_2U_LIB.S9S_MB_2U(SCH_1):PD_CPU0_DMIMODE_OVERRIDE':
 C_SIGNAL='@s9s_mb_2u_lib.s9s_mb_2u(sch_1):pd_cpu0_dmimode_override';
NODE_NAME     U2 AW17
 '@S9S_MB_2U_LIB.S9S_MB_2U(SCH_1):PAGE13_I57@PURE_QUANTA.SOCKET4677_AZIF0045P001C01CS(CHIPS)':
 'DMIMODE_OVERRIDE': CDS_PINID='DMIMODE_OVERRIDE';
NODE_NAME     R294 2
 '@S9S_MB_2U_LIB.S9S_MB_2U(SCH_1):PAGE119_I71@PURE_QUANTA.Q_RES(CHIPS)':
 'B': CDS_PINID='B';
NET_NAME
'PD_CPU0_ENH_MCECC_DIS'
 '@S9S_MB_2U_LIB.S9S_MB_2U(SCH_1):PD_CPU0_ENH_MCECC_DIS':
 C_SIGNAL='@s9s_mb_2u_lib.s9s_mb_2u(sch_1):pd_cpu0_enh_mcecc_dis';
NODE_NAME     U2 CH22
 '@S9S_MB_2U_LIB.S9S_MB_2U(SCH_1):PAGE14_I1@PURE_QUANTA.SOCKET4677_AZIF0045P001C01CS(CHIPS)':
 'RSVD96': CDS_PINID='RSVD96';
NODE_NAME     R295 2
 '@S9S_MB_2U_LIB.S9S_MB_2U(SCH_1):PAGE119_I72@PURE_QUANTA.Q_RES(CHIPS)':
 'B': CDS_PINID='B';
NET_NAME
'PD_CPU0_ERRS_DIR'
 '@S9S_MB_2U_LIB.S9S_MB_2U(SCH_1):PD_CPU0_ERRS_DIR':
 C_SIGNAL='@s9s_mb_2u_lib.s9s_mb_2u(sch_1):pd_cpu0_errs_dir';
NODE_NAME     R4029 1
 '@S9S_MB_2U_LIB.S9S_MB_2U(SCH_1):PAGE321_I77@PURE_QUANTA.Q_RES(CHIPS)':
 'A': CDS_PINID='A';
NODE_NAME     U301 1
 '@S9S_MB_2U_LIB.S9S_MB_2U(SCH_1):PAGE321_I91@PURE_QUANTA.GTL2014PW(CHIPS)':
 'DIR': CDS_PINID='DIR';
NET_NAME
'PD_CPU0_TXT_PLTEN'
 '@S9S_MB_2U_LIB.S9S_MB_2U(SCH_1):PD_CPU0_TXT_PLTEN':
 C_SIGNAL='@s9s_mb_2u_lib.s9s_mb_2u(sch_1):pd_cpu0_txt_plten';
NODE_NAME     U2 CT20
 '@S9S_MB_2U_LIB.S9S_MB_2U(SCH_1):PAGE13_I57@PURE_QUANTA.SOCKET4677_AZIF0045P001C01CS(CHIPS)':
 'TXT_PLTEN': CDS_PINID='TXT_PLTEN';
NODE_NAME     R292 2
 '@S9S_MB_2U_LIB.S9S_MB_2U(SCH_1):PAGE119_I196@PURE_QUANTA.Q_RES(CHIPS)':
 'B': CDS_PINID='B';
NODE_NAME     R293 1
 '@S9S_MB_2U_LIB.S9S_MB_2U(SCH_1):PAGE119_I211@PURE_QUANTA.Q_RES(CHIPS)':
 'A': CDS_PINID='A';
NET_NAME
'PD_CPU1_BIST_ENABLE'
 '@S9S_MB_2U_LIB.S9S_MB_2U(SCH_1):PD_CPU1_BIST_ENABLE':
 C_SIGNAL='@s9s_mb_2u_lib.s9s_mb_2u(sch_1):pd_cpu1_bist_enable';
NODE_NAME     U1 AT18
 '@S9S_MB_2U_LIB.S9S_MB_2U(SCH_1):PAGE44_I51@PURE_QUANTA.SOCKET4677_AZIF0045P001C01CS(CHIPS)':
 'BIST_ENABLE': CDS_PINID='BIST_ENABLE';
NODE_NAME     R4260 2
 '@S9S_MB_2U_LIB.S9S_MB_2U(SCH_1):PAGE119_I219@PURE_QUANTA.Q_RES(CHIPS)':
 'B': CDS_PINID='B';
NODE_NAME     R4261 1
 '@S9S_MB_2U_LIB.S9S_MB_2U(SCH_1):PAGE119_I220@PURE_QUANTA.Q_RES(CHIPS)':
 'A': CDS_PINID='A';
NET_NAME
'PD_CPU1_DMIMODE_OVERRIDE'
 '@S9S_MB_2U_LIB.S9S_MB_2U(SCH_1):PD_CPU1_DMIMODE_OVERRIDE':
 C_SIGNAL='@s9s_mb_2u_lib.s9s_mb_2u(sch_1):pd_cpu1_dmimode_override';
NODE_NAME     U1 AW17
 '@S9S_MB_2U_LIB.S9S_MB_2U(SCH_1):PAGE44_I51@PURE_QUANTA.SOCKET4677_AZIF0045P001C01CS(CHIPS)':
 'DMIMODE_OVERRIDE': CDS_PINID='DMIMODE_OVERRIDE';
NODE_NAME     R290 2
 '@S9S_MB_2U_LIB.S9S_MB_2U(SCH_1):PAGE119_I135@PURE_QUANTA.Q_RES(CHIPS)':
 'B': CDS_PINID='B';
NET_NAME
'PD_CPU1_ENH_MCECC_DIS'
 '@S9S_MB_2U_LIB.S9S_MB_2U(SCH_1):PD_CPU1_ENH_MCECC_DIS':
 C_SIGNAL='@s9s_mb_2u_lib.s9s_mb_2u(sch_1):pd_cpu1_enh_mcecc_dis';
NODE_NAME     U1 CH22
 '@S9S_MB_2U_LIB.S9S_MB_2U(SCH_1):PAGE45_I29@PURE_QUANTA.SOCKET4677_AZIF0045P001C01CS(CHIPS)':
 'RSVD96': CDS_PINID='RSVD96';
NODE_NAME     R291 2
 '@S9S_MB_2U_LIB.S9S_MB_2U(SCH_1):PAGE119_I116@PURE_QUANTA.Q_RES(CHIPS)':
 'B': CDS_PINID='B';
NET_NAME
'PD_CPU1_ERRS_U306_DIR'
 '@S9S_MB_2U_LIB.S9S_MB_2U(SCH_1):PD_CPU1_ERRS_U306_DIR':
 C_SIGNAL='@s9s_mb_2u_lib.s9s_mb_2u(sch_1):pd_cpu1_errs_u306_dir';
NODE_NAME     U306 1
 '@S9S_MB_2U_LIB.S9S_MB_2U(SCH_1):PAGE322_I80@PURE_QUANTA.GTL2014PW(CHIPS)':
 'DIR': CDS_PINID='DIR';
NODE_NAME     R4055 1
 '@S9S_MB_2U_LIB.S9S_MB_2U(SCH_1):PAGE322_I91@PURE_QUANTA.Q_RES(CHIPS)':
 'A': CDS_PINID='A';
NET_NAME
'PD_CPU1_PROCDIS_COD_GTL_N'
 '@S9S_MB_2U_LIB.S9S_MB_2U(SCH_1):PD_CPU1_PROCDIS_COD_GTL_N':
 C_SIGNAL='@s9s_mb_2u_lib.s9s_mb_2u(sch_1):pd_cpu1_procdis_cod_gtl_n';
NODE_NAME     U1 DA52
 '@S9S_MB_2U_LIB.S9S_MB_2U(SCH_1):PAGE44_I51@PURE_QUANTA.SOCKET4677_AZIF0045P001C01CS(CHIPS)':
 'PROCDIS_N': CDS_PINID='PROCDIS_N';
NODE_NAME     R1270 1
 '@S9S_MB_2U_LIB.S9S_MB_2U(SCH_1):PAGE44_I55@PURE_QUANTA.Q_RES(CHIPS)':
 'A': CDS_PINID='A';
NET_NAME
'PD_CPU1_TXT_PLTEN'
 '@S9S_MB_2U_LIB.S9S_MB_2U(SCH_1):PD_CPU1_TXT_PLTEN':
 C_SIGNAL='@s9s_mb_2u_lib.s9s_mb_2u(sch_1):pd_cpu1_txt_plten';
NODE_NAME     U1 CT20
 '@S9S_MB_2U_LIB.S9S_MB_2U(SCH_1):PAGE44_I51@PURE_QUANTA.SOCKET4677_AZIF0045P001C01CS(CHIPS)':
 'TXT_PLTEN': CDS_PINID='TXT_PLTEN';
NODE_NAME     R288 2
 '@S9S_MB_2U_LIB.S9S_MB_2U(SCH_1):PAGE119_I224@PURE_QUANTA.Q_RES(CHIPS)':
 'B': CDS_PINID='B';
NODE_NAME     R289 1
 '@S9S_MB_2U_LIB.S9S_MB_2U(SCH_1):PAGE119_I225@PURE_QUANTA.Q_RES(CHIPS)':
 'A': CDS_PINID='A';
NET_NAME
'PD_DB2000_SMB_SA0'
 '@S9S_MB_2U_LIB.S9S_MB_2U(SCH_1):PD_DB2000_SMB_SA0':
 C_SIGNAL='@s9s_mb_2u_lib.s9s_mb_2u(sch_1):pd_db2000_smb_sa0';
NODE_NAME     U38 B4
 '@S9S_MB_2U_LIB.S9S_MB_2U(SCH_1):PAGE195_I119@PURE_QUANTA.9QXL2001BNHGI8(CHIPS)':
 '^VSADR0_TRI': CDS_PINID='\^vsadr0_tri\';
NODE_NAME     R569 2
 '@S9S_MB_2U_LIB.S9S_MB_2U(SCH_1):PAGE195_I185@PURE_QUANTA.Q_RES(CHIPS)':
 'B': CDS_PINID='B';
NODE_NAME     R570 1
 '@S9S_MB_2U_LIB.S9S_MB_2U(SCH_1):PAGE195_I187@PURE_QUANTA.Q_RES(CHIPS)':
 'A': CDS_PINID='A';
NET_NAME
'PD_DB2000_SMB_SA1'
 '@S9S_MB_2U_LIB.S9S_MB_2U(SCH_1):PD_DB2000_SMB_SA1':
 C_SIGNAL='@s9s_mb_2u_lib.s9s_mb_2u(sch_1):pd_db2000_smb_sa1';
NODE_NAME     U38 B8
 '@S9S_MB_2U_LIB.S9S_MB_2U(SCH_1):PAGE195_I119@PURE_QUANTA.9QXL2001BNHGI8(CHIPS)':
 '^VSADR1_TRI': CDS_PINID='\^vsadr1_tri\';
NODE_NAME     R568 1
 '@S9S_MB_2U_LIB.S9S_MB_2U(SCH_1):PAGE195_I178@PURE_QUANTA.Q_RES(CHIPS)':
 'A': CDS_PINID='A';
NODE_NAME     R567 2
 '@S9S_MB_2U_LIB.S9S_MB_2U(SCH_1):PAGE195_I179@PURE_QUANTA.Q_RES(CHIPS)':
 'B': CDS_PINID='B';
NET_NAME
'PD_EXT_CLK_SEL_CPU0'
 '@S9S_MB_2U_LIB.S9S_MB_2U(SCH_1):PD_EXT_CLK_SEL_CPU0':
 C_SIGNAL='@s9s_mb_2u_lib.s9s_mb_2u(sch_1):pd_ext_clk_sel_cpu0';
NODE_NAME     U2 BY24
 '@S9S_MB_2U_LIB.S9S_MB_2U(SCH_1):PAGE13_I57@PURE_QUANTA.SOCKET4677_AZIF0045P001C01CS(CHIPS)':
 'RSVD76': CDS_PINID='RSVD76';
NODE_NAME     R1237 2
 '@S9S_MB_2U_LIB.S9S_MB_2U(SCH_1):PAGE119_I160@PURE_QUANTA.Q_RES(CHIPS)':
 'B': CDS_PINID='B';
NET_NAME
'PD_EXT_CLK_SEL_CPU1'
 '@S9S_MB_2U_LIB.S9S_MB_2U(SCH_1):PD_EXT_CLK_SEL_CPU1':
 C_SIGNAL='@s9s_mb_2u_lib.s9s_mb_2u(sch_1):pd_ext_clk_sel_cpu1';
NODE_NAME     U1 BY24
 '@S9S_MB_2U_LIB.S9S_MB_2U(SCH_1):PAGE44_I51@PURE_QUANTA.SOCKET4677_AZIF0045P001C01CS(CHIPS)':
 'RSVD76': CDS_PINID='RSVD76';
NODE_NAME     R3024 2
 '@S9S_MB_2U_LIB.S9S_MB_2U(SCH_1):PAGE119_I172@PURE_QUANTA.Q_RES(CHIPS)':
 'B': CDS_PINID='B';
NET_NAME
'PD_FORCE_PWRON'
 '@S9S_MB_2U_LIB.S9S_MB_2U(SCH_1):PD_FORCE_PWRON':
 C_SIGNAL='@s9s_mb_2u_lib.s9s_mb_2u(sch_1):pd_force_pwron';
NODE_NAME     JP15 3
 '@S9S_MB_2U_LIB.S9S_MB_2U(SCH_1):PAGE312_I187@PURE_QUANTA.CONN3_210HP1030BR1(CHIPS)':
 '3': CDS_PINID='\3\';
NODE_NAME     R1495 1
 '@S9S_MB_2U_LIB.S9S_MB_2U(SCH_1):PAGE312_I190@PURE_QUANTA.Q_RES(CHIPS)':
 'A': CDS_PINID='A';
NET_NAME
'PD_GPP_I_13'
 '@S9S_MB_2U_LIB.S9S_MB_2U(SCH_1):PD_GPP_I_13':
 C_SIGNAL='@s9s_mb_2u_lib.s9s_mb_2u(sch_1):pd_gpp_i_13';
NODE_NAME     U4 N2
 '@S9S_MB_2U_LIB.S9S_MB_2U(SCH_1):PAGE176_I22@PURE_QUANTA.EMMITSBURG_REV0P9(CHIPS)':
 'GPP_I_13_HDA_RST_N': CDS_PINID='GPP_I_13_HDA_RST_N';
NODE_NAME     R4565 1
 '@S9S_MB_2U_LIB.S9S_MB_2U(SCH_1):PAGE176_I240@PURE_QUANTA.Q_RES(CHIPS)':
 'A': CDS_PINID='A';
NET_NAME
'PD_GPP_I_14'
 '@S9S_MB_2U_LIB.S9S_MB_2U(SCH_1):PD_GPP_I_14':
 C_SIGNAL='@s9s_mb_2u_lib.s9s_mb_2u(sch_1):pd_gpp_i_14';
NODE_NAME     U4 P1
 '@S9S_MB_2U_LIB.S9S_MB_2U(SCH_1):PAGE176_I22@PURE_QUANTA.EMMITSBURG_REV0P9(CHIPS)':
 'GPP_I_14_HDA_SYNC': CDS_PINID='GPP_I_14_HDA_SYNC';
NODE_NAME     R4564 1
 '@S9S_MB_2U_LIB.S9S_MB_2U(SCH_1):PAGE176_I239@PURE_QUANTA.Q_RES(CHIPS)':
 'A': CDS_PINID='A';
NET_NAME
'PD_GPP_I_15'
 '@S9S_MB_2U_LIB.S9S_MB_2U(SCH_1):PD_GPP_I_15':
 C_SIGNAL='@s9s_mb_2u_lib.s9s_mb_2u(sch_1):pd_gpp_i_15';
NODE_NAME     U4 R2
 '@S9S_MB_2U_LIB.S9S_MB_2U(SCH_1):PAGE176_I22@PURE_QUANTA.EMMITSBURG_REV0P9(CHIPS)':
 'GPP_I_15_HDA_SDO': CDS_PINID='GPP_I_15_HDA_SDO';
NODE_NAME     R4109 1
 '@S9S_MB_2U_LIB.S9S_MB_2U(SCH_1):PAGE176_I195@PURE_QUANTA.Q_RES(CHIPS)':
 'A': CDS_PINID='A';
NET_NAME
'PD_GPP_I_16'
 '@S9S_MB_2U_LIB.S9S_MB_2U(SCH_1):PD_GPP_I_16':
 C_SIGNAL='@s9s_mb_2u_lib.s9s_mb_2u(sch_1):pd_gpp_i_16';
NODE_NAME     U4 U1
 '@S9S_MB_2U_LIB.S9S_MB_2U(SCH_1):PAGE176_I22@PURE_QUANTA.EMMITSBURG_REV0P9(CHIPS)':
 'GPP_I_16_HDA_SDI_0': CDS_PINID='GPP_I_16_HDA_SDI_0';
NODE_NAME     R4108 1
 '@S9S_MB_2U_LIB.S9S_MB_2U(SCH_1):PAGE176_I196@PURE_QUANTA.Q_RES(CHIPS)':
 'A': CDS_PINID='A';
NET_NAME
'PD_GPP_I_17'
 '@S9S_MB_2U_LIB.S9S_MB_2U(SCH_1):PD_GPP_I_17':
 C_SIGNAL='@s9s_mb_2u_lib.s9s_mb_2u(sch_1):pd_gpp_i_17';
NODE_NAME     U4 V4
 '@S9S_MB_2U_LIB.S9S_MB_2U(SCH_1):PAGE176_I22@PURE_QUANTA.EMMITSBURG_REV0P9(CHIPS)':
 'GPP_I_17_HDA_SDI_1': CDS_PINID='GPP_I_17_HDA_SDI_1';
NODE_NAME     R4107 1
 '@S9S_MB_2U_LIB.S9S_MB_2U(SCH_1):PAGE176_I197@PURE_QUANTA.Q_RES(CHIPS)':
 'A': CDS_PINID='A';
NET_NAME
'PD_GPP_M_15'
 '@S9S_MB_2U_LIB.S9S_MB_2U(SCH_1):PD_GPP_M_15':
 C_SIGNAL='@s9s_mb_2u_lib.s9s_mb_2u(sch_1):pd_gpp_m_15';
NODE_NAME     U4 T8
 '@S9S_MB_2U_LIB.S9S_MB_2U(SCH_1):PAGE176_I22@PURE_QUANTA.EMMITSBURG_REV0P9(CHIPS)':
 'GPP_M_15': CDS_PINID='GPP_M_15';
NODE_NAME     R4105 1
 '@S9S_MB_2U_LIB.S9S_MB_2U(SCH_1):PAGE176_I183@PURE_QUANTA.Q_RES(CHIPS)':
 'A': CDS_PINID='A';
NET_NAME
'PD_GPP_M_16'
 '@S9S_MB_2U_LIB.S9S_MB_2U(SCH_1):PD_GPP_M_16':
 C_SIGNAL='@s9s_mb_2u_lib.s9s_mb_2u(sch_1):pd_gpp_m_16';
NODE_NAME     U4 N10
 '@S9S_MB_2U_LIB.S9S_MB_2U(SCH_1):PAGE176_I22@PURE_QUANTA.EMMITSBURG_REV0P9(CHIPS)':
 'GPP_M_16': CDS_PINID='GPP_M_16';
NODE_NAME     R4104 1
 '@S9S_MB_2U_LIB.S9S_MB_2U(SCH_1):PAGE176_I185@PURE_QUANTA.Q_RES(CHIPS)':
 'A': CDS_PINID='A';
NET_NAME
'PD_GPP_M_17'
 '@S9S_MB_2U_LIB.S9S_MB_2U(SCH_1):PD_GPP_M_17':
 C_SIGNAL='@s9s_mb_2u_lib.s9s_mb_2u(sch_1):pd_gpp_m_17';
NODE_NAME     U4 W13
 '@S9S_MB_2U_LIB.S9S_MB_2U(SCH_1):PAGE176_I22@PURE_QUANTA.EMMITSBURG_REV0P9(CHIPS)':
 'GPP_M_17': CDS_PINID='GPP_M_17';
NODE_NAME     R4103 1
 '@S9S_MB_2U_LIB.S9S_MB_2U(SCH_1):PAGE176_I186@PURE_QUANTA.Q_RES(CHIPS)':
 'A': CDS_PINID='A';
NET_NAME
'PD_GPP_M_8'
 '@S9S_MB_2U_LIB.S9S_MB_2U(SCH_1):PD_GPP_M_8':
 C_SIGNAL='@s9s_mb_2u_lib.s9s_mb_2u(sch_1):pd_gpp_m_8';
NODE_NAME     U4 W10
 '@S9S_MB_2U_LIB.S9S_MB_2U(SCH_1):PAGE176_I22@PURE_QUANTA.EMMITSBURG_REV0P9(CHIPS)':
 'GPP_M_8': CDS_PINID='GPP_M_8';
NODE_NAME     R4106 1
 '@S9S_MB_2U_LIB.S9S_MB_2U(SCH_1):PAGE176_I184@PURE_QUANTA.Q_RES(CHIPS)':
 'A': CDS_PINID='A';
NET_NAME
'PD_GTL2014_BMC_JTAG_DIR_0'
 '@S9S_MB_2U_LIB.S9S_MB_2U(SCH_1):PD_GTL2014_BMC_JTAG_DIR_0':
 C_SIGNAL='@s9s_mb_2u_lib.s9s_mb_2u(sch_1):pd_gtl2014_bmc_jtag_dir_0';
NODE_NAME     U304 1
 '@S9S_MB_2U_LIB.S9S_MB_2U(SCH_1):PAGE322_I27@PURE_QUANTA.GTL2014PW(CHIPS)':
 'DIR': CDS_PINID='DIR';
NODE_NAME     R4053 1
 '@S9S_MB_2U_LIB.S9S_MB_2U(SCH_1):PAGE322_I66@PURE_QUANTA.Q_RES(CHIPS)':
 'A': CDS_PINID='A';
NET_NAME
'PD_GTL2014_BMC_JTAG_DIR_1'
 '@S9S_MB_2U_LIB.S9S_MB_2U(SCH_1):PD_GTL2014_BMC_JTAG_DIR_1':
 C_SIGNAL='@s9s_mb_2u_lib.s9s_mb_2u(sch_1):pd_gtl2014_bmc_jtag_dir_1';
NODE_NAME     U305 1
 '@S9S_MB_2U_LIB.S9S_MB_2U(SCH_1):PAGE322_I44@PURE_QUANTA.GTL2014PW(CHIPS)':
 'DIR': CDS_PINID='DIR';
NODE_NAME     R4054 1
 '@S9S_MB_2U_LIB.S9S_MB_2U(SCH_1):PAGE322_I67@PURE_QUANTA.Q_RES(CHIPS)':
 'A': CDS_PINID='A';
NET_NAME
'PD_GTL2014_BMC_JTAG_DIR_2'
 '@S9S_MB_2U_LIB.S9S_MB_2U(SCH_1):PD_GTL2014_BMC_JTAG_DIR_2':
 C_SIGNAL='@s9s_mb_2u_lib.s9s_mb_2u(sch_1):pd_gtl2014_bmc_jtag_dir_2';
NODE_NAME     U83 1
 '@S9S_MB_2U_LIB.S9S_MB_2U(SCH_1):PAGE226_I45@PURE_QUANTA.GTL2014PW(CHIPS)':
 'DIR': CDS_PINID='DIR';
NODE_NAME     R2513 1
 '@S9S_MB_2U_LIB.S9S_MB_2U(SCH_1):PAGE226_I90@PURE_QUANTA.Q_RES(CHIPS)':
 'A': CDS_PINID='A';
NET_NAME
'PD_GTL2014_BMC_JTAG_VREF_1'
 '@S9S_MB_2U_LIB.S9S_MB_2U(SCH_1):PD_GTL2014_BMC_JTAG_VREF_1':
 C_SIGNAL='@s9s_mb_2u_lib.s9s_mb_2u(sch_1):pd_gtl2014_bmc_jtag_vref_1';
NODE_NAME     R1347 1
 '@S9S_MB_2U_LIB.S9S_MB_2U(SCH_1):PAGE226_I10@PURE_QUANTA.Q_RES(CHIPS)':
 'A': CDS_PINID='A';
NODE_NAME     U84 4
 '@S9S_MB_2U_LIB.S9S_MB_2U(SCH_1):PAGE226_I18@PURE_QUANTA.GTL2014PW(CHIPS)':
 'VREF': CDS_PINID='VREF';
NET_NAME
'PD_GTL2014_ERROR_B0'
 '@S9S_MB_2U_LIB.S9S_MB_2U(SCH_1):PD_GTL2014_ERROR_B0':
 C_SIGNAL='@s9s_mb_2u_lib.s9s_mb_2u(sch_1):pd_gtl2014_error_b0';
NODE_NAME     U306 2
 '@S9S_MB_2U_LIB.S9S_MB_2U(SCH_1):PAGE322_I80@PURE_QUANTA.GTL2014PW(CHIPS)':
 'B0': CDS_PINID='B0';
NODE_NAME     R4391 1
 '@S9S_MB_2U_LIB.S9S_MB_2U(SCH_1):PAGE322_I190@PURE_QUANTA.Q_RES(CHIPS)':
 'A': CDS_PINID='A';
NET_NAME
'PD_I3C_SPD_DDR_CPU0_OE_N'
 '@S9S_MB_2U_LIB.S9S_MB_2U(SCH_1):PD_I3C_SPD_DDR_CPU0_OE_N':
 C_SIGNAL='@s9s_mb_2u_lib.s9s_mb_2u(sch_1):pd_i3c_spd_ddr_cpu0_oe_n';
NODE_NAME     R678 1
 '@S9S_MB_2U_LIB.S9S_MB_2U(SCH_1):PAGE217_I13@PURE_QUANTA.Q_RES(CHIPS)':
 'A': CDS_PINID='A';
NODE_NAME     U15 15
 '@S9S_MB_2U_LIB.S9S_MB_2U(SCH_1):PAGE217_I19@PURE_QUANTA.QS3VH257QG8(CHIPS)':
 'E*': CDS_PINID='\e*\';
NET_NAME
'PD_I3C_SPD_DDR_CPU1_OE_N'
 '@S9S_MB_2U_LIB.S9S_MB_2U(SCH_1):PD_I3C_SPD_DDR_CPU1_OE_N':
 C_SIGNAL='@s9s_mb_2u_lib.s9s_mb_2u(sch_1):pd_i3c_spd_ddr_cpu1_oe_n';
NODE_NAME     R661 1
 '@S9S_MB_2U_LIB.S9S_MB_2U(SCH_1):PAGE218_I4@PURE_QUANTA.Q_RES(CHIPS)':
 'A': CDS_PINID='A';
NODE_NAME     U14 15
 '@S9S_MB_2U_LIB.S9S_MB_2U(SCH_1):PAGE218_I12@PURE_QUANTA.QS3VH257QG8(CHIPS)':
 'E*': CDS_PINID='\e*\';
NET_NAME
'PD_JTAG_BMC_NTRST_N'
 '@S9S_MB_2U_LIB.S9S_MB_2U(SCH_1):PD_JTAG_BMC_NTRST_N':
 C_SIGNAL='@s9s_mb_2u_lib.s9s_mb_2u(sch_1):pd_jtag_bmc_ntrst_n';
NODE_NAME     U86 1
 '@S9S_MB_2U_LIB.S9S_MB_2U(SCH_1):PAGE137_I84@PURE_QUANTA.74CBTLV3126PW(CHIPS)':
 '1OE': CDS_PINID='\1oe\';
NODE_NAME     U86 13
 '@S9S_MB_2U_LIB.S9S_MB_2U(SCH_1):PAGE137_I84@PURE_QUANTA.74CBTLV3126PW(CHIPS)':
 '4OE': CDS_PINID='\4oe\';
NODE_NAME     R1374 1
 '@S9S_MB_2U_LIB.S9S_MB_2U(SCH_1):PAGE137_I103@PURE_QUANTA.Q_RES(CHIPS)':
 'A': CDS_PINID='A';
NET_NAME
'PD_JTAG_CPU0_PLD_TCK'
 '@S9S_MB_2U_LIB.S9S_MB_2U(SCH_1):PD_JTAG_CPU0_PLD_TCK':
 C_SIGNAL='@s9s_mb_2u_lib.s9s_mb_2u(sch_1):pd_jtag_cpu0_pld_tck';
NODE_NAME     U2 CY22
 '@S9S_MB_2U_LIB.S9S_MB_2U(SCH_1):PAGE15_I1@PURE_QUANTA.SOCKET4677_AZIF0045P001C01CS(CHIPS)':
 'TEST_5': CDS_PINID='TEST_5';
NODE_NAME     R1226 1
 '@S9S_MB_2U_LIB.S9S_MB_2U(SCH_1):PAGE43_I52@PURE_QUANTA.Q_RES(CHIPS)':
 'A': CDS_PINID='A';
NET_NAME
'PD_JTAG_CPU1_PLD_TCK'
 '@S9S_MB_2U_LIB.S9S_MB_2U(SCH_1):PD_JTAG_CPU1_PLD_TCK':
 C_SIGNAL='@s9s_mb_2u_lib.s9s_mb_2u(sch_1):pd_jtag_cpu1_pld_tck';
NODE_NAME     R1227 1
 '@S9S_MB_2U_LIB.S9S_MB_2U(SCH_1):PAGE43_I56@PURE_QUANTA.Q_RES(CHIPS)':
 'A': CDS_PINID='A';
NODE_NAME     U1 CY22
 '@S9S_MB_2U_LIB.S9S_MB_2U(SCH_1):PAGE46_I5@PURE_QUANTA.SOCKET4677_AZIF0045P001C01CS(CHIPS)':
 'TEST_5': CDS_PINID='TEST_5';
NET_NAME
'PD_JTAG_DBP_B0'
 '@S9S_MB_2U_LIB.S9S_MB_2U(SCH_1):PD_JTAG_DBP_B0':
 C_SIGNAL='@s9s_mb_2u_lib.s9s_mb_2u(sch_1):pd_jtag_dbp_b0';
NODE_NAME     U83 2
 '@S9S_MB_2U_LIB.S9S_MB_2U(SCH_1):PAGE226_I45@PURE_QUANTA.GTL2014PW(CHIPS)':
 'B0': CDS_PINID='B0';
NODE_NAME     R1369 1
 '@S9S_MB_2U_LIB.S9S_MB_2U(SCH_1):PAGE226_I47@PURE_QUANTA.Q_RES(CHIPS)':
 'A': CDS_PINID='A';
NET_NAME
'PD_JTAG_DBP_B2'
 '@S9S_MB_2U_LIB.S9S_MB_2U(SCH_1):PD_JTAG_DBP_B2':
 C_SIGNAL='@s9s_mb_2u_lib.s9s_mb_2u(sch_1):pd_jtag_dbp_b2';
NODE_NAME     U83 5
 '@S9S_MB_2U_LIB.S9S_MB_2U(SCH_1):PAGE226_I45@PURE_QUANTA.GTL2014PW(CHIPS)':
 'B2': CDS_PINID='B2';
NODE_NAME     R1368 1
 '@S9S_MB_2U_LIB.S9S_MB_2U(SCH_1):PAGE226_I48@PURE_QUANTA.Q_RES(CHIPS)':
 'A': CDS_PINID='A';
NET_NAME
'PD_M2_0_DEVSLP'
 '@S9S_MB_2U_LIB.S9S_MB_2U(SCH_1):PD_M2_0_DEVSLP':
 C_SIGNAL='@s9s_mb_2u_lib.s9s_mb_2u(sch_1):pd_m2_0_devslp';
NODE_NAME     R1605 1
 '@S9S_MB_2U_LIB.S9S_MB_2U(SCH_1):PAGE182_I105@PURE_QUANTA.Q_RES(CHIPS)':
 'A': CDS_PINID='A';
NODE_NAME     J59 38
 '@S9S_MB_2U_LIB.S9S_MB_2U(SCH_1):PAGE182_I178@PURE_QUANTA.SCONN75K_APCI0155P004A(CHIPS)':
 'DEVSLP': CDS_PINID='DEVSLP';
NET_NAME
'PD_MB_FRU_WP'
 '@S9S_MB_2U_LIB.S9S_MB_2U(SCH_1):PD_MB_FRU_WP':
 C_SIGNAL='@s9s_mb_2u_lib.s9s_mb_2u(sch_1):pd_mb_fru_wp';
NODE_NAME     U64 7
 '@S9S_MB_2U_LIB.S9S_MB_2U(SCH_1):PAGE231_I35@PURE_QUANTA.M24128BWMN6TP(CHIPS)':
 'WC#': CDS_PINID='\wc#\';
NODE_NAME     R710 1
 '@S9S_MB_2U_LIB.S9S_MB_2U(SCH_1):PAGE231_I57@PURE_QUANTA.Q_RES(CHIPS)':
 'A': CDS_PINID='A';
NET_NAME
'PD_ME_RCVR_N'
 '@S9S_MB_2U_LIB.S9S_MB_2U(SCH_1):PD_ME_RCVR_N':
 C_SIGNAL='@s9s_mb_2u_lib.s9s_mb_2u(sch_1):pd_me_rcvr_n';
NODE_NAME     R3039 2
 '@S9S_MB_2U_LIB.S9S_MB_2U(SCH_1):PAGE189_I132@PURE_QUANTA.Q_RES(CHIPS)':
 'B': CDS_PINID='B';
NODE_NAME     J104 11
 '@S9S_MB_2U_LIB.S9S_MB_2U(SCH_1):PAGE189_I134@PURE_QUANTA.CONN14_210HP207GBR1(CHIPS)':
 '11': CDS_PINID='\11\';
NET_NAME
'PD_P2E_BUF2_ENSMB'
 '@S9S_MB_2U_LIB.S9S_MB_2U(SCH_1):PD_P2E_BUF2_ENSMB':
 C_SIGNAL='@s9s_mb_2u_lib.s9s_mb_2u(sch_1):pd_p2e_buf2_ensmb';
NODE_NAME     U328 3
 '@S9S_MB_2U_LIB.S9S_MB_2U(SCH_1):PAGE159_I95@PURE_QUANTA.DS125BR111RTWR(CHIPS)':
 'ENSMB': CDS_PINID='ENSMB';
NODE_NAME     R3362 1
 '@S9S_MB_2U_LIB.S9S_MB_2U(SCH_1):PAGE159_I53@PURE_QUANTA.Q_RES(CHIPS)':
 'A': CDS_PINID='A';
NET_NAME
'PD_PASSWORD_CLEAR'
 '@S9S_MB_2U_LIB.S9S_MB_2U(SCH_1):PD_PASSWORD_CLEAR':
 C_SIGNAL='@s9s_mb_2u_lib.s9s_mb_2u(sch_1):pd_password_clear';
NODE_NAME     R1335 2
 '@S9S_MB_2U_LIB.S9S_MB_2U(SCH_1):PAGE189_I133@PURE_QUANTA.Q_RES(CHIPS)':
 'B': CDS_PINID='B';
NODE_NAME     J104 13
 '@S9S_MB_2U_LIB.S9S_MB_2U(SCH_1):PAGE189_I134@PURE_QUANTA.CONN14_210HP207GBR1(CHIPS)':
 '13': CDS_PINID='\13\';
NET_NAME
'PD_PCH_GPPC_A_10'
 '@S9S_MB_2U_LIB.S9S_MB_2U(SCH_1):PD_PCH_GPPC_A_10':
 C_SIGNAL='@s9s_mb_2u_lib.s9s_mb_2u(sch_1):pd_pch_gppc_a_10';
NODE_NAME     U4 BD17
 '@S9S_MB_2U_LIB.S9S_MB_2U(SCH_1):PAGE175_I93@PURE_QUANTA.EMMITSBURG_REV0P9(CHIPS)':
 'GPPC_A_10_SRCCLKREQ_N_0': CDS_PINID='GPPC_A_10_SRCCLKREQ_N_0';
NODE_NAME     R4099 1
 '@S9S_MB_2U_LIB.S9S_MB_2U(SCH_1):PAGE175_I288@PURE_QUANTA.Q_RES(CHIPS)':
 'A': CDS_PINID='A';
NET_NAME
'PD_PCH_GPPC_A_14'
 '@S9S_MB_2U_LIB.S9S_MB_2U(SCH_1):PD_PCH_GPPC_A_14':
 C_SIGNAL='@s9s_mb_2u_lib.s9s_mb_2u(sch_1):pd_pch_gppc_a_14';
NODE_NAME     U4 BE12
 '@S9S_MB_2U_LIB.S9S_MB_2U(SCH_1):PAGE175_I93@PURE_QUANTA.EMMITSBURG_REV0P9(CHIPS)':
 'GPPC_A_14_SRCCLKREQ_N_4': CDS_PINID='GPPC_A_14_SRCCLKREQ_N_4';
NODE_NAME     R4098 1
 '@S9S_MB_2U_LIB.S9S_MB_2U(SCH_1):PAGE175_I287@PURE_QUANTA.Q_RES(CHIPS)':
 'A': CDS_PINID='A';
NET_NAME
'PD_PCH_GPPC_A_15'
 '@S9S_MB_2U_LIB.S9S_MB_2U(SCH_1):PD_PCH_GPPC_A_15':
 C_SIGNAL='@s9s_mb_2u_lib.s9s_mb_2u(sch_1):pd_pch_gppc_a_15';
NODE_NAME     U4 BE14
 '@S9S_MB_2U_LIB.S9S_MB_2U(SCH_1):PAGE175_I93@PURE_QUANTA.EMMITSBURG_REV0P9(CHIPS)':
 'GPPC_A_15_SRCCLKREQ_N_5': CDS_PINID='GPPC_A_15_SRCCLKREQ_N_5';
NODE_NAME     R4097 1
 '@S9S_MB_2U_LIB.S9S_MB_2U(SCH_1):PAGE175_I286@PURE_QUANTA.Q_RES(CHIPS)':
 'A': CDS_PINID='A';
NET_NAME
'PD_PCH_GPPC_A_18'
 '@S9S_MB_2U_LIB.S9S_MB_2U(SCH_1):PD_PCH_GPPC_A_18':
 C_SIGNAL='@s9s_mb_2u_lib.s9s_mb_2u(sch_1):pd_pch_gppc_a_18';
NODE_NAME     U4 BF11
 '@S9S_MB_2U_LIB.S9S_MB_2U(SCH_1):PAGE175_I93@PURE_QUANTA.EMMITSBURG_REV0P9(CHIPS)':
 'GPPC_A_18_SRCCLKREQ_N_8': CDS_PINID='GPPC_A_18_SRCCLKREQ_N_8';
NODE_NAME     R4096 1
 '@S9S_MB_2U_LIB.S9S_MB_2U(SCH_1):PAGE175_I285@PURE_QUANTA.Q_RES(CHIPS)':
 'A': CDS_PINID='A';
NET_NAME
'PD_PCH_GPPC_A_19'
 '@S9S_MB_2U_LIB.S9S_MB_2U(SCH_1):PD_PCH_GPPC_A_19':
 C_SIGNAL='@s9s_mb_2u_lib.s9s_mb_2u(sch_1):pd_pch_gppc_a_19';
NODE_NAME     U4 BG14
 '@S9S_MB_2U_LIB.S9S_MB_2U(SCH_1):PAGE175_I93@PURE_QUANTA.EMMITSBURG_REV0P9(CHIPS)':
 'GPPC_A_19_SRCCLKREQ_N_9': CDS_PINID='GPPC_A_19_SRCCLKREQ_N_9';
NODE_NAME     R4095 1
 '@S9S_MB_2U_LIB.S9S_MB_2U(SCH_1):PAGE175_I284@PURE_QUANTA.Q_RES(CHIPS)':
 'A': CDS_PINID='A';
NET_NAME
'PD_PCH_GPPC_C10'
 '@S9S_MB_2U_LIB.S9S_MB_2U(SCH_1):PD_PCH_GPPC_C10':
 C_SIGNAL='@s9s_mb_2u_lib.s9s_mb_2u(sch_1):pd_pch_gppc_c10';
NODE_NAME     U4 AP3
 '@S9S_MB_2U_LIB.S9S_MB_2U(SCH_1):PAGE175_I93@PURE_QUANTA.EMMITSBURG_REV0P9(CHIPS)':
 'GPPC_C_10_ME_SML2DATA': CDS_PINID='GPPC_C_10_ME_SML2DATA';
NODE_NAME     R4100 1
 '@S9S_MB_2U_LIB.S9S_MB_2U(SCH_1):PAGE175_I300@PURE_QUANTA.Q_RES(CHIPS)':
 'A': CDS_PINID='A';
NET_NAME
'PD_PCH_GPPC_C5'
 '@S9S_MB_2U_LIB.S9S_MB_2U(SCH_1):PD_PCH_GPPC_C5':
 C_SIGNAL='@s9s_mb_2u_lib.s9s_mb_2u(sch_1):pd_pch_gppc_c5';
NODE_NAME     U4 AT3
 '@S9S_MB_2U_LIB.S9S_MB_2U(SCH_1):PAGE175_I93@PURE_QUANTA.EMMITSBURG_REV0P9(CHIPS)':
 'GPPC_C_5_ME_SML0BALERT_N': CDS_PINID='GPPC_C_5_ME_SML0BALERT_N';
NODE_NAME     R4102 1
 '@S9S_MB_2U_LIB.S9S_MB_2U(SCH_1):PAGE175_I298@PURE_QUANTA.Q_RES(CHIPS)':
 'A': CDS_PINID='A';
NET_NAME
'PD_PCH_GPPC_C9'
 '@S9S_MB_2U_LIB.S9S_MB_2U(SCH_1):PD_PCH_GPPC_C9':
 C_SIGNAL='@s9s_mb_2u_lib.s9s_mb_2u(sch_1):pd_pch_gppc_c9';
NODE_NAME     U4 AR2
 '@S9S_MB_2U_LIB.S9S_MB_2U(SCH_1):PAGE175_I93@PURE_QUANTA.EMMITSBURG_REV0P9(CHIPS)':
 'GPPC_C_9_ME_SML2CLK': CDS_PINID='GPPC_C_9_ME_SML2CLK';
NODE_NAME     R4101 1
 '@S9S_MB_2U_LIB.S9S_MB_2U(SCH_1):PAGE175_I299@PURE_QUANTA.Q_RES(CHIPS)':
 'A': CDS_PINID='A';
NET_NAME
'PD_PCH_GPP_E_10'
 '@S9S_MB_2U_LIB.S9S_MB_2U(SCH_1):PD_PCH_GPP_E_10':
 C_SIGNAL='@s9s_mb_2u_lib.s9s_mb_2u(sch_1):pd_pch_gpp_e_10';
NODE_NAME     U4 AV31
 '@S9S_MB_2U_LIB.S9S_MB_2U(SCH_1):PAGE176_I22@PURE_QUANTA.EMMITSBURG_REV0P9(CHIPS)':
 'GPP_E_10_SATA0_SDATAOUT_SATA0_GP': CDS_PINID='GPP_E_10_SATA0_SDATAOUT_SATA0_GP';
NODE_NAME     R4114 1
 '@S9S_MB_2U_LIB.S9S_MB_2U(SCH_1):PAGE176_I205@PURE_QUANTA.Q_RES(CHIPS)':
 'A': CDS_PINID='A';
NET_NAME
'PD_PCH_GPP_E_11'
 '@S9S_MB_2U_LIB.S9S_MB_2U(SCH_1):PD_PCH_GPP_E_11':
 C_SIGNAL='@s9s_mb_2u_lib.s9s_mb_2u(sch_1):pd_pch_gpp_e_11';
NODE_NAME     U4 AV34
 '@S9S_MB_2U_LIB.S9S_MB_2U(SCH_1):PAGE176_I22@PURE_QUANTA.EMMITSBURG_REV0P9(CHIPS)':
 'GPP_E_11_SATA1_SCLOCK_SATA1_LED_N': CDS_PINID='GPP_E_11_SATA1_SCLOCK_SATA1_LED_N';
NODE_NAME     R4113 1
 '@S9S_MB_2U_LIB.S9S_MB_2U(SCH_1):PAGE176_I206@PURE_QUANTA.Q_RES(CHIPS)':
 'A': CDS_PINID='A';
NET_NAME
'PD_PCH_GPP_E_12'
 '@S9S_MB_2U_LIB.S9S_MB_2U(SCH_1):PD_PCH_GPP_E_12':
 C_SIGNAL='@s9s_mb_2u_lib.s9s_mb_2u(sch_1):pd_pch_gpp_e_12';
NODE_NAME     U4 BB28
 '@S9S_MB_2U_LIB.S9S_MB_2U(SCH_1):PAGE176_I22@PURE_QUANTA.EMMITSBURG_REV0P9(CHIPS)':
 'GPP_E_12_SATA1_SLOAD_SATA1_GP': CDS_PINID='GPP_E_12_SATA1_SLOAD_SATA1_GP';
NODE_NAME     R4112 1
 '@S9S_MB_2U_LIB.S9S_MB_2U(SCH_1):PAGE176_I203@PURE_QUANTA.Q_RES(CHIPS)':
 'A': CDS_PINID='A';
NET_NAME
'PD_PCH_GPP_E_13'
 '@S9S_MB_2U_LIB.S9S_MB_2U(SCH_1):PD_PCH_GPP_E_13':
 C_SIGNAL='@s9s_mb_2u_lib.s9s_mb_2u(sch_1):pd_pch_gpp_e_13';
NODE_NAME     U4 BA32
 '@S9S_MB_2U_LIB.S9S_MB_2U(SCH_1):PAGE176_I22@PURE_QUANTA.EMMITSBURG_REV0P9(CHIPS)':
 'GPP_E_13_SATA1_SDATAOUT_SATA1_DEVSLP': CDS_PINID='GPP_E_13_SATA1_SDATAOUT_SATA1_DEVSLP';
NODE_NAME     R4111 1
 '@S9S_MB_2U_LIB.S9S_MB_2U(SCH_1):PAGE176_I204@PURE_QUANTA.Q_RES(CHIPS)':
 'A': CDS_PINID='A';
NET_NAME
'PD_PCH_GPP_E_14'
 '@S9S_MB_2U_LIB.S9S_MB_2U(SCH_1):PD_PCH_GPP_E_14':
 C_SIGNAL='@s9s_mb_2u_lib.s9s_mb_2u(sch_1):pd_pch_gpp_e_14';
NODE_NAME     U4 BB34
 '@S9S_MB_2U_LIB.S9S_MB_2U(SCH_1):PAGE176_I22@PURE_QUANTA.EMMITSBURG_REV0P9(CHIPS)':
 'GPP_E_14_SATA2_SCLOCK_SATA2_LED_N': CDS_PINID='GPP_E_14_SATA2_SCLOCK_SATA2_LED_N';
NODE_NAME     R4110 1
 '@S9S_MB_2U_LIB.S9S_MB_2U(SCH_1):PAGE176_I202@PURE_QUANTA.Q_RES(CHIPS)':
 'A': CDS_PINID='A';
NET_NAME
'PD_PCH_GPP_E_3'
 '@S9S_MB_2U_LIB.S9S_MB_2U(SCH_1):PD_PCH_GPP_E_3':
 C_SIGNAL='@s9s_mb_2u_lib.s9s_mb_2u(sch_1):pd_pch_gpp_e_3';
NODE_NAME     U4 BB21
 '@S9S_MB_2U_LIB.S9S_MB_2U(SCH_1):PAGE176_I22@PURE_QUANTA.EMMITSBURG_REV0P9(CHIPS)':
 'GPP_E_3_SATA1_XPCIE_3': CDS_PINID='GPP_E_3_SATA1_XPCIE_3';
NODE_NAME     R4117 1
 '@S9S_MB_2U_LIB.S9S_MB_2U(SCH_1):PAGE176_I209@PURE_QUANTA.Q_RES(CHIPS)':
 'A': CDS_PINID='A';
NET_NAME
'PD_PCH_GPP_E_8'
 '@S9S_MB_2U_LIB.S9S_MB_2U(SCH_1):PD_PCH_GPP_E_8':
 C_SIGNAL='@s9s_mb_2u_lib.s9s_mb_2u(sch_1):pd_pch_gpp_e_8';
NODE_NAME     U4 AW36
 '@S9S_MB_2U_LIB.S9S_MB_2U(SCH_1):PAGE176_I22@PURE_QUANTA.EMMITSBURG_REV0P9(CHIPS)':
 'GPP_E_8_SATA0_SCLOCK_SATA0_LED_N': CDS_PINID='GPP_E_8_SATA0_SCLOCK_SATA0_LED_N';
NODE_NAME     R4116 1
 '@S9S_MB_2U_LIB.S9S_MB_2U(SCH_1):PAGE176_I207@PURE_QUANTA.Q_RES(CHIPS)':
 'A': CDS_PINID='A';
NET_NAME
'PD_PCH_GPP_E_9'
 '@S9S_MB_2U_LIB.S9S_MB_2U(SCH_1):PD_PCH_GPP_E_9':
 C_SIGNAL='@s9s_mb_2u_lib.s9s_mb_2u(sch_1):pd_pch_gpp_e_9';
NODE_NAME     U4 BA29
 '@S9S_MB_2U_LIB.S9S_MB_2U(SCH_1):PAGE176_I22@PURE_QUANTA.EMMITSBURG_REV0P9(CHIPS)':
 'GPP_E_9_SATA0_SLOAD_SATA0_DEVSLP': CDS_PINID='GPP_E_9_SATA0_SLOAD_SATA0_DEVSLP';
NODE_NAME     R4115 1
 '@S9S_MB_2U_LIB.S9S_MB_2U(SCH_1):PAGE176_I201@PURE_QUANTA.Q_RES(CHIPS)':
 'A': CDS_PINID='A';
NET_NAME
'PD_PCH_USB2_COMP'
 '@S9S_MB_2U_LIB.S9S_MB_2U(SCH_1):PD_PCH_USB2_COMP':
 C_SIGNAL='@s9s_mb_2u_lib.s9s_mb_2u(sch_1):pd_pch_usb2_comp';
NODE_NAME     R496 1
 '@S9S_MB_2U_LIB.S9S_MB_2U(SCH_1):PAGE172_I10@PURE_QUANTA.Q_RES(CHIPS)':
 'A': CDS_PINID='A';
NODE_NAME     U4 BB41
 '@S9S_MB_2U_LIB.S9S_MB_2U(SCH_1):PAGE172_I11@PURE_QUANTA.EMMITSBURG_REV0P9(CHIPS)':
 'USB2_COMP': CDS_PINID='USB2_COMP';
NET_NAME
'PD_PCH_XCLK_BIASREF'
 '@S9S_MB_2U_LIB.S9S_MB_2U(SCH_1):PD_PCH_XCLK_BIASREF':
 C_SIGNAL='@s9s_mb_2u_lib.s9s_mb_2u(sch_1):pd_pch_xclk_biasref';
NODE_NAME     R477 1
 '@S9S_MB_2U_LIB.S9S_MB_2U(SCH_1):PAGE171_I69@PURE_QUANTA.Q_RES(CHIPS)':
 'A': CDS_PINID='A';
NODE_NAME     U4 N29
 '@S9S_MB_2U_LIB.S9S_MB_2U(SCH_1):PAGE171_I78@PURE_QUANTA.EMMITSBURG_REV0P9(CHIPS)':
 'XCLK_BIASREF': CDS_PINID='XCLK_BIASREF';
NET_NAME
'PD_PIROM_CPU0_ADDR0'
 '@S9S_MB_2U_LIB.S9S_MB_2U(SCH_1):PD_PIROM_CPU0_ADDR0':
 C_SIGNAL='@s9s_mb_2u_lib.s9s_mb_2u(sch_1):pd_pirom_cpu0_addr0';
NODE_NAME     U2 CR70
 '@S9S_MB_2U_LIB.S9S_MB_2U(SCH_1):PAGE14_I1@PURE_QUANTA.SOCKET4677_AZIF0045P001C01CS(CHIPS)':
 'PIROM_AD0': CDS_PINID='PIROM_AD0';
NODE_NAME     R335 2
 '@S9S_MB_2U_LIB.S9S_MB_2U(SCH_1):PAGE127_I5@PURE_QUANTA.Q_RES(CHIPS)':
 'B': CDS_PINID='B';
NODE_NAME     R515 1
 '@S9S_MB_2U_LIB.S9S_MB_2U(SCH_1):PAGE127_I7@PURE_QUANTA.Q_RES(CHIPS)':
 'A': CDS_PINID='A';
NET_NAME
'PD_PIROM_CPU0_ADDR1'
 '@S9S_MB_2U_LIB.S9S_MB_2U(SCH_1):PD_PIROM_CPU0_ADDR1':
 C_SIGNAL='@s9s_mb_2u_lib.s9s_mb_2u(sch_1):pd_pirom_cpu0_addr1';
NODE_NAME     U2 CT71
 '@S9S_MB_2U_LIB.S9S_MB_2U(SCH_1):PAGE14_I1@PURE_QUANTA.SOCKET4677_AZIF0045P001C01CS(CHIPS)':
 'PIROM_AD1': CDS_PINID='PIROM_AD1';
NODE_NAME     R334 1
 '@S9S_MB_2U_LIB.S9S_MB_2U(SCH_1):PAGE127_I1@PURE_QUANTA.Q_RES(CHIPS)':
 'A': CDS_PINID='A';
NODE_NAME     R333 2
 '@S9S_MB_2U_LIB.S9S_MB_2U(SCH_1):PAGE127_I6@PURE_QUANTA.Q_RES(CHIPS)':
 'B': CDS_PINID='B';
NET_NAME
'PD_PIROM_CPU0_ADDR2'
 '@S9S_MB_2U_LIB.S9S_MB_2U(SCH_1):PD_PIROM_CPU0_ADDR2':
 C_SIGNAL='@s9s_mb_2u_lib.s9s_mb_2u(sch_1):pd_pirom_cpu0_addr2';
NODE_NAME     U2 CP71
 '@S9S_MB_2U_LIB.S9S_MB_2U(SCH_1):PAGE14_I1@PURE_QUANTA.SOCKET4677_AZIF0045P001C01CS(CHIPS)':
 'PIROM_AD2': CDS_PINID='PIROM_AD2';
NODE_NAME     R331 2
 '@S9S_MB_2U_LIB.S9S_MB_2U(SCH_1):PAGE127_I20@PURE_QUANTA.Q_RES(CHIPS)':
 'B': CDS_PINID='B';
NODE_NAME     R332 1
 '@S9S_MB_2U_LIB.S9S_MB_2U(SCH_1):PAGE127_I21@PURE_QUANTA.Q_RES(CHIPS)':
 'A': CDS_PINID='A';
NET_NAME
'PD_PIROM_CPU1_ADDR1'
 '@S9S_MB_2U_LIB.S9S_MB_2U(SCH_1):PD_PIROM_CPU1_ADDR1':
 C_SIGNAL='@s9s_mb_2u_lib.s9s_mb_2u(sch_1):pd_pirom_cpu1_addr1';
NODE_NAME     U1 CT71
 '@S9S_MB_2U_LIB.S9S_MB_2U(SCH_1):PAGE45_I29@PURE_QUANTA.SOCKET4677_AZIF0045P001C01CS(CHIPS)':
 'PIROM_AD1': CDS_PINID='PIROM_AD1';
NODE_NAME     R627 2
 '@S9S_MB_2U_LIB.S9S_MB_2U(SCH_1):PAGE127_I14@PURE_QUANTA.Q_RES(CHIPS)':
 'B': CDS_PINID='B';
NODE_NAME     R628 1
 '@S9S_MB_2U_LIB.S9S_MB_2U(SCH_1):PAGE127_I17@PURE_QUANTA.Q_RES(CHIPS)':
 'A': CDS_PINID='A';
NET_NAME
'PD_PIROM_CPU1_ADDR2'
 '@S9S_MB_2U_LIB.S9S_MB_2U(SCH_1):PD_PIROM_CPU1_ADDR2':
 C_SIGNAL='@s9s_mb_2u_lib.s9s_mb_2u(sch_1):pd_pirom_cpu1_addr2';
NODE_NAME     U1 CP71
 '@S9S_MB_2U_LIB.S9S_MB_2U(SCH_1):PAGE45_I29@PURE_QUANTA.SOCKET4677_AZIF0045P001C01CS(CHIPS)':
 'PIROM_AD2': CDS_PINID='PIROM_AD2';
NODE_NAME     R625 2
 '@S9S_MB_2U_LIB.S9S_MB_2U(SCH_1):PAGE127_I24@PURE_QUANTA.Q_RES(CHIPS)':
 'B': CDS_PINID='B';
NODE_NAME     R626 1
 '@S9S_MB_2U_LIB.S9S_MB_2U(SCH_1):PAGE127_I26@PURE_QUANTA.Q_RES(CHIPS)':
 'A': CDS_PINID='A';
NET_NAME
'PD_RCOMP_1P8_3P3'
 '@S9S_MB_2U_LIB.S9S_MB_2U(SCH_1):PD_RCOMP_1P8_3P3':
 C_SIGNAL='@s9s_mb_2u_lib.s9s_mb_2u(sch_1):pd_rcomp_1p8_3p3';
NODE_NAME     R497 1
 '@S9S_MB_2U_LIB.S9S_MB_2U(SCH_1):PAGE179_I2@PURE_QUANTA.Q_RES(CHIPS)':
 'A': CDS_PINID='A';
NODE_NAME     U4 AC13
 '@S9S_MB_2U_LIB.S9S_MB_2U(SCH_1):PAGE179_I4@PURE_QUANTA.EMMITSBURG_REV0P9(CHIPS)':
 'GPIO_RCOMP_1P8_3P3': CDS_PINID='GPIO_RCOMP_1P8_3P3';
NET_NAME
'PD_RST_RTCRST_N'
 '@S9S_MB_2U_LIB.S9S_MB_2U(SCH_1):PD_RST_RTCRST_N':
 C_SIGNAL='@s9s_mb_2u_lib.s9s_mb_2u(sch_1):pd_rst_rtcrst_n';
NODE_NAME     SW5 1
 '@S9S_MB_2U_LIB.S9S_MB_2U(SCH_1):PAGE189_I122@PURE_QUANTA.SW_PUSHBUTTON4P_24(CHIPS)':
 '1': CDS_PINID='\1\';
NODE_NAME     SW5 2
 '@S9S_MB_2U_LIB.S9S_MB_2U(SCH_1):PAGE189_I122@PURE_QUANTA.SW_PUSHBUTTON4P_24(CHIPS)':
 '2': CDS_PINID='\2\';
NODE_NAME     R1333 2
 '@S9S_MB_2U_LIB.S9S_MB_2U(SCH_1):PAGE189_I123@PURE_QUANTA.Q_RES(CHIPS)':
 'B': CDS_PINID='B';
NET_NAME
'PD_SMB_OCP1_HP_ADD0'
 '@S9S_MB_2U_LIB.S9S_MB_2U(SCH_1):PD_SMB_OCP1_HP_ADD0':
 C_SIGNAL='@s9s_mb_2u_lib.s9s_mb_2u(sch_1):pd_smb_ocp1_hp_add0';
NODE_NAME     R1127 2
 '@S9S_MB_2U_LIB.S9S_MB_2U(SCH_1):PAGE154_I133@PURE_QUANTA.Q_RES(CHIPS)':
 'B': CDS_PINID='B';
NODE_NAME     R1128 1
 '@S9S_MB_2U_LIB.S9S_MB_2U(SCH_1):PAGE154_I137@PURE_QUANTA.Q_RES(CHIPS)':
 'A': CDS_PINID='A';
NODE_NAME     U209 21
 '@S9S_MB_2U_LIB.S9S_MB_2U(SCH_1):PAGE154_I206@PURE_QUANTA.PCA9555APW(CHIPS)':
 'A0': CDS_PINID='A0';
NET_NAME
'PD_SMB_OCP1_HP_ADD1'
 '@S9S_MB_2U_LIB.S9S_MB_2U(SCH_1):PD_SMB_OCP1_HP_ADD1':
 C_SIGNAL='@s9s_mb_2u_lib.s9s_mb_2u(sch_1):pd_smb_ocp1_hp_add1';
NODE_NAME     R3037 2
 '@S9S_MB_2U_LIB.S9S_MB_2U(SCH_1):PAGE154_I134@PURE_QUANTA.Q_RES(CHIPS)':
 'B': CDS_PINID='B';
NODE_NAME     R1126 1
 '@S9S_MB_2U_LIB.S9S_MB_2U(SCH_1):PAGE154_I140@PURE_QUANTA.Q_RES(CHIPS)':
 'A': CDS_PINID='A';
NODE_NAME     U209 2
 '@S9S_MB_2U_LIB.S9S_MB_2U(SCH_1):PAGE154_I206@PURE_QUANTA.PCA9555APW(CHIPS)':
 'A1': CDS_PINID='A1';
NET_NAME
'PD_SMB_OCP1_HP_ADD2'
 '@S9S_MB_2U_LIB.S9S_MB_2U(SCH_1):PD_SMB_OCP1_HP_ADD2':
 C_SIGNAL='@s9s_mb_2u_lib.s9s_mb_2u(sch_1):pd_smb_ocp1_hp_add2';
NODE_NAME     R1123 2
 '@S9S_MB_2U_LIB.S9S_MB_2U(SCH_1):PAGE154_I142@PURE_QUANTA.Q_RES(CHIPS)':
 'B': CDS_PINID='B';
NODE_NAME     R1124 1
 '@S9S_MB_2U_LIB.S9S_MB_2U(SCH_1):PAGE154_I143@PURE_QUANTA.Q_RES(CHIPS)':
 'A': CDS_PINID='A';
NODE_NAME     U209 3
 '@S9S_MB_2U_LIB.S9S_MB_2U(SCH_1):PAGE154_I206@PURE_QUANTA.PCA9555APW(CHIPS)':
 'A2': CDS_PINID='A2';
NET_NAME
'PD_SMB_OCP2_HP_ADD0'
 '@S9S_MB_2U_LIB.S9S_MB_2U(SCH_1):PD_SMB_OCP2_HP_ADD0':
 C_SIGNAL='@s9s_mb_2u_lib.s9s_mb_2u(sch_1):pd_smb_ocp2_hp_add0';
NODE_NAME     R3153 2
 '@S9S_MB_2U_LIB.S9S_MB_2U(SCH_1):PAGE132_I32@PURE_QUANTA.Q_RES(CHIPS)':
 'B': CDS_PINID='B';
NODE_NAME     R3154 1
 '@S9S_MB_2U_LIB.S9S_MB_2U(SCH_1):PAGE132_I65@PURE_QUANTA.Q_RES(CHIPS)':
 'A': CDS_PINID='A';
NODE_NAME     U51 21
 '@S9S_MB_2U_LIB.S9S_MB_2U(SCH_1):PAGE132_I66@PURE_QUANTA.PCA9555APW(CHIPS)':
 'A0': CDS_PINID='A0';
NET_NAME
'PD_SMB_OCP2_HP_ADD1'
 '@S9S_MB_2U_LIB.S9S_MB_2U(SCH_1):PD_SMB_OCP2_HP_ADD1':
 C_SIGNAL='@s9s_mb_2u_lib.s9s_mb_2u(sch_1):pd_smb_ocp2_hp_add1';
NODE_NAME     R3152 1
 '@S9S_MB_2U_LIB.S9S_MB_2U(SCH_1):PAGE132_I27@PURE_QUANTA.Q_RES(CHIPS)':
 'A': CDS_PINID='A';
NODE_NAME     R3151 2
 '@S9S_MB_2U_LIB.S9S_MB_2U(SCH_1):PAGE132_I31@PURE_QUANTA.Q_RES(CHIPS)':
 'B': CDS_PINID='B';
NODE_NAME     U51 2
 '@S9S_MB_2U_LIB.S9S_MB_2U(SCH_1):PAGE132_I66@PURE_QUANTA.PCA9555APW(CHIPS)':
 'A1': CDS_PINID='A1';
NET_NAME
'PD_SMB_OCP2_HP_ADD2'
 '@S9S_MB_2U_LIB.S9S_MB_2U(SCH_1):PD_SMB_OCP2_HP_ADD2':
 C_SIGNAL='@s9s_mb_2u_lib.s9s_mb_2u(sch_1):pd_smb_ocp2_hp_add2';
NODE_NAME     R3149 2
 '@S9S_MB_2U_LIB.S9S_MB_2U(SCH_1):PAGE132_I29@PURE_QUANTA.Q_RES(CHIPS)':
 'B': CDS_PINID='B';
NODE_NAME     R3150 1
 '@S9S_MB_2U_LIB.S9S_MB_2U(SCH_1):PAGE132_I25@PURE_QUANTA.Q_RES(CHIPS)':
 'A': CDS_PINID='A';
NODE_NAME     U51 3
 '@S9S_MB_2U_LIB.S9S_MB_2U(SCH_1):PAGE132_I66@PURE_QUANTA.PCA9555APW(CHIPS)':
 'A2': CDS_PINID='A2';
NET_NAME
'PD_SUSCLK'
 '@S9S_MB_2U_LIB.S9S_MB_2U(SCH_1):PD_SUSCLK':
 C_SIGNAL='@s9s_mb_2u_lib.s9s_mb_2u(sch_1):pd_susclk';
NODE_NAME     U4 AR7
 '@S9S_MB_2U_LIB.S9S_MB_2U(SCH_1):PAGE174_I36@PURE_QUANTA.EMMITSBURG_REV0P9(CHIPS)':
 'SUSCLK': CDS_PINID='SUSCLK';
NODE_NAME     R1197 2
 '@S9S_MB_2U_LIB.S9S_MB_2U(SCH_1):PAGE174_I50@PURE_QUANTA.Q_RES(CHIPS)':
 'B': CDS_PINID='B';
NET_NAME
'PD_TRST_P3'
 '@S9S_MB_2U_LIB.S9S_MB_2U(SCH_1):PD_TRST_P3':
 C_SIGNAL='@s9s_mb_2u_lib.s9s_mb_2u(sch_1):pd_trst_p3';
NODE_NAME     J42 8
 '@S9S_MB_2U_LIB.S9S_MB_2U(SCH_1):PAGE133_I44@PURE_QUANTA.SCONN60_ASP21410801(CHIPS)':
 '8': CDS_PINID='\8\';
NODE_NAME     R769 1
 '@S9S_MB_2U_LIB.S9S_MB_2U(SCH_1):PAGE133_I102@PURE_QUANTA.Q_RES(CHIPS)':
 'A': CDS_PINID='A';
NET_NAME
'PD_U5201_EQ'
 '@S9S_MB_2U_LIB.S9S_MB_2U(SCH_1):PD_U5201_EQ':
 C_SIGNAL='@s9s_mb_2u_lib.s9s_mb_2u(sch_1):pd_u5201_eq';
NODE_NAME     R5238 1
 '@S9S_MB_2U_LIB.S9S_MB_2U(SCH_1):PAGE155_I83@PURE_QUANTA.Q_RES(CHIPS)':
 'A': CDS_PINID='A';
NODE_NAME     U5201 6
 '@S9S_MB_2U_LIB.S9S_MB_2U(SCH_1):PAGE155_I84@PURE_QUANTA.TUSB211IRWBR(CHIPS)':
 'EQ': CDS_PINID='EQ';
NET_NAME
'PD_U5201_RSTN'
 '@S9S_MB_2U_LIB.S9S_MB_2U(SCH_1):PD_U5201_RSTN':
 C_SIGNAL='@s9s_mb_2u_lib.s9s_mb_2u(sch_1):pd_u5201_rstn';
NODE_NAME     C5232 1
 '@S9S_MB_2U_LIB.S9S_MB_2U(SCH_1):PAGE155_I81@PURE_QUANTA.Q_CAP(CHIPS)':
 'A': CDS_PINID='A';
NODE_NAME     U5201 5
 '@S9S_MB_2U_LIB.S9S_MB_2U(SCH_1):PAGE155_I84@PURE_QUANTA.TUSB211IRWBR(CHIPS)':
 'RSTN': CDS_PINID='RSTN';
NET_NAME
'PD_U5201_VREG'
 '@S9S_MB_2U_LIB.S9S_MB_2U(SCH_1):PD_U5201_VREG':
 C_SIGNAL='@s9s_mb_2u_lib.s9s_mb_2u(sch_1):pd_u5201_vreg';
NODE_NAME     U5201 11
 '@S9S_MB_2U_LIB.S9S_MB_2U(SCH_1):PAGE155_I84@PURE_QUANTA.TUSB211IRWBR(CHIPS)':
 'VREG': CDS_PINID='VREG';
NODE_NAME     C5236 1
 '@S9S_MB_2U_LIB.S9S_MB_2U(SCH_1):PAGE155_I87@PURE_QUANTA.Q_CAP(CHIPS)':
 'A': CDS_PINID='A';
NET_NAME
'PD_USB_HUB_2_EQ'
 '@S9S_MB_2U_LIB.S9S_MB_2U(SCH_1):PD_USB_HUB_2_EQ':
 C_SIGNAL='@s9s_mb_2u_lib.s9s_mb_2u(sch_1):pd_usb_hub_2_eq';
NODE_NAME     R4465 1
 '@S9S_MB_2U_LIB.S9S_MB_2U(SCH_1):PAGE194_I4@PURE_QUANTA.Q_RES(CHIPS)':
 'A': CDS_PINID='A';
NODE_NAME     U312 6
 '@S9S_MB_2U_LIB.S9S_MB_2U(SCH_1):PAGE194_I20@PURE_QUANTA.TUSB211IRWBR(CHIPS)':
 'EQ': CDS_PINID='EQ';
NET_NAME
'PD_USB_HUB_2_RSTN'
 '@S9S_MB_2U_LIB.S9S_MB_2U(SCH_1):PD_USB_HUB_2_RSTN':
 C_SIGNAL='@s9s_mb_2u_lib.s9s_mb_2u(sch_1):pd_usb_hub_2_rstn';
NODE_NAME     C2321 1
 '@S9S_MB_2U_LIB.S9S_MB_2U(SCH_1):PAGE194_I2@PURE_QUANTA.Q_CAP(CHIPS)':
 'A': CDS_PINID='A';
NODE_NAME     U312 5
 '@S9S_MB_2U_LIB.S9S_MB_2U(SCH_1):PAGE194_I20@PURE_QUANTA.TUSB211IRWBR(CHIPS)':
 'RSTN': CDS_PINID='RSTN';
NET_NAME
'PD_USB_HUB_2_VREG'
 '@S9S_MB_2U_LIB.S9S_MB_2U(SCH_1):PD_USB_HUB_2_VREG':
 C_SIGNAL='@s9s_mb_2u_lib.s9s_mb_2u(sch_1):pd_usb_hub_2_vreg';
NODE_NAME     U312 11
 '@S9S_MB_2U_LIB.S9S_MB_2U(SCH_1):PAGE194_I20@PURE_QUANTA.TUSB211IRWBR(CHIPS)':
 'VREG': CDS_PINID='VREG';
NODE_NAME     C2325 1
 '@S9S_MB_2U_LIB.S9S_MB_2U(SCH_1):PAGE194_I55@PURE_QUANTA.Q_CAP(CHIPS)':
 'A': CDS_PINID='A';
NET_NAME
'PECI_BMC'
 '@S9S_MB_2U_LIB.S9S_MB_2U(SCH_1):PECI_BMC':
 C_SIGNAL='@s9s_mb_2u_lib.s9s_mb_2u(sch_1):peci_bmc';
NODE_NAME     R144 1
 '@S9S_MB_2U_LIB.S9S_MB_2U(SCH_1):PAGE185_I51@PURE_QUANTA.Q_RES(CHIPS)':
 'A': CDS_PINID='A';
NODE_NAME     J41 B27
 '@S9S_MB_2U_LIB.S9S_MB_2U(SCH_1):PAGE227_I173@PURE_QUANTA.SCONN168_ME1016810202011(CHIPS)':
 'PETP3': CDS_PINID='PETP3';
NET_NAME
'PECI_BMC_B1'
 '@S9S_MB_2U_LIB.S9S_MB_2U(SCH_1):PECI_BMC_B1':
 C_SIGNAL='@s9s_mb_2u_lib.s9s_mb_2u(sch_1):peci_bmc_b1';
NODE_NAME     R1297 2
 '@S9S_MB_2U_LIB.S9S_MB_2U(SCH_1):PAGE185_I32@PURE_QUANTA.Q_RES(CHIPS)':
 'B': CDS_PINID='B';
NODE_NAME     U142 1
 '@S9S_MB_2U_LIB.S9S_MB_2U(SCH_1):PAGE185_I35@PURE_QUANTA.NC7SB3157(CHIPS)':
 'B1': CDS_PINID='B1';
NET_NAME
'PECI_BMC_ME'
 '@S9S_MB_2U_LIB.S9S_MB_2U(SCH_1):PECI_BMC_ME':
 C_SIGNAL='@s9s_mb_2u_lib.s9s_mb_2u(sch_1):peci_bmc_me';
NODE_NAME     R3064 2
 '@S9S_MB_2U_LIB.S9S_MB_2U(SCH_1):PAGE185_I45@PURE_QUANTA.Q_RES(CHIPS)':
 'B': CDS_PINID='B';
NODE_NAME     J100 16
 '@S9S_MB_2U_LIB.S9S_MB_2U(SCH_1):PAGE215_I32@PURE_QUANTA.SCONN20_513860200CV01(CHIPS)':
 '16': CDS_PINID='\16\';
NET_NAME
'PECI_BMC_R'
 '@S9S_MB_2U_LIB.S9S_MB_2U(SCH_1):PECI_BMC_R':
 C_SIGNAL='@s9s_mb_2u_lib.s9s_mb_2u(sch_1):peci_bmc_r';
NODE_NAME     R146 2
 '@S9S_MB_2U_LIB.S9S_MB_2U(SCH_1):PAGE185_I30@PURE_QUANTA.Q_RES(CHIPS)':
 'B': CDS_PINID='B';
NODE_NAME     R1297 1
 '@S9S_MB_2U_LIB.S9S_MB_2U(SCH_1):PAGE185_I32@PURE_QUANTA.Q_RES(CHIPS)':
 'A': CDS_PINID='A';
NODE_NAME     R148 1
 '@S9S_MB_2U_LIB.S9S_MB_2U(SCH_1):PAGE185_I49@PURE_QUANTA.Q_RES(CHIPS)':
 'A': CDS_PINID='A';
NODE_NAME     R144 2
 '@S9S_MB_2U_LIB.S9S_MB_2U(SCH_1):PAGE185_I51@PURE_QUANTA.Q_RES(CHIPS)':
 'B': CDS_PINID='B';
NET_NAME
'PECI_CPU0_GTL_R'
 '@S9S_MB_2U_LIB.S9S_MB_2U(SCH_1):PECI_CPU0_GTL_R':
 C_SIGNAL='@s9s_mb_2u_lib.s9s_mb_2u(sch_1):peci_cpu0_gtl_r';
NODE_NAME     R3 2
 '@S9S_MB_2U_LIB.S9S_MB_2U(SCH_1):PAGE13_I21@PURE_QUANTA.Q_RES(CHIPS)':
 'B': CDS_PINID='B';
NODE_NAME     U2 BH24
 '@S9S_MB_2U_LIB.S9S_MB_2U(SCH_1):PAGE13_I57@PURE_QUANTA.SOCKET4677_AZIF0045P001C01CS(CHIPS)':
 'PECI': CDS_PINID='PECI';
NET_NAME
'PECI_CPU1_GTL_R'
 '@S9S_MB_2U_LIB.S9S_MB_2U(SCH_1):PECI_CPU1_GTL_R':
 C_SIGNAL='@s9s_mb_2u_lib.s9s_mb_2u(sch_1):peci_cpu1_gtl_r';
NODE_NAME     R63 2
 '@S9S_MB_2U_LIB.S9S_MB_2U(SCH_1):PAGE44_I10@PURE_QUANTA.Q_RES(CHIPS)':
 'B': CDS_PINID='B';
NODE_NAME     U1 BH24
 '@S9S_MB_2U_LIB.S9S_MB_2U(SCH_1):PAGE44_I51@PURE_QUANTA.SOCKET4677_AZIF0045P001C01CS(CHIPS)':
 'PECI': CDS_PINID='PECI';
NET_NAME
'PECI_CPU_GTL'
 '@S9S_MB_2U_LIB.S9S_MB_2U(SCH_1):PECI_CPU_GTL':
 C_SIGNAL='@s9s_mb_2u_lib.s9s_mb_2u(sch_1):peci_cpu_gtl';
NODE_NAME     R3 1
 '@S9S_MB_2U_LIB.S9S_MB_2U(SCH_1):PAGE13_I21@PURE_QUANTA.Q_RES(CHIPS)':
 'A': CDS_PINID='A';
NODE_NAME     R63 1
 '@S9S_MB_2U_LIB.S9S_MB_2U(SCH_1):PAGE44_I10@PURE_QUANTA.Q_RES(CHIPS)':
 'A': CDS_PINID='A';
NODE_NAME     U142 4
 '@S9S_MB_2U_LIB.S9S_MB_2U(SCH_1):PAGE185_I35@PURE_QUANTA.NC7SB3157(CHIPS)':
 'A': CDS_PINID='A';
NODE_NAME     R3064 1
 '@S9S_MB_2U_LIB.S9S_MB_2U(SCH_1):PAGE185_I45@PURE_QUANTA.Q_RES(CHIPS)':
 'A': CDS_PINID='A';
NET_NAME
'PECI_MUX_SEL_R'
 '@S9S_MB_2U_LIB.S9S_MB_2U(SCH_1):PECI_MUX_SEL_R':
 C_SIGNAL='@s9s_mb_2u_lib.s9s_mb_2u(sch_1):peci_mux_sel_r';
NODE_NAME     U142 6
 '@S9S_MB_2U_LIB.S9S_MB_2U(SCH_1):PAGE185_I35@PURE_QUANTA.NC7SB3157(CHIPS)':
 'S': CDS_PINID='S';
NODE_NAME     R2253 2
 '@S9S_MB_2U_LIB.S9S_MB_2U(SCH_1):PAGE185_I39@PURE_QUANTA.Q_RES(CHIPS)':
 'B': CDS_PINID='B';
NODE_NAME     R2255 1
 '@S9S_MB_2U_LIB.S9S_MB_2U(SCH_1):PAGE185_I41@PURE_QUANTA.Q_RES(CHIPS)':
 'A': CDS_PINID='A';
NODE_NAME     R2252 1
 '@S9S_MB_2U_LIB.S9S_MB_2U(SCH_1):PAGE185_I42@PURE_QUANTA.Q_RES(CHIPS)':
 'A': CDS_PINID='A';
NET_NAME
'PECI_PCH'
 '@S9S_MB_2U_LIB.S9S_MB_2U(SCH_1):PECI_PCH':
 C_SIGNAL='@s9s_mb_2u_lib.s9s_mb_2u(sch_1):peci_pch';
NODE_NAME     U4 J10
 '@S9S_MB_2U_LIB.S9S_MB_2U(SCH_1):PAGE174_I36@PURE_QUANTA.EMMITSBURG_REV0P9(CHIPS)':
 'ME_PECI': CDS_PINID='ME_PECI';
NODE_NAME     R143 1
 '@S9S_MB_2U_LIB.S9S_MB_2U(SCH_1):PAGE185_I47@PURE_QUANTA.Q_RES(CHIPS)':
 'A': CDS_PINID='A';
NET_NAME
'PECI_PCH_B1'
 '@S9S_MB_2U_LIB.S9S_MB_2U(SCH_1):PECI_PCH_B1':
 C_SIGNAL='@s9s_mb_2u_lib.s9s_mb_2u(sch_1):peci_pch_b1';
NODE_NAME     R149 2
 '@S9S_MB_2U_LIB.S9S_MB_2U(SCH_1):PAGE185_I24@PURE_QUANTA.Q_RES(CHIPS)':
 'B': CDS_PINID='B';
NODE_NAME     U142 3
 '@S9S_MB_2U_LIB.S9S_MB_2U(SCH_1):PAGE185_I35@PURE_QUANTA.NC7SB3157(CHIPS)':
 'B0': CDS_PINID='B0';
NET_NAME
'PECI_PCH_R'
 '@S9S_MB_2U_LIB.S9S_MB_2U(SCH_1):PECI_PCH_R':
 C_SIGNAL='@s9s_mb_2u_lib.s9s_mb_2u(sch_1):peci_pch_r';
NODE_NAME     R149 1
 '@S9S_MB_2U_LIB.S9S_MB_2U(SCH_1):PAGE185_I24@PURE_QUANTA.Q_RES(CHIPS)':
 'A': CDS_PINID='A';
NODE_NAME     R145 2
 '@S9S_MB_2U_LIB.S9S_MB_2U(SCH_1):PAGE185_I26@PURE_QUANTA.Q_RES(CHIPS)':
 'B': CDS_PINID='B';
NODE_NAME     R143 2
 '@S9S_MB_2U_LIB.S9S_MB_2U(SCH_1):PAGE185_I47@PURE_QUANTA.Q_RES(CHIPS)':
 'B': CDS_PINID='B';
NODE_NAME     R147 1
 '@S9S_MB_2U_LIB.S9S_MB_2U(SCH_1):PAGE185_I50@PURE_QUANTA.Q_RES(CHIPS)':
 'A': CDS_PINID='A';
NET_NAME
'PGPPA_AUX'
 '@S9S_MB_2U_LIB.S9S_MB_2U(SCH_1):PGPPA_AUX':
 C_SIGNAL='@s9s_mb_2u_lib.s9s_mb_2u(sch_1):pgppa_aux',
 CDS_GLOBAL_NET='TRUE';
NODE_NAME     U60 5
 '@S9S_MB_2U_LIB.S9S_MB_2U(SCH_1):PAGE190_I34@PURE_QUANTA.NC7SB3157(CHIPS)':
 'VCC': CDS_PINID='VCC';
NODE_NAME     C607 1
 '@S9S_MB_2U_LIB.S9S_MB_2U(SCH_1):PAGE190_I36@PURE_QUANTA.Q_CAP(CHIPS)':
 'A': CDS_PINID='A';
NODE_NAME     C605 1
 '@S9S_MB_2U_LIB.S9S_MB_2U(SCH_1):PAGE190_I37@PURE_QUANTA.Q_CAP(CHIPS)':
 'A': CDS_PINID='A';
NODE_NAME     U61 5
 '@S9S_MB_2U_LIB.S9S_MB_2U(SCH_1):PAGE190_I39@PURE_QUANTA.NC7SB3157(CHIPS)':
 'VCC': CDS_PINID='VCC';
NODE_NAME     C608 1
 '@S9S_MB_2U_LIB.S9S_MB_2U(SCH_1):PAGE190_I43@PURE_QUANTA.Q_CAP(CHIPS)':
 'A': CDS_PINID='A';
NODE_NAME     C606 1
 '@S9S_MB_2U_LIB.S9S_MB_2U(SCH_1):PAGE190_I45@PURE_QUANTA.Q_CAP(CHIPS)':
 'A': CDS_PINID='A';
NODE_NAME     R1961 1
 '@S9S_MB_2U_LIB.S9S_MB_2U(SCH_1):PAGE190_I70@PURE_QUANTA.Q_RES(CHIPS)':
 'A': CDS_PINID='A';
NODE_NAME     R1750 1
 '@S9S_MB_2U_LIB.S9S_MB_2U(SCH_1):PAGE190_I87@PURE_QUANTA.Q_RES(CHIPS)':
 'A': CDS_PINID='A';
NODE_NAME     R1253 1
 '@S9S_MB_2U_LIB.S9S_MB_2U(SCH_1):PAGE192_I23@PURE_QUANTA.Q_RES(CHIPS)':
 'A': CDS_PINID='A';
NODE_NAME     R1254 1
 '@S9S_MB_2U_LIB.S9S_MB_2U(SCH_1):PAGE192_I24@PURE_QUANTA.Q_RES(CHIPS)':
 'A': CDS_PINID='A';
NODE_NAME     R1255 1
 '@S9S_MB_2U_LIB.S9S_MB_2U(SCH_1):PAGE192_I26@PURE_QUANTA.Q_RES(CHIPS)':
 'A': CDS_PINID='A';
NODE_NAME     R1747 2
 '@S9S_MB_2U_LIB.S9S_MB_2U(SCH_1):PAGE243_I2@PURE_QUANTA.Q_RES(CHIPS)':
 'B': CDS_PINID='B';
NODE_NAME     C535 1
 '@S9S_MB_2U_LIB.S9S_MB_2U(SCH_1):PAGE243_I4@PURE_QUANTA.Q_CAP(CHIPS)':
 'A': CDS_PINID='A';
NODE_NAME     C513 1
 '@S9S_MB_2U_LIB.S9S_MB_2U(SCH_1):PAGE243_I5@PURE_QUANTA.Q_CAP(CHIPS)':
 'A': CDS_PINID='A';
NODE_NAME     R1763 1
 '@S9S_MB_2U_LIB.S9S_MB_2U(SCH_1):PAGE243_I7@PURE_QUANTA.Q_RES(CHIPS)':
 'A': CDS_PINID='A';
NODE_NAME     R1765 1
 '@S9S_MB_2U_LIB.S9S_MB_2U(SCH_1):PAGE243_I13@PURE_QUANTA.Q_RES(CHIPS)':
 'A': CDS_PINID='A';
NET_NAME
'PRSNT0_N'
 '@S9S_MB_2U_LIB.S9S_MB_2U(SCH_1):PRSNT0_N':
 C_SIGNAL='@s9s_mb_2u_lib.s9s_mb_2u(sch_1):prsnt0_n';
NODE_NAME     R1801 1
 '@S9S_MB_2U_LIB.S9S_MB_2U(SCH_1):PAGE227_I172@PURE_QUANTA.Q_RES(CHIPS)':
 'A': CDS_PINID='A';
NODE_NAME     J41 OB3
 '@S9S_MB_2U_LIB.S9S_MB_2U(SCH_1):PAGE227_I173@PURE_QUANTA.SCONN168_ME1016810202011(CHIPS)':
 'LD#': CDS_PINID='\ld#\';
NET_NAME
'PRSNT_CABLE_GPU_A1'
 '@S9S_MB_2U_LIB.S9S_MB_2U(SCH_1):PRSNT_CABLE_GPU_A1':
 C_SIGNAL='@s9s_mb_2u_lib.s9s_mb_2u(sch_1):prsnt_cable_gpu_a1';
NODE_NAME     Q134 6
 '@S9S_MB_2U_LIB.S9S_MB_2U(SCH_1):PAGE143_I99@PURE_QUANTA.MOSFET_NCH_DUAL(CHIPS)':
 'D1': CDS_PINID='D1';
NODE_NAME     R4155 2
 '@S9S_MB_2U_LIB.S9S_MB_2U(SCH_1):PAGE143_I100@PURE_QUANTA.Q_RES(CHIPS)':
 'B': CDS_PINID='B';
NODE_NAME     Q134 5
 '@S9S_MB_2U_LIB.S9S_MB_2U(SCH_1):PAGE143_I107@PURE_QUANTA.MOSFET_NCH_DUAL(CHIPS)':
 'G2': CDS_PINID='G2';
NET_NAME
'PRSNT_CABLE_GPU_A1_ISO_N'
 '@S9S_MB_2U_LIB.S9S_MB_2U(SCH_1):PRSNT_CABLE_GPU_A1_ISO_N':
 C_SIGNAL='@s9s_mb_2u_lib.s9s_mb_2u(sch_1):prsnt_cable_gpu_a1_iso_n';
NODE_NAME     R4156 2
 '@S9S_MB_2U_LIB.S9S_MB_2U(SCH_1):PAGE143_I101@PURE_QUANTA.Q_RES(CHIPS)':
 'B': CDS_PINID='B';
NODE_NAME     C2270 1
 '@S9S_MB_2U_LIB.S9S_MB_2U(SCH_1):PAGE143_I105@PURE_QUANTA.Q_CAP(CHIPS)':
 'A': CDS_PINID='A';
NODE_NAME     Q134 3
 '@S9S_MB_2U_LIB.S9S_MB_2U(SCH_1):PAGE143_I107@PURE_QUANTA.MOSFET_NCH_DUAL(CHIPS)':
 'D2': CDS_PINID='D2';
NODE_NAME     R4157 1
 '@S9S_MB_2U_LIB.S9S_MB_2U(SCH_1):PAGE312_I114@PURE_QUANTA.Q_RES(CHIPS)':
 'A': CDS_PINID='A';
NODE_NAME     R4574 2
 '@S9S_MB_2U_LIB.S9S_MB_2U(SCH_1):PAGE143_I136@PURE_QUANTA.Q_RES(CHIPS)':
 'B': CDS_PINID='B';
NODE_NAME     R4742 1
 '@S9S_MB_2U_LIB.S9S_MB_2U(SCH_1):PAGE214_I161@PURE_QUANTA.Q_RES(CHIPS)':
 'A': CDS_PINID='A';
NET_NAME
'PRSNT_CABLE_GPU_A1_ISO_R1_N'
 '@S9S_MB_2U_LIB.S9S_MB_2U(SCH_1):PRSNT_CABLE_GPU_A1_ISO_R1_N':
 C_SIGNAL='@s9s_mb_2u_lib.s9s_mb_2u(sch_1):prsnt_cable_gpu_a1_iso_r1_n';
NODE_NAME     U181 19
 '@S9S_MB_2U_LIB.S9S_MB_2U(SCH_1):PAGE214_I66@PURE_QUANTA.PCA9539RPW(CHIPS)':
 'IO1_6': CDS_PINID='IO1_6';
NODE_NAME     R4742 2
 '@S9S_MB_2U_LIB.S9S_MB_2U(SCH_1):PAGE214_I161@PURE_QUANTA.Q_RES(CHIPS)':
 'B': CDS_PINID='B';
NET_NAME
'PRSNT_CABLE_GPU_A1_ISO_R_N'
 '@S9S_MB_2U_LIB.S9S_MB_2U(SCH_1):PRSNT_CABLE_GPU_A1_ISO_R_N':
 C_SIGNAL='@s9s_mb_2u_lib.s9s_mb_2u(sch_1):prsnt_cable_gpu_a1_iso_r_n';
NODE_NAME     U249 Y12
 '@S9S_MB_2U_LIB.S9S_MB_2U(SCH_1):PAGE312_I1@PURE_QUANTA.LCMXO3LF9400C5BG484C(CHIPS)':
 'PB27A': CDS_PINID='PB27A';
NODE_NAME     R4157 2
 '@S9S_MB_2U_LIB.S9S_MB_2U(SCH_1):PAGE312_I114@PURE_QUANTA.Q_RES(CHIPS)':
 'B': CDS_PINID='B';
NET_NAME
'PRSNT_CABLE_GPU_A1_N'
 '@S9S_MB_2U_LIB.S9S_MB_2U(SCH_1):PRSNT_CABLE_GPU_A1_N':
 C_SIGNAL='@s9s_mb_2u_lib.s9s_mb_2u(sch_1):prsnt_cable_gpu_a1_n';
NODE_NAME     J106 A7
 '@S9S_MB_2U_LIB.S9S_MB_2U(SCH_1):PAGE144_I68@PURE_QUANTA.CONN112_10137002101LF(CHIPS)':
 'A7': CDS_PINID='A7';
NODE_NAME     Q134 2
 '@S9S_MB_2U_LIB.S9S_MB_2U(SCH_1):PAGE143_I99@PURE_QUANTA.MOSFET_NCH_DUAL(CHIPS)':
 'G1': CDS_PINID='G1';
NODE_NAME     R4154 1
 '@S9S_MB_2U_LIB.S9S_MB_2U(SCH_1):PAGE143_I113@PURE_QUANTA.Q_RES(CHIPS)':
 'A': CDS_PINID='A';
NODE_NAME     R4574 1
 '@S9S_MB_2U_LIB.S9S_MB_2U(SCH_1):PAGE143_I136@PURE_QUANTA.Q_RES(CHIPS)':
 'A': CDS_PINID='A';
NODE_NAME     R4153 2
 '@S9S_MB_2U_LIB.S9S_MB_2U(SCH_1):PAGE143_I145@PURE_QUANTA.Q_RES(CHIPS)':
 'B': CDS_PINID='B';
NET_NAME
'PRSNT_CABLE_GPU_A2'
 '@S9S_MB_2U_LIB.S9S_MB_2U(SCH_1):PRSNT_CABLE_GPU_A2':
 C_SIGNAL='@s9s_mb_2u_lib.s9s_mb_2u(sch_1):prsnt_cable_gpu_a2';
NODE_NAME     Q133 5
 '@S9S_MB_2U_LIB.S9S_MB_2U(SCH_1):PAGE143_I71@PURE_QUANTA.MOSFET_NCH_DUAL(CHIPS)':
 'G2': CDS_PINID='G2';
NODE_NAME     R4139 2
 '@S9S_MB_2U_LIB.S9S_MB_2U(SCH_1):PAGE143_I76@PURE_QUANTA.Q_RES(CHIPS)':
 'B': CDS_PINID='B';
NODE_NAME     Q133 6
 '@S9S_MB_2U_LIB.S9S_MB_2U(SCH_1):PAGE143_I78@PURE_QUANTA.MOSFET_NCH_DUAL(CHIPS)':
 'D1': CDS_PINID='D1';
NET_NAME
'PRSNT_CABLE_GPU_A2_ISO_N'
 '@S9S_MB_2U_LIB.S9S_MB_2U(SCH_1):PRSNT_CABLE_GPU_A2_ISO_N':
 C_SIGNAL='@s9s_mb_2u_lib.s9s_mb_2u(sch_1):prsnt_cable_gpu_a2_iso_n';
NODE_NAME     C2269 1
 '@S9S_MB_2U_LIB.S9S_MB_2U(SCH_1):PAGE143_I57@PURE_QUANTA.Q_CAP(CHIPS)':
 'A': CDS_PINID='A';
NODE_NAME     R4142 2
 '@S9S_MB_2U_LIB.S9S_MB_2U(SCH_1):PAGE143_I60@PURE_QUANTA.Q_RES(CHIPS)':
 'B': CDS_PINID='B';
NODE_NAME     Q133 3
 '@S9S_MB_2U_LIB.S9S_MB_2U(SCH_1):PAGE143_I71@PURE_QUANTA.MOSFET_NCH_DUAL(CHIPS)':
 'D2': CDS_PINID='D2';
NODE_NAME     R4147 1
 '@S9S_MB_2U_LIB.S9S_MB_2U(SCH_1):PAGE312_I104@PURE_QUANTA.Q_RES(CHIPS)':
 'A': CDS_PINID='A';
NODE_NAME     R4578 2
 '@S9S_MB_2U_LIB.S9S_MB_2U(SCH_1):PAGE143_I138@PURE_QUANTA.Q_RES(CHIPS)':
 'B': CDS_PINID='B';
NODE_NAME     R4736 1
 '@S9S_MB_2U_LIB.S9S_MB_2U(SCH_1):PAGE214_I153@PURE_QUANTA.Q_RES(CHIPS)':
 'A': CDS_PINID='A';
NET_NAME
'PRSNT_CABLE_GPU_A2_ISO_R1_N'
 '@S9S_MB_2U_LIB.S9S_MB_2U(SCH_1):PRSNT_CABLE_GPU_A2_ISO_R1_N':
 C_SIGNAL='@s9s_mb_2u_lib.s9s_mb_2u(sch_1):prsnt_cable_gpu_a2_iso_r1_n';
NODE_NAME     U181 13
 '@S9S_MB_2U_LIB.S9S_MB_2U(SCH_1):PAGE214_I66@PURE_QUANTA.PCA9539RPW(CHIPS)':
 'IO1_0': CDS_PINID='IO1_0';
NODE_NAME     R4736 2
 '@S9S_MB_2U_LIB.S9S_MB_2U(SCH_1):PAGE214_I153@PURE_QUANTA.Q_RES(CHIPS)':
 'B': CDS_PINID='B';
NET_NAME
'PRSNT_CABLE_GPU_A2_ISO_R_N'
 '@S9S_MB_2U_LIB.S9S_MB_2U(SCH_1):PRSNT_CABLE_GPU_A2_ISO_R_N':
 C_SIGNAL='@s9s_mb_2u_lib.s9s_mb_2u(sch_1):prsnt_cable_gpu_a2_iso_r_n';
NODE_NAME     U249 V11
 '@S9S_MB_2U_LIB.S9S_MB_2U(SCH_1):PAGE312_I1@PURE_QUANTA.LCMXO3LF9400C5BG484C(CHIPS)':
 'PB24C': CDS_PINID='PB24C';
NODE_NAME     R4147 2
 '@S9S_MB_2U_LIB.S9S_MB_2U(SCH_1):PAGE312_I104@PURE_QUANTA.Q_RES(CHIPS)':
 'B': CDS_PINID='B';
NET_NAME
'PRSNT_CABLE_GPU_A2_N'
 '@S9S_MB_2U_LIB.S9S_MB_2U(SCH_1):PRSNT_CABLE_GPU_A2_N':
 C_SIGNAL='@s9s_mb_2u_lib.s9s_mb_2u(sch_1):prsnt_cable_gpu_a2_n';
NODE_NAME     J108 A3
 '@S9S_MB_2U_LIB.S9S_MB_2U(SCH_1):PAGE320_I57@PURE_QUANTA.CONN112_10137002101LF(CHIPS)':
 'A3': CDS_PINID='A3';
NODE_NAME     Q133 2
 '@S9S_MB_2U_LIB.S9S_MB_2U(SCH_1):PAGE143_I78@PURE_QUANTA.MOSFET_NCH_DUAL(CHIPS)':
 'G1': CDS_PINID='G1';
NODE_NAME     R4136 1
 '@S9S_MB_2U_LIB.S9S_MB_2U(SCH_1):PAGE143_I91@PURE_QUANTA.Q_RES(CHIPS)':
 'A': CDS_PINID='A';
NODE_NAME     R4578 1
 '@S9S_MB_2U_LIB.S9S_MB_2U(SCH_1):PAGE143_I138@PURE_QUANTA.Q_RES(CHIPS)':
 'A': CDS_PINID='A';
NODE_NAME     R4135 2
 '@S9S_MB_2U_LIB.S9S_MB_2U(SCH_1):PAGE143_I144@PURE_QUANTA.Q_RES(CHIPS)':
 'B': CDS_PINID='B';
NET_NAME
'PRSNT_CABLE_GPU_A3'
 '@S9S_MB_2U_LIB.S9S_MB_2U(SCH_1):PRSNT_CABLE_GPU_A3':
 C_SIGNAL='@s9s_mb_2u_lib.s9s_mb_2u(sch_1):prsnt_cable_gpu_a3';
NODE_NAME     Q154 5
 '@S9S_MB_2U_LIB.S9S_MB_2U(SCH_1):PAGE147_I62@PURE_QUANTA.MOSFET_NCH_DUAL(CHIPS)':
 'G2': CDS_PINID='G2';
NODE_NAME     R4800 2
 '@S9S_MB_2U_LIB.S9S_MB_2U(SCH_1):PAGE147_I70@PURE_QUANTA.Q_RES(CHIPS)':
 'B': CDS_PINID='B';
NODE_NAME     Q154 6
 '@S9S_MB_2U_LIB.S9S_MB_2U(SCH_1):PAGE147_I71@PURE_QUANTA.MOSFET_NCH_DUAL(CHIPS)':
 'D1': CDS_PINID='D1';
NET_NAME
'PRSNT_CABLE_GPU_A3_ISO_N'
 '@S9S_MB_2U_LIB.S9S_MB_2U(SCH_1):PRSNT_CABLE_GPU_A3_ISO_N':
 C_SIGNAL='@s9s_mb_2u_lib.s9s_mb_2u(sch_1):prsnt_cable_gpu_a3_iso_n';
NODE_NAME     Q154 3
 '@S9S_MB_2U_LIB.S9S_MB_2U(SCH_1):PAGE147_I62@PURE_QUANTA.MOSFET_NCH_DUAL(CHIPS)':
 'D2': CDS_PINID='D2';
NODE_NAME     R4801 2
 '@S9S_MB_2U_LIB.S9S_MB_2U(SCH_1):PAGE147_I65@PURE_QUANTA.Q_RES(CHIPS)':
 'B': CDS_PINID='B';
NODE_NAME     C2391 1
 '@S9S_MB_2U_LIB.S9S_MB_2U(SCH_1):PAGE147_I66@PURE_QUANTA.Q_CAP(CHIPS)':
 'A': CDS_PINID='A';
NODE_NAME     R4802 1
 '@S9S_MB_2U_LIB.S9S_MB_2U(SCH_1):PAGE214_I164@PURE_QUANTA.Q_RES(CHIPS)':
 'A': CDS_PINID='A';
NET_NAME
'PRSNT_CABLE_GPU_A3_ISO_R_N'
 '@S9S_MB_2U_LIB.S9S_MB_2U(SCH_1):PRSNT_CABLE_GPU_A3_ISO_R_N':
 C_SIGNAL='@s9s_mb_2u_lib.s9s_mb_2u(sch_1):prsnt_cable_gpu_a3_iso_r_n';
NODE_NAME     U181 20
 '@S9S_MB_2U_LIB.S9S_MB_2U(SCH_1):PAGE214_I66@PURE_QUANTA.PCA9539RPW(CHIPS)':
 'IO1_7': CDS_PINID='IO1_7';
NODE_NAME     R4802 2
 '@S9S_MB_2U_LIB.S9S_MB_2U(SCH_1):PAGE214_I164@PURE_QUANTA.Q_RES(CHIPS)':
 'B': CDS_PINID='B';
NET_NAME
'PRSNT_CABLE_GPU_A3_N'
 '@S9S_MB_2U_LIB.S9S_MB_2U(SCH_1):PRSNT_CABLE_GPU_A3_N':
 C_SIGNAL='@s9s_mb_2u_lib.s9s_mb_2u(sch_1):prsnt_cable_gpu_a3_n';
NODE_NAME     J108 N8
 '@S9S_MB_2U_LIB.S9S_MB_2U(SCH_1):PAGE320_I76@PURE_QUANTA.CONN112_10137002101LF(CHIPS)':
 'N8': CDS_PINID='N8';
NODE_NAME     Q154 2
 '@S9S_MB_2U_LIB.S9S_MB_2U(SCH_1):PAGE147_I71@PURE_QUANTA.MOSFET_NCH_DUAL(CHIPS)':
 'G1': CDS_PINID='G1';
NODE_NAME     R4798 2
 '@S9S_MB_2U_LIB.S9S_MB_2U(SCH_1):PAGE147_I75@PURE_QUANTA.Q_RES(CHIPS)':
 'B': CDS_PINID='B';
NODE_NAME     R4799 1
 '@S9S_MB_2U_LIB.S9S_MB_2U(SCH_1):PAGE147_I76@PURE_QUANTA.Q_RES(CHIPS)':
 'A': CDS_PINID='A';
NET_NAME
'PRSNT_CABLE_GPU_B3'
 '@S9S_MB_2U_LIB.S9S_MB_2U(SCH_1):PRSNT_CABLE_GPU_B3':
 C_SIGNAL='@s9s_mb_2u_lib.s9s_mb_2u(sch_1):prsnt_cable_gpu_b3';
NODE_NAME     Q132 5
 '@S9S_MB_2U_LIB.S9S_MB_2U(SCH_1):PAGE143_I35@PURE_QUANTA.MOSFET_NCH_DUAL(CHIPS)':
 'G2': CDS_PINID='G2';
NODE_NAME     R4126 2
 '@S9S_MB_2U_LIB.S9S_MB_2U(SCH_1):PAGE143_I43@PURE_QUANTA.Q_RES(CHIPS)':
 'B': CDS_PINID='B';
NODE_NAME     Q132 6
 '@S9S_MB_2U_LIB.S9S_MB_2U(SCH_1):PAGE143_I44@PURE_QUANTA.MOSFET_NCH_DUAL(CHIPS)':
 'D1': CDS_PINID='D1';
NET_NAME
'PRSNT_CABLE_GPU_B3_ISO_N'
 '@S9S_MB_2U_LIB.S9S_MB_2U(SCH_1):PRSNT_CABLE_GPU_B3_ISO_N':
 C_SIGNAL='@s9s_mb_2u_lib.s9s_mb_2u(sch_1):prsnt_cable_gpu_b3_iso_n';
NODE_NAME     Q132 3
 '@S9S_MB_2U_LIB.S9S_MB_2U(SCH_1):PAGE143_I35@PURE_QUANTA.MOSFET_NCH_DUAL(CHIPS)':
 'D2': CDS_PINID='D2';
NODE_NAME     R4129 2
 '@S9S_MB_2U_LIB.S9S_MB_2U(SCH_1):PAGE143_I36@PURE_QUANTA.Q_RES(CHIPS)':
 'B': CDS_PINID='B';
NODE_NAME     C2265 1
 '@S9S_MB_2U_LIB.S9S_MB_2U(SCH_1):PAGE143_I40@PURE_QUANTA.Q_CAP(CHIPS)':
 'A': CDS_PINID='A';
NODE_NAME     R4145 1
 '@S9S_MB_2U_LIB.S9S_MB_2U(SCH_1):PAGE312_I97@PURE_QUANTA.Q_RES(CHIPS)':
 'A': CDS_PINID='A';
NODE_NAME     R4573 2
 '@S9S_MB_2U_LIB.S9S_MB_2U(SCH_1):PAGE143_I140@PURE_QUANTA.Q_RES(CHIPS)':
 'B': CDS_PINID='B';
NODE_NAME     R4734 1
 '@S9S_MB_2U_LIB.S9S_MB_2U(SCH_1):PAGE214_I144@PURE_QUANTA.Q_RES(CHIPS)':
 'A': CDS_PINID='A';
NET_NAME
'PRSNT_CABLE_GPU_B3_ISO_R1_N'
 '@S9S_MB_2U_LIB.S9S_MB_2U(SCH_1):PRSNT_CABLE_GPU_B3_ISO_R1_N':
 C_SIGNAL='@s9s_mb_2u_lib.s9s_mb_2u(sch_1):prsnt_cable_gpu_b3_iso_r1_n';
NODE_NAME     U181 10
 '@S9S_MB_2U_LIB.S9S_MB_2U(SCH_1):PAGE214_I66@PURE_QUANTA.PCA9539RPW(CHIPS)':
 'IO0_6': CDS_PINID='IO0_6';
NODE_NAME     R4734 2
 '@S9S_MB_2U_LIB.S9S_MB_2U(SCH_1):PAGE214_I144@PURE_QUANTA.Q_RES(CHIPS)':
 'B': CDS_PINID='B';
NET_NAME
'PRSNT_CABLE_GPU_B3_ISO_R_N'
 '@S9S_MB_2U_LIB.S9S_MB_2U(SCH_1):PRSNT_CABLE_GPU_B3_ISO_R_N':
 C_SIGNAL='@s9s_mb_2u_lib.s9s_mb_2u(sch_1):prsnt_cable_gpu_b3_iso_r_n';
NODE_NAME     U249 AA11
 '@S9S_MB_2U_LIB.S9S_MB_2U(SCH_1):PAGE312_I1@PURE_QUANTA.LCMXO3LF9400C5BG484C(CHIPS)':
 'PB24A': CDS_PINID='PB24A';
NODE_NAME     R4145 2
 '@S9S_MB_2U_LIB.S9S_MB_2U(SCH_1):PAGE312_I97@PURE_QUANTA.Q_RES(CHIPS)':
 'B': CDS_PINID='B';
NET_NAME
'PRSNT_CABLE_GPU_B3_N'
 '@S9S_MB_2U_LIB.S9S_MB_2U(SCH_1):PRSNT_CABLE_GPU_B3_N':
 C_SIGNAL='@s9s_mb_2u_lib.s9s_mb_2u(sch_1):prsnt_cable_gpu_b3_n';
NODE_NAME     J109 N8
 '@S9S_MB_2U_LIB.S9S_MB_2U(SCH_1):PAGE319_I76@PURE_QUANTA.CONN112_10137002101LF(CHIPS)':
 'N8': CDS_PINID='N8';
NODE_NAME     Q132 2
 '@S9S_MB_2U_LIB.S9S_MB_2U(SCH_1):PAGE143_I44@PURE_QUANTA.MOSFET_NCH_DUAL(CHIPS)':
 'G1': CDS_PINID='G1';
NODE_NAME     R4122 1
 '@S9S_MB_2U_LIB.S9S_MB_2U(SCH_1):PAGE143_I49@PURE_QUANTA.Q_RES(CHIPS)':
 'A': CDS_PINID='A';
NODE_NAME     R4573 1
 '@S9S_MB_2U_LIB.S9S_MB_2U(SCH_1):PAGE143_I140@PURE_QUANTA.Q_RES(CHIPS)':
 'A': CDS_PINID='A';
NODE_NAME     R4121 2
 '@S9S_MB_2U_LIB.S9S_MB_2U(SCH_1):PAGE143_I143@PURE_QUANTA.Q_RES(CHIPS)':
 'B': CDS_PINID='B';
NET_NAME
'PRSNT_CABLE_SWB_B1'
 '@S9S_MB_2U_LIB.S9S_MB_2U(SCH_1):PRSNT_CABLE_SWB_B1':
 C_SIGNAL='@s9s_mb_2u_lib.s9s_mb_2u(sch_1):prsnt_cable_swb_b1';
NODE_NAME     Q153 5
 '@S9S_MB_2U_LIB.S9S_MB_2U(SCH_1):PAGE147_I51@PURE_QUANTA.MOSFET_NCH_DUAL(CHIPS)':
 'G2': CDS_PINID='G2';
NODE_NAME     R4739 2
 '@S9S_MB_2U_LIB.S9S_MB_2U(SCH_1):PAGE147_I54@PURE_QUANTA.Q_RES(CHIPS)':
 'B': CDS_PINID='B';
NODE_NAME     Q153 6
 '@S9S_MB_2U_LIB.S9S_MB_2U(SCH_1):PAGE147_I55@PURE_QUANTA.MOSFET_NCH_DUAL(CHIPS)':
 'D1': CDS_PINID='D1';
NET_NAME
'PRSNT_CABLE_SWB_B1_ISO_N'
 '@S9S_MB_2U_LIB.S9S_MB_2U(SCH_1):PRSNT_CABLE_SWB_B1_ISO_N':
 C_SIGNAL='@s9s_mb_2u_lib.s9s_mb_2u(sch_1):prsnt_cable_swb_b1_iso_n';
NODE_NAME     C2374 1
 '@S9S_MB_2U_LIB.S9S_MB_2U(SCH_1):PAGE147_I47@PURE_QUANTA.Q_CAP(CHIPS)':
 'A': CDS_PINID='A';
NODE_NAME     R4740 2
 '@S9S_MB_2U_LIB.S9S_MB_2U(SCH_1):PAGE147_I50@PURE_QUANTA.Q_RES(CHIPS)':
 'B': CDS_PINID='B';
NODE_NAME     Q153 3
 '@S9S_MB_2U_LIB.S9S_MB_2U(SCH_1):PAGE147_I51@PURE_QUANTA.MOSFET_NCH_DUAL(CHIPS)':
 'D2': CDS_PINID='D2';
NODE_NAME     R4741 1
 '@S9S_MB_2U_LIB.S9S_MB_2U(SCH_1):PAGE214_I156@PURE_QUANTA.Q_RES(CHIPS)':
 'A': CDS_PINID='A';
NET_NAME
'PRSNT_CABLE_SWB_B1_ISO_R_N'
 '@S9S_MB_2U_LIB.S9S_MB_2U(SCH_1):PRSNT_CABLE_SWB_B1_ISO_R_N':
 C_SIGNAL='@s9s_mb_2u_lib.s9s_mb_2u(sch_1):prsnt_cable_swb_b1_iso_r_n';
NODE_NAME     U181 14
 '@S9S_MB_2U_LIB.S9S_MB_2U(SCH_1):PAGE214_I66@PURE_QUANTA.PCA9539RPW(CHIPS)':
 'IO1_1': CDS_PINID='IO1_1';
NODE_NAME     R4741 2
 '@S9S_MB_2U_LIB.S9S_MB_2U(SCH_1):PAGE214_I156@PURE_QUANTA.Q_RES(CHIPS)':
 'B': CDS_PINID='B';
NET_NAME
'PRSNT_CABLE_SWB_B1_N'
 '@S9S_MB_2U_LIB.S9S_MB_2U(SCH_1):PRSNT_CABLE_SWB_B1_N':
 C_SIGNAL='@s9s_mb_2u_lib.s9s_mb_2u(sch_1):prsnt_cable_swb_b1_n';
NODE_NAME     J106 A1
 '@S9S_MB_2U_LIB.S9S_MB_2U(SCH_1):PAGE144_I65@PURE_QUANTA.CONN112_10137002101LF(CHIPS)':
 'A1': CDS_PINID='A1';
NODE_NAME     Q153 2
 '@S9S_MB_2U_LIB.S9S_MB_2U(SCH_1):PAGE147_I55@PURE_QUANTA.MOSFET_NCH_DUAL(CHIPS)':
 'G1': CDS_PINID='G1';
NODE_NAME     R4737 2
 '@S9S_MB_2U_LIB.S9S_MB_2U(SCH_1):PAGE147_I58@PURE_QUANTA.Q_RES(CHIPS)':
 'B': CDS_PINID='B';
NODE_NAME     R4738 1
 '@S9S_MB_2U_LIB.S9S_MB_2U(SCH_1):PAGE147_I60@PURE_QUANTA.Q_RES(CHIPS)':
 'A': CDS_PINID='A';
NET_NAME
'PRSNT_CABLE_SWB_B2'
 '@S9S_MB_2U_LIB.S9S_MB_2U(SCH_1):PRSNT_CABLE_SWB_B2':
 C_SIGNAL='@s9s_mb_2u_lib.s9s_mb_2u(sch_1):prsnt_cable_swb_b2';
NODE_NAME     Q152 5
 '@S9S_MB_2U_LIB.S9S_MB_2U(SCH_1):PAGE147_I26@PURE_QUANTA.MOSFET_NCH_DUAL(CHIPS)':
 'G2': CDS_PINID='G2';
NODE_NAME     R4732 2
 '@S9S_MB_2U_LIB.S9S_MB_2U(SCH_1):PAGE147_I36@PURE_QUANTA.Q_RES(CHIPS)':
 'B': CDS_PINID='B';
NODE_NAME     Q152 6
 '@S9S_MB_2U_LIB.S9S_MB_2U(SCH_1):PAGE147_I38@PURE_QUANTA.MOSFET_NCH_DUAL(CHIPS)':
 'D1': CDS_PINID='D1';
NET_NAME
'PRSNT_CABLE_SWB_B2_ISO_N'
 '@S9S_MB_2U_LIB.S9S_MB_2U(SCH_1):PRSNT_CABLE_SWB_B2_ISO_N':
 C_SIGNAL='@s9s_mb_2u_lib.s9s_mb_2u(sch_1):prsnt_cable_swb_b2_iso_n';
NODE_NAME     R4735 1
 '@S9S_MB_2U_LIB.S9S_MB_2U(SCH_1):PAGE214_I148@PURE_QUANTA.Q_RES(CHIPS)':
 'A': CDS_PINID='A';
NODE_NAME     C2373 1
 '@S9S_MB_2U_LIB.S9S_MB_2U(SCH_1):PAGE147_I22@PURE_QUANTA.Q_CAP(CHIPS)':
 'A': CDS_PINID='A';
NODE_NAME     R4733 2
 '@S9S_MB_2U_LIB.S9S_MB_2U(SCH_1):PAGE147_I25@PURE_QUANTA.Q_RES(CHIPS)':
 'B': CDS_PINID='B';
NODE_NAME     Q152 3
 '@S9S_MB_2U_LIB.S9S_MB_2U(SCH_1):PAGE147_I26@PURE_QUANTA.MOSFET_NCH_DUAL(CHIPS)':
 'D2': CDS_PINID='D2';
NET_NAME
'PRSNT_CABLE_SWB_B2_ISO_R_N'
 '@S9S_MB_2U_LIB.S9S_MB_2U(SCH_1):PRSNT_CABLE_SWB_B2_ISO_R_N':
 C_SIGNAL='@s9s_mb_2u_lib.s9s_mb_2u(sch_1):prsnt_cable_swb_b2_iso_r_n';
NODE_NAME     U181 11
 '@S9S_MB_2U_LIB.S9S_MB_2U(SCH_1):PAGE214_I66@PURE_QUANTA.PCA9539RPW(CHIPS)':
 'IO0_7': CDS_PINID='IO0_7';
NODE_NAME     R4735 2
 '@S9S_MB_2U_LIB.S9S_MB_2U(SCH_1):PAGE214_I148@PURE_QUANTA.Q_RES(CHIPS)':
 'B': CDS_PINID='B';
NET_NAME
'PRSNT_CABLE_SWB_B2_N'
 '@S9S_MB_2U_LIB.S9S_MB_2U(SCH_1):PRSNT_CABLE_SWB_B2_N':
 C_SIGNAL='@s9s_mb_2u_lib.s9s_mb_2u(sch_1):prsnt_cable_swb_b2_n';
NODE_NAME     J107 N2
 '@S9S_MB_2U_LIB.S9S_MB_2U(SCH_1):PAGE317_I58@PURE_QUANTA.CONN112_10137002101LF(CHIPS)':
 'N2': CDS_PINID='N2';
NODE_NAME     Q152 2
 '@S9S_MB_2U_LIB.S9S_MB_2U(SCH_1):PAGE147_I38@PURE_QUANTA.MOSFET_NCH_DUAL(CHIPS)':
 'G1': CDS_PINID='G1';
NODE_NAME     R4730 2
 '@S9S_MB_2U_LIB.S9S_MB_2U(SCH_1):PAGE147_I41@PURE_QUANTA.Q_RES(CHIPS)':
 'B': CDS_PINID='B';
NODE_NAME     R4731 1
 '@S9S_MB_2U_LIB.S9S_MB_2U(SCH_1):PAGE147_I42@PURE_QUANTA.Q_RES(CHIPS)':
 'A': CDS_PINID='A';
NET_NAME
'PRSNT_SWB'
 '@S9S_MB_2U_LIB.S9S_MB_2U(SCH_1):PRSNT_SWB':
 C_SIGNAL='@s9s_mb_2u_lib.s9s_mb_2u(sch_1):prsnt_swb';
NODE_NAME     Q151 5
 '@S9S_MB_2U_LIB.S9S_MB_2U(SCH_1):PAGE147_I20@PURE_QUANTA.MOSFET_NCH_DUAL(CHIPS)':
 'G2': CDS_PINID='G2';
NODE_NAME     R4725 2
 '@S9S_MB_2U_LIB.S9S_MB_2U(SCH_1):PAGE147_I28@PURE_QUANTA.Q_RES(CHIPS)':
 'B': CDS_PINID='B';
NODE_NAME     Q151 6
 '@S9S_MB_2U_LIB.S9S_MB_2U(SCH_1):PAGE147_I31@PURE_QUANTA.MOSFET_NCH_DUAL(CHIPS)':
 'D1': CDS_PINID='D1';
NET_NAME
'PRSNT_SWB_ISO_N'
 '@S9S_MB_2U_LIB.S9S_MB_2U(SCH_1):PRSNT_SWB_ISO_N':
 C_SIGNAL='@s9s_mb_2u_lib.s9s_mb_2u(sch_1):prsnt_swb_iso_n';
NODE_NAME     R4057 1
 '@S9S_MB_2U_LIB.S9S_MB_2U(SCH_1):PAGE312_I217@PURE_QUANTA.Q_RES(CHIPS)':
 'A': CDS_PINID='A';
NODE_NAME     R4728 1
 '@S9S_MB_2U_LIB.S9S_MB_2U(SCH_1):PAGE214_I137@PURE_QUANTA.Q_RES(CHIPS)':
 'A': CDS_PINID='A';
NODE_NAME     C2372 1
 '@S9S_MB_2U_LIB.S9S_MB_2U(SCH_1):PAGE147_I15@PURE_QUANTA.Q_CAP(CHIPS)':
 'A': CDS_PINID='A';
NODE_NAME     R4726 2
 '@S9S_MB_2U_LIB.S9S_MB_2U(SCH_1):PAGE147_I18@PURE_QUANTA.Q_RES(CHIPS)':
 'B': CDS_PINID='B';
NODE_NAME     Q151 3
 '@S9S_MB_2U_LIB.S9S_MB_2U(SCH_1):PAGE147_I20@PURE_QUANTA.MOSFET_NCH_DUAL(CHIPS)':
 'D2': CDS_PINID='D2';
NET_NAME
'PRSNT_SWB_ISO_R1_N'
 '@S9S_MB_2U_LIB.S9S_MB_2U(SCH_1):PRSNT_SWB_ISO_R1_N':
 C_SIGNAL='@s9s_mb_2u_lib.s9s_mb_2u(sch_1):prsnt_swb_iso_r1_n';
NODE_NAME     U181 8
 '@S9S_MB_2U_LIB.S9S_MB_2U(SCH_1):PAGE214_I66@PURE_QUANTA.PCA9539RPW(CHIPS)':
 'IO0_4': CDS_PINID='IO0_4';
NODE_NAME     R4728 2
 '@S9S_MB_2U_LIB.S9S_MB_2U(SCH_1):PAGE214_I137@PURE_QUANTA.Q_RES(CHIPS)':
 'B': CDS_PINID='B';
NET_NAME
'PRSNT_SWB_ISO_R_N'
 '@S9S_MB_2U_LIB.S9S_MB_2U(SCH_1):PRSNT_SWB_ISO_R_N':
 C_SIGNAL='@s9s_mb_2u_lib.s9s_mb_2u(sch_1):prsnt_swb_iso_r_n';
NODE_NAME     U249 Y9
 '@S9S_MB_2U_LIB.S9S_MB_2U(SCH_1):PAGE312_I1@PURE_QUANTA.LCMXO3LF9400C5BG484C(CHIPS)':
 'PB21C': CDS_PINID='PB21C';
NODE_NAME     R4057 2
 '@S9S_MB_2U_LIB.S9S_MB_2U(SCH_1):PAGE312_I217@PURE_QUANTA.Q_RES(CHIPS)':
 'B': CDS_PINID='B';
NET_NAME
'PRSNT_SWB_N'
 '@S9S_MB_2U_LIB.S9S_MB_2U(SCH_1):PRSNT_SWB_N':
 C_SIGNAL='@s9s_mb_2u_lib.s9s_mb_2u(sch_1):prsnt_swb_n';
NODE_NAME     J112 A7
 '@S9S_MB_2U_LIB.S9S_MB_2U(SCH_1):PAGE149_I75@PURE_QUANTA.CONN160_10131762101LF(CHIPS)':
 'A7': CDS_PINID='A7';
NODE_NAME     Q151 2
 '@S9S_MB_2U_LIB.S9S_MB_2U(SCH_1):PAGE147_I31@PURE_QUANTA.MOSFET_NCH_DUAL(CHIPS)':
 'G1': CDS_PINID='G1';
NODE_NAME     R4727 2
 '@S9S_MB_2U_LIB.S9S_MB_2U(SCH_1):PAGE147_I33@PURE_QUANTA.Q_RES(CHIPS)':
 'B': CDS_PINID='B';
NODE_NAME     R4724 1
 '@S9S_MB_2U_LIB.S9S_MB_2U(SCH_1):PAGE147_I34@PURE_QUANTA.Q_RES(CHIPS)':
 'A': CDS_PINID='A';
NET_NAME
'PUD_PCH_BOOT_MODE_CPU0'
 '@S9S_MB_2U_LIB.S9S_MB_2U(SCH_1):PUD_PCH_BOOT_MODE_CPU0':
 C_SIGNAL='@s9s_mb_2u_lib.s9s_mb_2u(sch_1):pud_pch_boot_mode_cpu0';
NODE_NAME     U2 CF61
 '@S9S_MB_2U_LIB.S9S_MB_2U(SCH_1):PAGE15_I1@PURE_QUANTA.SOCKET4677_AZIF0045P001C01CS(CHIPS)':
 'TEST_6': CDS_PINID='TEST_6';
NODE_NAME     R252 2
 '@S9S_MB_2U_LIB.S9S_MB_2U(SCH_1):PAGE120_I30@PURE_QUANTA.Q_RES(CHIPS)':
 'B': CDS_PINID='B';
NET_NAME
'PUD_PCH_BOOT_MODE_CPU1'
 '@S9S_MB_2U_LIB.S9S_MB_2U(SCH_1):PUD_PCH_BOOT_MODE_CPU1':
 C_SIGNAL='@s9s_mb_2u_lib.s9s_mb_2u(sch_1):pud_pch_boot_mode_cpu1';
NODE_NAME     U1 CF61
 '@S9S_MB_2U_LIB.S9S_MB_2U(SCH_1):PAGE46_I5@PURE_QUANTA.SOCKET4677_AZIF0045P001C01CS(CHIPS)':
 'TEST_6': CDS_PINID='TEST_6';
NODE_NAME     R258 2
 '@S9S_MB_2U_LIB.S9S_MB_2U(SCH_1):PAGE120_I44@PURE_QUANTA.Q_RES(CHIPS)':
 'B': CDS_PINID='B';
NET_NAME
'PUD_XTAL_CPU0_MODE0'
 '@S9S_MB_2U_LIB.S9S_MB_2U(SCH_1):PUD_XTAL_CPU0_MODE0':
 C_SIGNAL='@s9s_mb_2u_lib.s9s_mb_2u(sch_1):pud_xtal_cpu0_mode0';
NODE_NAME     U2 CL72
 '@S9S_MB_2U_LIB.S9S_MB_2U(SCH_1):PAGE13_I57@PURE_QUANTA.SOCKET4677_AZIF0045P001C01CS(CHIPS)':
 'RSVD120': CDS_PINID='RSVD120';
NODE_NAME     R1232 2
 '@S9S_MB_2U_LIB.S9S_MB_2U(SCH_1):PAGE119_I156@PURE_QUANTA.Q_RES(CHIPS)':
 'B': CDS_PINID='B';
NODE_NAME     R1238 2
 '@S9S_MB_2U_LIB.S9S_MB_2U(SCH_1):PAGE119_I161@PURE_QUANTA.Q_RES(CHIPS)':
 'B': CDS_PINID='B';
NET_NAME
'PUD_XTAL_CPU0_MODE1'
 '@S9S_MB_2U_LIB.S9S_MB_2U(SCH_1):PUD_XTAL_CPU0_MODE1':
 C_SIGNAL='@s9s_mb_2u_lib.s9s_mb_2u(sch_1):pud_xtal_cpu0_mode1';
NODE_NAME     U2 CJ72
 '@S9S_MB_2U_LIB.S9S_MB_2U(SCH_1):PAGE13_I57@PURE_QUANTA.SOCKET4677_AZIF0045P001C01CS(CHIPS)':
 'RSVD108': CDS_PINID='RSVD108';
NODE_NAME     R1233 2
 '@S9S_MB_2U_LIB.S9S_MB_2U(SCH_1):PAGE119_I158@PURE_QUANTA.Q_RES(CHIPS)':
 'B': CDS_PINID='B';
NODE_NAME     R1239 2
 '@S9S_MB_2U_LIB.S9S_MB_2U(SCH_1):PAGE119_I163@PURE_QUANTA.Q_RES(CHIPS)':
 'B': CDS_PINID='B';
NET_NAME
'PUD_XTAL_CPU1_MODE0'
 '@S9S_MB_2U_LIB.S9S_MB_2U(SCH_1):PUD_XTAL_CPU1_MODE0':
 C_SIGNAL='@s9s_mb_2u_lib.s9s_mb_2u(sch_1):pud_xtal_cpu1_mode0';
NODE_NAME     U1 CL72
 '@S9S_MB_2U_LIB.S9S_MB_2U(SCH_1):PAGE44_I51@PURE_QUANTA.SOCKET4677_AZIF0045P001C01CS(CHIPS)':
 'RSVD120': CDS_PINID='RSVD120';
NODE_NAME     R1229 2
 '@S9S_MB_2U_LIB.S9S_MB_2U(SCH_1):PAGE119_I169@PURE_QUANTA.Q_RES(CHIPS)':
 'B': CDS_PINID='B';
NODE_NAME     R1235 2
 '@S9S_MB_2U_LIB.S9S_MB_2U(SCH_1):PAGE119_I176@PURE_QUANTA.Q_RES(CHIPS)':
 'B': CDS_PINID='B';
NET_NAME
'PUD_XTAL_CPU1_MODE1'
 '@S9S_MB_2U_LIB.S9S_MB_2U(SCH_1):PUD_XTAL_CPU1_MODE1':
 C_SIGNAL='@s9s_mb_2u_lib.s9s_mb_2u(sch_1):pud_xtal_cpu1_mode1';
NODE_NAME     U1 CJ72
 '@S9S_MB_2U_LIB.S9S_MB_2U(SCH_1):PAGE44_I51@PURE_QUANTA.SOCKET4677_AZIF0045P001C01CS(CHIPS)':
 'RSVD108': CDS_PINID='RSVD108';
NODE_NAME     R1230 2
 '@S9S_MB_2U_LIB.S9S_MB_2U(SCH_1):PAGE119_I170@PURE_QUANTA.Q_RES(CHIPS)':
 'B': CDS_PINID='B';
NODE_NAME     R1236 2
 '@S9S_MB_2U_LIB.S9S_MB_2U(SCH_1):PAGE119_I177@PURE_QUANTA.Q_RES(CHIPS)':
 'B': CDS_PINID='B';
NET_NAME
'PULL_FPGA_PB46A'
 '@S9S_MB_2U_LIB.S9S_MB_2U(SCH_1):PULL_FPGA_PB46A':
 C_SIGNAL='@s9s_mb_2u_lib.s9s_mb_2u(sch_1):pull_fpga_pb46a';
NODE_NAME     U249 AB21
 '@S9S_MB_2U_LIB.S9S_MB_2U(SCH_1):PAGE312_I1@PURE_QUANTA.LCMXO3LF9400C5BG484C(CHIPS)':
 'PB46A||SN': CDS_PINID='\pb46a||sn\';
NODE_NAME     R4086 2
 '@S9S_MB_2U_LIB.S9S_MB_2U(SCH_1):PAGE312_I86@PURE_QUANTA.Q_RES(CHIPS)':
 'B': CDS_PINID='B';
NET_NAME
'PU_ACPRESENT'
 '@S9S_MB_2U_LIB.S9S_MB_2U(SCH_1):PU_ACPRESENT':
 C_SIGNAL='@s9s_mb_2u_lib.s9s_mb_2u(sch_1):pu_acpresent';
NODE_NAME     U4 AN7
 '@S9S_MB_2U_LIB.S9S_MB_2U(SCH_1):PAGE174_I36@PURE_QUANTA.EMMITSBURG_REV0P9(CHIPS)':
 'ACPRESENT': CDS_PINID='ACPRESENT';
NODE_NAME     R1198 2
 '@S9S_MB_2U_LIB.S9S_MB_2U(SCH_1):PAGE174_I48@PURE_QUANTA.Q_RES(CHIPS)':
 'B': CDS_PINID='B';
NET_NAME
'PU_BIOS_RCVR_BOOT'
 '@S9S_MB_2U_LIB.S9S_MB_2U(SCH_1):PU_BIOS_RCVR_BOOT':
 C_SIGNAL='@s9s_mb_2u_lib.s9s_mb_2u(sch_1):pu_bios_rcvr_boot';
NODE_NAME     R1317 2
 '@S9S_MB_2U_LIB.S9S_MB_2U(SCH_1):PAGE189_I88@PURE_QUANTA.Q_RES(CHIPS)':
 'B': CDS_PINID='B';
NODE_NAME     J104 3
 '@S9S_MB_2U_LIB.S9S_MB_2U(SCH_1):PAGE189_I134@PURE_QUANTA.CONN14_210HP207GBR1(CHIPS)':
 '3': CDS_PINID='\3\';
NET_NAME
'PU_BUFFER_HDD_ACTIVITY'
 '@S9S_MB_2U_LIB.S9S_MB_2U(SCH_1):PU_BUFFER_HDD_ACTIVITY':
 C_SIGNAL='@s9s_mb_2u_lib.s9s_mb_2u(sch_1):pu_buffer_hdd_activity';
NODE_NAME     R5377 2
 '@S9S_MB_2U_LIB.S9S_MB_2U(SCH_1):PAGE182_I312@PURE_QUANTA.Q_RES(CHIPS)':
 'B': CDS_PINID='B';
NODE_NAME     U239 1
 '@S9S_MB_2U_LIB.S9S_MB_2U(SCH_1):PAGE182_I315@PURE_QUANTA.74LVC1G126SE7(CHIPS)':
 'OE': CDS_PINID='OE';
NET_NAME
'PU_CK440_SHFT_LD_N'
 '@S9S_MB_2U_LIB.S9S_MB_2U(SCH_1):PU_CK440_SHFT_LD_N':
 C_SIGNAL='@s9s_mb_2u_lib.s9s_mb_2u(sch_1):pu_ck440_shft_ld_n';
NODE_NAME     U13 B42
 '@S9S_MB_2U_LIB.S9S_MB_2U(SCH_1):PAGE197_I180@PURE_QUANTA.9SQ440NQQI8(CHIPS)':
 'SHFT_LD#': CDS_PINID='\shft_ld#\';
NODE_NAME     R1204 2
 '@S9S_MB_2U_LIB.S9S_MB_2U(SCH_1):PAGE197_I273@PURE_QUANTA.Q_RES(CHIPS)':
 'B': CDS_PINID='B';
NODE_NAME     R1267 1
 '@S9S_MB_2U_LIB.S9S_MB_2U(SCH_1):PAGE197_I276@PURE_QUANTA.Q_RES(CHIPS)':
 'A': CDS_PINID='A';
NET_NAME
'PU_CLK25M_OSC_FPGA_EN'
 '@S9S_MB_2U_LIB.S9S_MB_2U(SCH_1):PU_CLK25M_OSC_FPGA_EN':
 C_SIGNAL='@s9s_mb_2u_lib.s9s_mb_2u(sch_1):pu_clk25m_osc_fpga_en';
NODE_NAME     OSC2 1
 '@S9S_MB_2U_LIB.S9S_MB_2U(SCH_1):PAGE313_I127@PURE_QUANTA.Q_OSC4P(CHIPS)':
 'OE': CDS_PINID='OE';
NODE_NAME     R1099 2
 '@S9S_MB_2U_LIB.S9S_MB_2U(SCH_1):PAGE313_I129@PURE_QUANTA.Q_RES(CHIPS)':
 'B': CDS_PINID='B';
NET_NAME
'PU_CLK_BUF_ISO_EN'
 '@S9S_MB_2U_LIB.S9S_MB_2U(SCH_1):PU_CLK_BUF_ISO_EN':
 C_SIGNAL='@s9s_mb_2u_lib.s9s_mb_2u(sch_1):pu_clk_buf_iso_en';
NODE_NAME     U315 5
 '@S9S_MB_2U_LIB.S9S_MB_2U(SCH_1):PAGE225_I17@PURE_QUANTA.PCA9617ADP(CHIPS)':
 'EN': CDS_PINID='EN';
NODE_NAME     R4500 2
 '@S9S_MB_2U_LIB.S9S_MB_2U(SCH_1):PAGE225_I32@PURE_QUANTA.Q_RES(CHIPS)':
 'B': CDS_PINID='B';
NET_NAME
'PU_CLK_PFT_LOST_N'
 '@S9S_MB_2U_LIB.S9S_MB_2U(SCH_1):PU_CLK_PFT_LOST_N':
 C_SIGNAL='@s9s_mb_2u_lib.s9s_mb_2u(sch_1):pu_clk_pft_lost_n';
NODE_NAME     U13 B4
 '@S9S_MB_2U_LIB.S9S_MB_2U(SCH_1):PAGE197_I180@PURE_QUANTA.9SQ440NQQI8(CHIPS)':
 'PFT_LOST#': CDS_PINID='\pft_lost#\';
NODE_NAME     R1958 2
 '@S9S_MB_2U_LIB.S9S_MB_2U(SCH_1):PAGE197_I303@PURE_QUANTA.Q_RES(CHIPS)':
 'B': CDS_PINID='B';
NET_NAME
'PU_CPU0_FRMAGENT'
 '@S9S_MB_2U_LIB.S9S_MB_2U(SCH_1):PU_CPU0_FRMAGENT':
 C_SIGNAL='@s9s_mb_2u_lib.s9s_mb_2u(sch_1):pu_cpu0_frmagent';
NODE_NAME     U2 AU17
 '@S9S_MB_2U_LIB.S9S_MB_2U(SCH_1):PAGE13_I57@PURE_QUANTA.SOCKET4677_AZIF0045P001C01CS(CHIPS)':
 'FRMAGENT': CDS_PINID='FRMAGENT';
NODE_NAME     R277 2
 '@S9S_MB_2U_LIB.S9S_MB_2U(SCH_1):PAGE119_I62@PURE_QUANTA.Q_RES(CHIPS)':
 'B': CDS_PINID='B';
NET_NAME
'PU_CPU0_LEGACY_SKT'
 '@S9S_MB_2U_LIB.S9S_MB_2U(SCH_1):PU_CPU0_LEGACY_SKT':
 C_SIGNAL='@s9s_mb_2u_lib.s9s_mb_2u(sch_1):pu_cpu0_legacy_skt';
NODE_NAME     U2 CY59
 '@S9S_MB_2U_LIB.S9S_MB_2U(SCH_1):PAGE13_I57@PURE_QUANTA.SOCKET4677_AZIF0045P001C01CS(CHIPS)':
 'LEGACY_SKT': CDS_PINID='LEGACY_SKT';
NODE_NAME     R282 2
 '@S9S_MB_2U_LIB.S9S_MB_2U(SCH_1):PAGE119_I53@PURE_QUANTA.Q_RES(CHIPS)':
 'B': CDS_PINID='B';
NET_NAME
'PU_CPU0_SAFE_MODE_BOOT'
 '@S9S_MB_2U_LIB.S9S_MB_2U(SCH_1):PU_CPU0_SAFE_MODE_BOOT':
 C_SIGNAL='@s9s_mb_2u_lib.s9s_mb_2u(sch_1):pu_cpu0_safe_mode_boot';
NODE_NAME     U2 AU23
 '@S9S_MB_2U_LIB.S9S_MB_2U(SCH_1):PAGE13_I57@PURE_QUANTA.SOCKET4677_AZIF0045P001C01CS(CHIPS)':
 'SAFE_MODE_BOOT': CDS_PINID='SAFE_MODE_BOOT';
NODE_NAME     R276 2
 '@S9S_MB_2U_LIB.S9S_MB_2U(SCH_1):PAGE119_I66@PURE_QUANTA.Q_RES(CHIPS)':
 'B': CDS_PINID='B';
NET_NAME
'PU_CPU0_SOCKET_ID0'
 '@S9S_MB_2U_LIB.S9S_MB_2U(SCH_1):PU_CPU0_SOCKET_ID0':
 C_SIGNAL='@s9s_mb_2u_lib.s9s_mb_2u(sch_1):pu_cpu0_socket_id0';
NODE_NAME     U2 CW60
 '@S9S_MB_2U_LIB.S9S_MB_2U(SCH_1):PAGE13_I57@PURE_QUANTA.SOCKET4677_AZIF0045P001C01CS(CHIPS)':
 'SOCKET_ID0': CDS_PINID='SOCKET_ID0';
NODE_NAME     R279 2
 '@S9S_MB_2U_LIB.S9S_MB_2U(SCH_1):PAGE119_I54@PURE_QUANTA.Q_RES(CHIPS)':
 'B': CDS_PINID='B';
NET_NAME
'PU_CPU0_SOCKET_ID1'
 '@S9S_MB_2U_LIB.S9S_MB_2U(SCH_1):PU_CPU0_SOCKET_ID1':
 C_SIGNAL='@s9s_mb_2u_lib.s9s_mb_2u(sch_1):pu_cpu0_socket_id1';
NODE_NAME     U2 CY61
 '@S9S_MB_2U_LIB.S9S_MB_2U(SCH_1):PAGE13_I57@PURE_QUANTA.SOCKET4677_AZIF0045P001C01CS(CHIPS)':
 'SOCKET_ID1': CDS_PINID='SOCKET_ID1';
NODE_NAME     R280 2
 '@S9S_MB_2U_LIB.S9S_MB_2U(SCH_1):PAGE119_I57@PURE_QUANTA.Q_RES(CHIPS)':
 'B': CDS_PINID='B';
NET_NAME
'PU_CPU0_SOCKET_ID2'
 '@S9S_MB_2U_LIB.S9S_MB_2U(SCH_1):PU_CPU0_SOCKET_ID2':
 C_SIGNAL='@s9s_mb_2u_lib.s9s_mb_2u(sch_1):pu_cpu0_socket_id2';
NODE_NAME     U2 CT61
 '@S9S_MB_2U_LIB.S9S_MB_2U(SCH_1):PAGE13_I57@PURE_QUANTA.SOCKET4677_AZIF0045P001C01CS(CHIPS)':
 'SOCKET_ID2': CDS_PINID='SOCKET_ID2';
NODE_NAME     R281 2
 '@S9S_MB_2U_LIB.S9S_MB_2U(SCH_1):PAGE119_I58@PURE_QUANTA.Q_RES(CHIPS)':
 'B': CDS_PINID='B';
NET_NAME
'PU_CPU0_TXT_AGENT'
 '@S9S_MB_2U_LIB.S9S_MB_2U(SCH_1):PU_CPU0_TXT_AGENT':
 C_SIGNAL='@s9s_mb_2u_lib.s9s_mb_2u(sch_1):pu_cpu0_txt_agent';
NODE_NAME     U2 BT26
 '@S9S_MB_2U_LIB.S9S_MB_2U(SCH_1):PAGE13_I57@PURE_QUANTA.SOCKET4677_AZIF0045P001C01CS(CHIPS)':
 'TXT_AGENT': CDS_PINID='TXT_AGENT';
NODE_NAME     R275 2
 '@S9S_MB_2U_LIB.S9S_MB_2U(SCH_1):PAGE119_I68@PURE_QUANTA.Q_RES(CHIPS)':
 'B': CDS_PINID='B';
NET_NAME
'PU_CPU0_UPI0_AC_COUPLING'
 '@S9S_MB_2U_LIB.S9S_MB_2U(SCH_1):PU_CPU0_UPI0_AC_COUPLING':
 C_SIGNAL='@s9s_mb_2u_lib.s9s_mb_2u(sch_1):pu_cpu0_upi0_ac_coupling';
NODE_NAME     U2 BA23
 '@S9S_MB_2U_LIB.S9S_MB_2U(SCH_1):PAGE19_I1@PURE_QUANTA.SOCKET4677_AZIF0045P001C01CS(CHIPS)':
 'UPI0_AC_COUPLING': CDS_PINID='UPI0_AC_COUPLING';
NODE_NAME     R94 2
 '@S9S_MB_2U_LIB.S9S_MB_2U(SCH_1):PAGE126_I25@PURE_QUANTA.Q_RES(CHIPS)':
 'B': CDS_PINID='B';
NET_NAME
'PU_CPU0_UPI1_AC_COUPLING'
 '@S9S_MB_2U_LIB.S9S_MB_2U(SCH_1):PU_CPU0_UPI1_AC_COUPLING':
 C_SIGNAL='@s9s_mb_2u_lib.s9s_mb_2u(sch_1):pu_cpu0_upi1_ac_coupling';
NODE_NAME     U2 CW19
 '@S9S_MB_2U_LIB.S9S_MB_2U(SCH_1):PAGE19_I1@PURE_QUANTA.SOCKET4677_AZIF0045P001C01CS(CHIPS)':
 'UPI1_AC_COUPLING': CDS_PINID='UPI1_AC_COUPLING';
NODE_NAME     R95 2
 '@S9S_MB_2U_LIB.S9S_MB_2U(SCH_1):PAGE126_I23@PURE_QUANTA.Q_RES(CHIPS)':
 'B': CDS_PINID='B';
NET_NAME
'PU_CPU0_UPI2_AC_COUPLING'
 '@S9S_MB_2U_LIB.S9S_MB_2U(SCH_1):PU_CPU0_UPI2_AC_COUPLING':
 C_SIGNAL='@s9s_mb_2u_lib.s9s_mb_2u(sch_1):pu_cpu0_upi2_ac_coupling';
NODE_NAME     U2 BB65
 '@S9S_MB_2U_LIB.S9S_MB_2U(SCH_1):PAGE19_I1@PURE_QUANTA.SOCKET4677_AZIF0045P001C01CS(CHIPS)':
 'UPI2_AC_COUPLING': CDS_PINID='UPI2_AC_COUPLING';
NODE_NAME     R96 2
 '@S9S_MB_2U_LIB.S9S_MB_2U(SCH_1):PAGE126_I22@PURE_QUANTA.Q_RES(CHIPS)':
 'B': CDS_PINID='B';
NET_NAME
'PU_CPU0_UPI3_AC_COUPLING'
 '@S9S_MB_2U_LIB.S9S_MB_2U(SCH_1):PU_CPU0_UPI3_AC_COUPLING':
 C_SIGNAL='@s9s_mb_2u_lib.s9s_mb_2u(sch_1):pu_cpu0_upi3_ac_coupling';
NODE_NAME     U2 CK71
 '@S9S_MB_2U_LIB.S9S_MB_2U(SCH_1):PAGE19_I1@PURE_QUANTA.SOCKET4677_AZIF0045P001C01CS(CHIPS)':
 'UPI3_AC_COUPLING': CDS_PINID='UPI3_AC_COUPLING';
NODE_NAME     R97 2
 '@S9S_MB_2U_LIB.S9S_MB_2U(SCH_1):PAGE126_I114@PURE_QUANTA.Q_RES(CHIPS)':
 'B': CDS_PINID='B';
NET_NAME
'PU_CPU1_FRMAGENT'
 '@S9S_MB_2U_LIB.S9S_MB_2U(SCH_1):PU_CPU1_FRMAGENT':
 C_SIGNAL='@s9s_mb_2u_lib.s9s_mb_2u(sch_1):pu_cpu1_frmagent';
NODE_NAME     U1 AU17
 '@S9S_MB_2U_LIB.S9S_MB_2U(SCH_1):PAGE44_I51@PURE_QUANTA.SOCKET4677_AZIF0045P001C01CS(CHIPS)':
 'FRMAGENT': CDS_PINID='FRMAGENT';
NODE_NAME     R263 2
 '@S9S_MB_2U_LIB.S9S_MB_2U(SCH_1):PAGE119_I125@PURE_QUANTA.Q_RES(CHIPS)':
 'B': CDS_PINID='B';
NET_NAME
'PU_CPU1_LEGACY_SKT'
 '@S9S_MB_2U_LIB.S9S_MB_2U(SCH_1):PU_CPU1_LEGACY_SKT':
 C_SIGNAL='@s9s_mb_2u_lib.s9s_mb_2u(sch_1):pu_cpu1_legacy_skt';
NODE_NAME     U1 CY59
 '@S9S_MB_2U_LIB.S9S_MB_2U(SCH_1):PAGE44_I51@PURE_QUANTA.SOCKET4677_AZIF0045P001C01CS(CHIPS)':
 'LEGACY_SKT': CDS_PINID='LEGACY_SKT';
NODE_NAME     R268 2
 '@S9S_MB_2U_LIB.S9S_MB_2U(SCH_1):PAGE119_I94@PURE_QUANTA.Q_RES(CHIPS)':
 'B': CDS_PINID='B';
NET_NAME
'PU_CPU1_SAFE_MODE_BOOT'
 '@S9S_MB_2U_LIB.S9S_MB_2U(SCH_1):PU_CPU1_SAFE_MODE_BOOT':
 C_SIGNAL='@s9s_mb_2u_lib.s9s_mb_2u(sch_1):pu_cpu1_safe_mode_boot';
NODE_NAME     U1 AU23
 '@S9S_MB_2U_LIB.S9S_MB_2U(SCH_1):PAGE44_I51@PURE_QUANTA.SOCKET4677_AZIF0045P001C01CS(CHIPS)':
 'SAFE_MODE_BOOT': CDS_PINID='SAFE_MODE_BOOT';
NODE_NAME     R262 2
 '@S9S_MB_2U_LIB.S9S_MB_2U(SCH_1):PAGE119_I100@PURE_QUANTA.Q_RES(CHIPS)':
 'B': CDS_PINID='B';
NET_NAME
'PU_CPU1_SOCKET_ID0'
 '@S9S_MB_2U_LIB.S9S_MB_2U(SCH_1):PU_CPU1_SOCKET_ID0':
 C_SIGNAL='@s9s_mb_2u_lib.s9s_mb_2u(sch_1):pu_cpu1_socket_id0';
NODE_NAME     U1 CW60
 '@S9S_MB_2U_LIB.S9S_MB_2U(SCH_1):PAGE44_I51@PURE_QUANTA.SOCKET4677_AZIF0045P001C01CS(CHIPS)':
 'SOCKET_ID0': CDS_PINID='SOCKET_ID0';
NODE_NAME     R265 2
 '@S9S_MB_2U_LIB.S9S_MB_2U(SCH_1):PAGE119_I97@PURE_QUANTA.Q_RES(CHIPS)':
 'B': CDS_PINID='B';
NET_NAME
'PU_CPU1_SOCKET_ID1'
 '@S9S_MB_2U_LIB.S9S_MB_2U(SCH_1):PU_CPU1_SOCKET_ID1':
 C_SIGNAL='@s9s_mb_2u_lib.s9s_mb_2u(sch_1):pu_cpu1_socket_id1';
NODE_NAME     U1 CY61
 '@S9S_MB_2U_LIB.S9S_MB_2U(SCH_1):PAGE44_I51@PURE_QUANTA.SOCKET4677_AZIF0045P001C01CS(CHIPS)':
 'SOCKET_ID1': CDS_PINID='SOCKET_ID1';
NODE_NAME     R266 2
 '@S9S_MB_2U_LIB.S9S_MB_2U(SCH_1):PAGE119_I96@PURE_QUANTA.Q_RES(CHIPS)':
 'B': CDS_PINID='B';
NET_NAME
'PU_CPU1_SOCKET_ID2'
 '@S9S_MB_2U_LIB.S9S_MB_2U(SCH_1):PU_CPU1_SOCKET_ID2':
 C_SIGNAL='@s9s_mb_2u_lib.s9s_mb_2u(sch_1):pu_cpu1_socket_id2';
NODE_NAME     U1 CT61
 '@S9S_MB_2U_LIB.S9S_MB_2U(SCH_1):PAGE44_I51@PURE_QUANTA.SOCKET4677_AZIF0045P001C01CS(CHIPS)':
 'SOCKET_ID2': CDS_PINID='SOCKET_ID2';
NODE_NAME     R267 2
 '@S9S_MB_2U_LIB.S9S_MB_2U(SCH_1):PAGE119_I95@PURE_QUANTA.Q_RES(CHIPS)':
 'B': CDS_PINID='B';
NET_NAME
'PU_CPU1_TXT_AGENT'
 '@S9S_MB_2U_LIB.S9S_MB_2U(SCH_1):PU_CPU1_TXT_AGENT':
 C_SIGNAL='@s9s_mb_2u_lib.s9s_mb_2u(sch_1):pu_cpu1_txt_agent';
NODE_NAME     U1 BT26
 '@S9S_MB_2U_LIB.S9S_MB_2U(SCH_1):PAGE44_I51@PURE_QUANTA.SOCKET4677_AZIF0045P001C01CS(CHIPS)':
 'TXT_AGENT': CDS_PINID='TXT_AGENT';
NODE_NAME     R261 2
 '@S9S_MB_2U_LIB.S9S_MB_2U(SCH_1):PAGE119_I101@PURE_QUANTA.Q_RES(CHIPS)':
 'B': CDS_PINID='B';
NET_NAME
'PU_CPU1_UPI0_AC_COUPLING'
 '@S9S_MB_2U_LIB.S9S_MB_2U(SCH_1):PU_CPU1_UPI0_AC_COUPLING':
 C_SIGNAL='@s9s_mb_2u_lib.s9s_mb_2u(sch_1):pu_cpu1_upi0_ac_coupling';
NODE_NAME     U1 BA23
 '@S9S_MB_2U_LIB.S9S_MB_2U(SCH_1):PAGE50_I23@PURE_QUANTA.SOCKET4677_AZIF0045P001C01CS(CHIPS)':
 'UPI0_AC_COUPLING': CDS_PINID='UPI0_AC_COUPLING';
NODE_NAME     R90 2
 '@S9S_MB_2U_LIB.S9S_MB_2U(SCH_1):PAGE126_I135@PURE_QUANTA.Q_RES(CHIPS)':
 'B': CDS_PINID='B';
NET_NAME
'PU_CPU1_UPI1_AC_COUPLING'
 '@S9S_MB_2U_LIB.S9S_MB_2U(SCH_1):PU_CPU1_UPI1_AC_COUPLING':
 C_SIGNAL='@s9s_mb_2u_lib.s9s_mb_2u(sch_1):pu_cpu1_upi1_ac_coupling';
NODE_NAME     U1 CW19
 '@S9S_MB_2U_LIB.S9S_MB_2U(SCH_1):PAGE50_I23@PURE_QUANTA.SOCKET4677_AZIF0045P001C01CS(CHIPS)':
 'UPI1_AC_COUPLING': CDS_PINID='UPI1_AC_COUPLING';
NODE_NAME     R91 2
 '@S9S_MB_2U_LIB.S9S_MB_2U(SCH_1):PAGE126_I136@PURE_QUANTA.Q_RES(CHIPS)':
 'B': CDS_PINID='B';
NET_NAME
'PU_CPU1_UPI2_AC_COUPLING'
 '@S9S_MB_2U_LIB.S9S_MB_2U(SCH_1):PU_CPU1_UPI2_AC_COUPLING':
 C_SIGNAL='@s9s_mb_2u_lib.s9s_mb_2u(sch_1):pu_cpu1_upi2_ac_coupling';
NODE_NAME     U1 BB65
 '@S9S_MB_2U_LIB.S9S_MB_2U(SCH_1):PAGE50_I23@PURE_QUANTA.SOCKET4677_AZIF0045P001C01CS(CHIPS)':
 'UPI2_AC_COUPLING': CDS_PINID='UPI2_AC_COUPLING';
NODE_NAME     R92 2
 '@S9S_MB_2U_LIB.S9S_MB_2U(SCH_1):PAGE126_I140@PURE_QUANTA.Q_RES(CHIPS)':
 'B': CDS_PINID='B';
NET_NAME
'PU_CPU1_UPI3_AC_COUPLING'
 '@S9S_MB_2U_LIB.S9S_MB_2U(SCH_1):PU_CPU1_UPI3_AC_COUPLING':
 C_SIGNAL='@s9s_mb_2u_lib.s9s_mb_2u(sch_1):pu_cpu1_upi3_ac_coupling';
NODE_NAME     U1 CK71
 '@S9S_MB_2U_LIB.S9S_MB_2U(SCH_1):PAGE50_I23@PURE_QUANTA.SOCKET4677_AZIF0045P001C01CS(CHIPS)':
 'UPI3_AC_COUPLING': CDS_PINID='UPI3_AC_COUPLING';
NODE_NAME     R93 2
 '@S9S_MB_2U_LIB.S9S_MB_2U(SCH_1):PAGE126_I141@PURE_QUANTA.Q_RES(CHIPS)':
 'B': CDS_PINID='B';
NET_NAME
'PU_E1S_0_DUALPORT_EN_N'
 '@S9S_MB_2U_LIB.S9S_MB_2U(SCH_1):PU_E1S_0_DUALPORT_EN_N':
 C_SIGNAL='@s9s_mb_2u_lib.s9s_mb_2u(sch_1):pu_e1s_0_dualport_en_n';
NODE_NAME     R2317 2
 '@S9S_MB_2U_LIB.S9S_MB_2U(SCH_1):PAGE297_I264@PURE_QUANTA.Q_RES(CHIPS)':
 'B': CDS_PINID='B';
NODE_NAME     J90 B9
 '@S9S_MB_2U_LIB.S9S_MB_2U(SCH_1):PAGE297_I318@PURE_QUANTA.SCONN56_123276793(CHIPS)':
 'DUALPORTEN#': CDS_PINID='\dualporten#\';
NET_NAME
'PU_ESPI_ENABLE_STRAP'
 '@S9S_MB_2U_LIB.S9S_MB_2U(SCH_1):PU_ESPI_ENABLE_STRAP':
 C_SIGNAL='@s9s_mb_2u_lib.s9s_mb_2u(sch_1):pu_espi_enable_strap';
NODE_NAME     R2133 2
 '@S9S_MB_2U_LIB.S9S_MB_2U(SCH_1):PAGE189_I86@PURE_QUANTA.Q_RES(CHIPS)':
 'B': CDS_PINID='B';
NODE_NAME     J104 1
 '@S9S_MB_2U_LIB.S9S_MB_2U(SCH_1):PAGE189_I134@PURE_QUANTA.CONN14_210HP207GBR1(CHIPS)':
 '1': CDS_PINID='\1\';
NET_NAME
'PU_FLASH_SECURITY_STRAP'
 '@S9S_MB_2U_LIB.S9S_MB_2U(SCH_1):PU_FLASH_SECURITY_STRAP':
 C_SIGNAL='@s9s_mb_2u_lib.s9s_mb_2u(sch_1):pu_flash_security_strap';
NODE_NAME     R1325 2
 '@S9S_MB_2U_LIB.S9S_MB_2U(SCH_1):PAGE189_I93@PURE_QUANTA.Q_RES(CHIPS)':
 'B': CDS_PINID='B';
NODE_NAME     J104 9
 '@S9S_MB_2U_LIB.S9S_MB_2U(SCH_1):PAGE189_I134@PURE_QUANTA.CONN14_210HP207GBR1(CHIPS)':
 '9': CDS_PINID='\9\';
NET_NAME
'PU_FORCE_PWRON'
 '@S9S_MB_2U_LIB.S9S_MB_2U(SCH_1):PU_FORCE_PWRON':
 C_SIGNAL='@s9s_mb_2u_lib.s9s_mb_2u(sch_1):pu_force_pwron';
NODE_NAME     JP15 1
 '@S9S_MB_2U_LIB.S9S_MB_2U(SCH_1):PAGE312_I187@PURE_QUANTA.CONN3_210HP1030BR1(CHIPS)':
 '1': CDS_PINID='\1\';
NODE_NAME     R1493 2
 '@S9S_MB_2U_LIB.S9S_MB_2U(SCH_1):PAGE312_I191@PURE_QUANTA.Q_RES(CHIPS)':
 'B': CDS_PINID='B';
NET_NAME
'PU_FPGA_D12_PROGRAMN'
 '@S9S_MB_2U_LIB.S9S_MB_2U(SCH_1):PU_FPGA_D12_PROGRAMN':
 C_SIGNAL='@s9s_mb_2u_lib.s9s_mb_2u(sch_1):pu_fpga_d12_programn';
NODE_NAME     R3249 2
 '@S9S_MB_2U_LIB.S9S_MB_2U(SCH_1):PAGE311_I29@PURE_QUANTA.Q_RES(CHIPS)':
 'B': CDS_PINID='B';
NODE_NAME     U249 E15
 '@S9S_MB_2U_LIB.S9S_MB_2U(SCH_1):PAGE311_I70@PURE_QUANTA.LCMXO3LF9400C5BG484C(CHIPS)':
 'PT31D||PROGRAMN': CDS_PINID='\pt31d||programn\';
NET_NAME
'PU_GTL2014_BMC_JTAG_DIR_1'
 '@S9S_MB_2U_LIB.S9S_MB_2U(SCH_1):PU_GTL2014_BMC_JTAG_DIR_1':
 C_SIGNAL='@s9s_mb_2u_lib.s9s_mb_2u(sch_1):pu_gtl2014_bmc_jtag_dir_1';
NODE_NAME     R3055 2
 '@S9S_MB_2U_LIB.S9S_MB_2U(SCH_1):PAGE226_I11@PURE_QUANTA.Q_RES(CHIPS)':
 'B': CDS_PINID='B';
NODE_NAME     U84 1
 '@S9S_MB_2U_LIB.S9S_MB_2U(SCH_1):PAGE226_I18@PURE_QUANTA.GTL2014PW(CHIPS)':
 'DIR': CDS_PINID='DIR';
NODE_NAME     R2514 1
 '@S9S_MB_2U_LIB.S9S_MB_2U(SCH_1):PAGE226_I89@PURE_QUANTA.Q_RES(CHIPS)':
 'A': CDS_PINID='A';
NET_NAME
'PU_JTAG_SW_PU'
 '@S9S_MB_2U_LIB.S9S_MB_2U(SCH_1):PU_JTAG_SW_PU':
 C_SIGNAL='@s9s_mb_2u_lib.s9s_mb_2u(sch_1):pu_jtag_sw_pu';
NODE_NAME     R4623 2
 '@S9S_MB_2U_LIB.S9S_MB_2U(SCH_1):PAGE235_I11@PURE_QUANTA.Q_RES(CHIPS)':
 'B': CDS_PINID='B';
NODE_NAME     JP16 1
 '@S9S_MB_2U_LIB.S9S_MB_2U(SCH_1):PAGE235_I13@PURE_QUANTA.CONN3_210HP1030BR1(CHIPS)':
 '1': CDS_PINID='\1\';
NET_NAME
'PU_LAN_WAKE_N'
 '@S9S_MB_2U_LIB.S9S_MB_2U(SCH_1):PU_LAN_WAKE_N':
 C_SIGNAL='@s9s_mb_2u_lib.s9s_mb_2u(sch_1):pu_lan_wake_n';
NODE_NAME     U4 AU7
 '@S9S_MB_2U_LIB.S9S_MB_2U(SCH_1):PAGE174_I36@PURE_QUANTA.EMMITSBURG_REV0P9(CHIPS)':
 'LAN_WAKE_N': CDS_PINID='LAN_WAKE_N';
NODE_NAME     R453 2
 '@S9S_MB_2U_LIB.S9S_MB_2U(SCH_1):PAGE174_I77@PURE_QUANTA.Q_RES(CHIPS)':
 'B': CDS_PINID='B';
NET_NAME
'PU_LPC_PME_N'
 '@S9S_MB_2U_LIB.S9S_MB_2U(SCH_1):PU_LPC_PME_N':
 C_SIGNAL='@s9s_mb_2u_lib.s9s_mb_2u(sch_1):pu_lpc_pme_n';
NODE_NAME     U4 AJ3
 '@S9S_MB_2U_LIB.S9S_MB_2U(SCH_1):PAGE175_I93@PURE_QUANTA.EMMITSBURG_REV0P9(CHIPS)':
 'GPP_D_9_PME_N': CDS_PINID='GPP_D_9_PME_N';
NODE_NAME     R1259 2
 '@S9S_MB_2U_LIB.S9S_MB_2U(SCH_1):PAGE192_I8@PURE_QUANTA.Q_RES(CHIPS)':
 'B': CDS_PINID='B';
NET_NAME
'PU_MAIN_FPGA_CONFIG_DONE'
 '@S9S_MB_2U_LIB.S9S_MB_2U(SCH_1):PU_MAIN_FPGA_CONFIG_DONE':
 C_SIGNAL='@s9s_mb_2u_lib.s9s_mb_2u(sch_1):pu_main_fpga_config_done';
NODE_NAME     R1401 1
 '@S9S_MB_2U_LIB.S9S_MB_2U(SCH_1):PAGE209_I16@PURE_QUANTA.Q_RES(CHIPS)':
 'A': CDS_PINID='A';
NODE_NAME     U249 B19
 '@S9S_MB_2U_LIB.S9S_MB_2U(SCH_1):PAGE314_I188@PURE_QUANTA.LCMXO3LF9400C5BG484C(CHIPS)':
 'PT41B': CDS_PINID='PT41B';
NET_NAME
'PU_OC2_USB_N'
 '@S9S_MB_2U_LIB.S9S_MB_2U(SCH_1):PU_OC2_USB_N':
 C_SIGNAL='@s9s_mb_2u_lib.s9s_mb_2u(sch_1):pu_oc2_usb_n';
NODE_NAME     U4 BG30
 '@S9S_MB_2U_LIB.S9S_MB_2U(SCH_1):PAGE175_I93@PURE_QUANTA.EMMITSBURG_REV0P9(CHIPS)':
 'GPPC_B_7_USB2_OCB_2': CDS_PINID='GPPC_B_7_USB2_OCB_2';
NODE_NAME     R3938 1
 '@S9S_MB_2U_LIB.S9S_MB_2U(SCH_1):PAGE175_I272@PURE_QUANTA.Q_RES(CHIPS)':
 'A': CDS_PINID='A';
NET_NAME
'PU_OC3_USB_N'
 '@S9S_MB_2U_LIB.S9S_MB_2U(SCH_1):PU_OC3_USB_N':
 C_SIGNAL='@s9s_mb_2u_lib.s9s_mb_2u(sch_1):pu_oc3_usb_n';
NODE_NAME     U4 BG28
 '@S9S_MB_2U_LIB.S9S_MB_2U(SCH_1):PAGE175_I93@PURE_QUANTA.EMMITSBURG_REV0P9(CHIPS)':
 'GPPC_B_8_USB2_OCB_3': CDS_PINID='GPPC_B_8_USB2_OCB_3';
NODE_NAME     R635 1
 '@S9S_MB_2U_LIB.S9S_MB_2U(SCH_1):PAGE175_I234@PURE_QUANTA.Q_RES(CHIPS)':
 'A': CDS_PINID='A';
NET_NAME
'PU_OC4_USB_N'
 '@S9S_MB_2U_LIB.S9S_MB_2U(SCH_1):PU_OC4_USB_N':
 C_SIGNAL='@s9s_mb_2u_lib.s9s_mb_2u(sch_1):pu_oc4_usb_n';
NODE_NAME     U4 BG26
 '@S9S_MB_2U_LIB.S9S_MB_2U(SCH_1):PAGE175_I93@PURE_QUANTA.EMMITSBURG_REV0P9(CHIPS)':
 'GPPC_B_9_USB2_OCB_4': CDS_PINID='GPPC_B_9_USB2_OCB_4';
NODE_NAME     R727 1
 '@S9S_MB_2U_LIB.S9S_MB_2U(SCH_1):PAGE175_I236@PURE_QUANTA.Q_RES(CHIPS)':
 'A': CDS_PINID='A';
NET_NAME
'PU_OC5_USB_N'
 '@S9S_MB_2U_LIB.S9S_MB_2U(SCH_1):PU_OC5_USB_N':
 C_SIGNAL='@s9s_mb_2u_lib.s9s_mb_2u(sch_1):pu_oc5_usb_n';
NODE_NAME     U4 BG24
 '@S9S_MB_2U_LIB.S9S_MB_2U(SCH_1):PAGE175_I93@PURE_QUANTA.EMMITSBURG_REV0P9(CHIPS)':
 'GPPC_B_10_USB2_OCB_5': CDS_PINID='GPPC_B_10_USB2_OCB_5';
NODE_NAME     R770 1
 '@S9S_MB_2U_LIB.S9S_MB_2U(SCH_1):PAGE175_I239@PURE_QUANTA.Q_RES(CHIPS)':
 'A': CDS_PINID='A';
NET_NAME
'PU_OC6_USB_N'
 '@S9S_MB_2U_LIB.S9S_MB_2U(SCH_1):PU_OC6_USB_N':
 C_SIGNAL='@s9s_mb_2u_lib.s9s_mb_2u(sch_1):pu_oc6_usb_n';
NODE_NAME     U4 BG22
 '@S9S_MB_2U_LIB.S9S_MB_2U(SCH_1):PAGE175_I93@PURE_QUANTA.EMMITSBURG_REV0P9(CHIPS)':
 'GPPC_B_11_USB2_OCB_6': CDS_PINID='GPPC_B_11_USB2_OCB_6';
NODE_NAME     R913 1
 '@S9S_MB_2U_LIB.S9S_MB_2U(SCH_1):PAGE175_I241@PURE_QUANTA.Q_RES(CHIPS)':
 'A': CDS_PINID='A';
NET_NAME
'PU_OCP_SFF_WAKE_OE'
 '@S9S_MB_2U_LIB.S9S_MB_2U(SCH_1):PU_OCP_SFF_WAKE_OE':
 C_SIGNAL='@s9s_mb_2u_lib.s9s_mb_2u(sch_1):pu_ocp_sff_wake_oe';
NODE_NAME     R1592 2
 '@S9S_MB_2U_LIB.S9S_MB_2U(SCH_1):PAGE152_I37@PURE_QUANTA.Q_RES(CHIPS)':
 'B': CDS_PINID='B';
NODE_NAME     U82 1
 '@S9S_MB_2U_LIB.S9S_MB_2U(SCH_1):PAGE152_I79@PURE_QUANTA.74LVC1G126SE7(CHIPS)':
 'OE': CDS_PINID='OE';
NET_NAME
'PU_OCP_V3_2_WAKE_OE'
 '@S9S_MB_2U_LIB.S9S_MB_2U(SCH_1):PU_OCP_V3_2_WAKE_OE':
 C_SIGNAL='@s9s_mb_2u_lib.s9s_mb_2u(sch_1):pu_ocp_v3_2_wake_oe';
NODE_NAME     R3183 2
 '@S9S_MB_2U_LIB.S9S_MB_2U(SCH_1):PAGE156_I7@PURE_QUANTA.Q_RES(CHIPS)':
 'B': CDS_PINID='B';
NODE_NAME     U217 1
 '@S9S_MB_2U_LIB.S9S_MB_2U(SCH_1):PAGE156_I79@PURE_QUANTA.74LVC1G126SE7(CHIPS)':
 'OE': CDS_PINID='OE';
NET_NAME
'PU_PCH_PLD_3V3AUX_ALERT_N'
 '@S9S_MB_2U_LIB.S9S_MB_2U(SCH_1):PU_PCH_PLD_3V3AUX_ALERT_N':
 C_SIGNAL='@s9s_mb_2u_lib.s9s_mb_2u(sch_1):pu_pch_pld_3v3aux_alert_n';
NODE_NAME     U4 AN2
 '@S9S_MB_2U_LIB.S9S_MB_2U(SCH_1):PAGE175_I93@PURE_QUANTA.EMMITSBURG_REV0P9(CHIPS)':
 'GPPC_C_21_MC_SMBALERT_N': CDS_PINID='GPPC_C_21_MC_SMBALERT_N';
NODE_NAME     R1583 1
 '@S9S_MB_2U_LIB.S9S_MB_2U(SCH_1):PAGE175_I144@PURE_QUANTA.Q_RES(CHIPS)':
 'A': CDS_PINID='A';
NET_NAME
'PU_PCH_PMCALERT_N'
 '@S9S_MB_2U_LIB.S9S_MB_2U(SCH_1):PU_PCH_PMCALERT_N':
 C_SIGNAL='@s9s_mb_2u_lib.s9s_mb_2u(sch_1):pu_pch_pmcalert_n';
NODE_NAME     U4 J4
 '@S9S_MB_2U_LIB.S9S_MB_2U(SCH_1):PAGE176_I22@PURE_QUANTA.EMMITSBURG_REV0P9(CHIPS)':
 'GPPC_H_18_PMCALERT_N': CDS_PINID='GPPC_H_18_PMCALERT_N';
NODE_NAME     R456 2
 '@S9S_MB_2U_LIB.S9S_MB_2U(SCH_1):PAGE192_I66@PURE_QUANTA.Q_RES(CHIPS)':
 'B': CDS_PINID='B';
NET_NAME
'PU_PCH_VRALERT_N'
 '@S9S_MB_2U_LIB.S9S_MB_2U(SCH_1):PU_PCH_VRALERT_N':
 C_SIGNAL='@s9s_mb_2u_lib.s9s_mb_2u(sch_1):pu_pch_vralert_n';
NODE_NAME     U4 AC3
 '@S9S_MB_2U_LIB.S9S_MB_2U(SCH_1):PAGE175_I93@PURE_QUANTA.EMMITSBURG_REV0P9(CHIPS)':
 'GPP_D_15_VRALERT_N': CDS_PINID='GPP_D_15_VRALERT_N';
NODE_NAME     R1257 2
 '@S9S_MB_2U_LIB.S9S_MB_2U(SCH_1):PAGE192_I4@PURE_QUANTA.Q_RES(CHIPS)':
 'B': CDS_PINID='B';
NET_NAME
'PU_PIROM_CPU0_SM_WP'
 '@S9S_MB_2U_LIB.S9S_MB_2U(SCH_1):PU_PIROM_CPU0_SM_WP':
 C_SIGNAL='@s9s_mb_2u_lib.s9s_mb_2u(sch_1):pu_pirom_cpu0_sm_wp';
NODE_NAME     U2 CR72
 '@S9S_MB_2U_LIB.S9S_MB_2U(SCH_1):PAGE14_I1@PURE_QUANTA.SOCKET4677_AZIF0045P001C01CS(CHIPS)':
 'PIROM_SM_WP': CDS_PINID='PIROM_SM_WP';
NODE_NAME     R997 1
 '@S9S_MB_2U_LIB.S9S_MB_2U(SCH_1):PAGE127_I31@PURE_QUANTA.Q_RES(CHIPS)':
 'A': CDS_PINID='A';
NODE_NAME     R650 2
 '@S9S_MB_2U_LIB.S9S_MB_2U(SCH_1):PAGE127_I32@PURE_QUANTA.Q_RES(CHIPS)':
 'B': CDS_PINID='B';
NET_NAME
'PU_PIROM_CPU1_ADDR0'
 '@S9S_MB_2U_LIB.S9S_MB_2U(SCH_1):PU_PIROM_CPU1_ADDR0':
 C_SIGNAL='@s9s_mb_2u_lib.s9s_mb_2u(sch_1):pu_pirom_cpu1_addr0';
NODE_NAME     U1 CR70
 '@S9S_MB_2U_LIB.S9S_MB_2U(SCH_1):PAGE45_I29@PURE_QUANTA.SOCKET4677_AZIF0045P001C01CS(CHIPS)':
 'PIROM_AD0': CDS_PINID='PIROM_AD0';
NODE_NAME     R629 2
 '@S9S_MB_2U_LIB.S9S_MB_2U(SCH_1):PAGE127_I13@PURE_QUANTA.Q_RES(CHIPS)':
 'B': CDS_PINID='B';
NODE_NAME     R630 1
 '@S9S_MB_2U_LIB.S9S_MB_2U(SCH_1):PAGE127_I15@PURE_QUANTA.Q_RES(CHIPS)':
 'A': CDS_PINID='A';
NET_NAME
'PU_PIROM_CPU1_SM_WP'
 '@S9S_MB_2U_LIB.S9S_MB_2U(SCH_1):PU_PIROM_CPU1_SM_WP':
 C_SIGNAL='@s9s_mb_2u_lib.s9s_mb_2u(sch_1):pu_pirom_cpu1_sm_wp';
NODE_NAME     U1 CR72
 '@S9S_MB_2U_LIB.S9S_MB_2U(SCH_1):PAGE45_I29@PURE_QUANTA.SOCKET4677_AZIF0045P001C01CS(CHIPS)':
 'PIROM_SM_WP': CDS_PINID='PIROM_SM_WP';
NODE_NAME     R1004 2
 '@S9S_MB_2U_LIB.S9S_MB_2U(SCH_1):PAGE127_I35@PURE_QUANTA.Q_RES(CHIPS)':
 'B': CDS_PINID='B';
NODE_NAME     R1005 1
 '@S9S_MB_2U_LIB.S9S_MB_2U(SCH_1):PAGE127_I36@PURE_QUANTA.Q_RES(CHIPS)':
 'A': CDS_PINID='A';
NET_NAME
'PU_PLD_HEARTBEAT_LVC3'
 '@S9S_MB_2U_LIB.S9S_MB_2U(SCH_1):PU_PLD_HEARTBEAT_LVC3':
 C_SIGNAL='@s9s_mb_2u_lib.s9s_mb_2u(sch_1):pu_pld_heartbeat_lvc3';
NODE_NAME     D0 A
 '@S9S_MB_2U_LIB.S9S_MB_2U(SCH_1):PAGE207_I277@PURE_QUANTA.Q_LED(CHIPS)':
 'A': CDS_PINID='A';
NODE_NAME     R1195 2
 '@S9S_MB_2U_LIB.S9S_MB_2U(SCH_1):PAGE207_I278@PURE_QUANTA.Q_RES(CHIPS)':
 'B': CDS_PINID='B';
NET_NAME
'PU_RST_DEDI_BUSY_PLD_N'
 '@S9S_MB_2U_LIB.S9S_MB_2U(SCH_1):PU_RST_DEDI_BUSY_PLD_N':
 C_SIGNAL='@s9s_mb_2u_lib.s9s_mb_2u(sch_1):pu_rst_dedi_busy_pld_n';
NODE_NAME     R1681 2
 '@S9S_MB_2U_LIB.S9S_MB_2U(SCH_1):PAGE314_I47@PURE_QUANTA.Q_RES(CHIPS)':
 'B': CDS_PINID='B';
NODE_NAME     U249 D9
 '@S9S_MB_2U_LIB.S9S_MB_2U(SCH_1):PAGE314_I188@PURE_QUANTA.LCMXO3LF9400C5BG484C(CHIPS)':
 'PT20D': CDS_PINID='PT20D';
NET_NAME
'PU_RST_SMB_PCIE0_N'
 '@S9S_MB_2U_LIB.S9S_MB_2U(SCH_1):PU_RST_SMB_PCIE0_N':
 C_SIGNAL='@s9s_mb_2u_lib.s9s_mb_2u(sch_1):pu_rst_smb_pcie0_n';
NODE_NAME     R2268 2
 '@S9S_MB_2U_LIB.S9S_MB_2U(SCH_1):PAGE219_I41@PURE_QUANTA.Q_RES(CHIPS)':
 'B': CDS_PINID='B';
NODE_NAME     U36 3
 '@S9S_MB_2U_LIB.S9S_MB_2U(SCH_1):PAGE219_I45@PURE_QUANTA.TCA9548APWR(CHIPS)':
 'RESET#': CDS_PINID='\reset#\';
NET_NAME
'PU_RST_SMB_PCIE2_N'
 '@S9S_MB_2U_LIB.S9S_MB_2U(SCH_1):PU_RST_SMB_PCIE2_N':
 C_SIGNAL='@s9s_mb_2u_lib.s9s_mb_2u(sch_1):pu_rst_smb_pcie2_n';
NODE_NAME     U39 3
 '@S9S_MB_2U_LIB.S9S_MB_2U(SCH_1):PAGE221_I103@PURE_QUANTA.TCA9548APWR(CHIPS)':
 'RESET#': CDS_PINID='\reset#\';
NODE_NAME     R3710 2
 '@S9S_MB_2U_LIB.S9S_MB_2U(SCH_1):PAGE221_I145@PURE_QUANTA.Q_RES(CHIPS)':
 'B': CDS_PINID='B';
NET_NAME
'PU_RST_SMB_U181_N'
 '@S9S_MB_2U_LIB.S9S_MB_2U(SCH_1):PU_RST_SMB_U181_N':
 C_SIGNAL='@s9s_mb_2u_lib.s9s_mb_2u(sch_1):pu_rst_smb_u181_n';
NODE_NAME     U181 3
 '@S9S_MB_2U_LIB.S9S_MB_2U(SCH_1):PAGE214_I66@PURE_QUANTA.PCA9539RPW(CHIPS)':
 'RESET': CDS_PINID='RESET';
NODE_NAME     R2922 2
 '@S9S_MB_2U_LIB.S9S_MB_2U(SCH_1):PAGE214_I95@PURE_QUANTA.Q_RES(CHIPS)':
 'B': CDS_PINID='B';
NET_NAME
'PU_S3M_CPU0_CPLD_CONFD'
 '@S9S_MB_2U_LIB.S9S_MB_2U(SCH_1):PU_S3M_CPU0_CPLD_CONFD':
 C_SIGNAL='@s9s_mb_2u_lib.s9s_mb_2u(sch_1):pu_s3m_cpu0_cpld_confd';
NODE_NAME     U2 CJ64
 '@S9S_MB_2U_LIB.S9S_MB_2U(SCH_1):PAGE15_I1@PURE_QUANTA.SOCKET4677_AZIF0045P001C01CS(CHIPS)':
 'TEST_1': CDS_PINID='TEST_1';
NODE_NAME     R320 2
 '@S9S_MB_2U_LIB.S9S_MB_2U(SCH_1):PAGE80_I7@PURE_QUANTA.Q_RES(CHIPS)':
 'B': CDS_PINID='B';
NET_NAME
'PU_S3M_CPU0_CPLD_STATUS'
 '@S9S_MB_2U_LIB.S9S_MB_2U(SCH_1):PU_S3M_CPU0_CPLD_STATUS':
 C_SIGNAL='@s9s_mb_2u_lib.s9s_mb_2u(sch_1):pu_s3m_cpu0_cpld_status';
NODE_NAME     U2 CH65
 '@S9S_MB_2U_LIB.S9S_MB_2U(SCH_1):PAGE15_I1@PURE_QUANTA.SOCKET4677_AZIF0045P001C01CS(CHIPS)':
 'TEST_3': CDS_PINID='TEST_3';
NODE_NAME     R319 2
 '@S9S_MB_2U_LIB.S9S_MB_2U(SCH_1):PAGE80_I8@PURE_QUANTA.Q_RES(CHIPS)':
 'B': CDS_PINID='B';
NET_NAME
'PU_S3M_CPU1_CPLD_CONFD'
 '@S9S_MB_2U_LIB.S9S_MB_2U(SCH_1):PU_S3M_CPU1_CPLD_CONFD':
 C_SIGNAL='@s9s_mb_2u_lib.s9s_mb_2u(sch_1):pu_s3m_cpu1_cpld_confd';
NODE_NAME     U1 CJ64
 '@S9S_MB_2U_LIB.S9S_MB_2U(SCH_1):PAGE46_I5@PURE_QUANTA.SOCKET4677_AZIF0045P001C01CS(CHIPS)':
 'TEST_1': CDS_PINID='TEST_1';
NODE_NAME     R326 2
 '@S9S_MB_2U_LIB.S9S_MB_2U(SCH_1):PAGE80_I26@PURE_QUANTA.Q_RES(CHIPS)':
 'B': CDS_PINID='B';
NET_NAME
'PU_S3M_CPU1_CPLD_STATUS'
 '@S9S_MB_2U_LIB.S9S_MB_2U(SCH_1):PU_S3M_CPU1_CPLD_STATUS':
 C_SIGNAL='@s9s_mb_2u_lib.s9s_mb_2u(sch_1):pu_s3m_cpu1_cpld_status';
NODE_NAME     U1 CH65
 '@S9S_MB_2U_LIB.S9S_MB_2U(SCH_1):PAGE46_I5@PURE_QUANTA.SOCKET4677_AZIF0045P001C01CS(CHIPS)':
 'TEST_3': CDS_PINID='TEST_3';
NODE_NAME     R325 2
 '@S9S_MB_2U_LIB.S9S_MB_2U(SCH_1):PAGE80_I27@PURE_QUANTA.Q_RES(CHIPS)':
 'B': CDS_PINID='B';
NET_NAME
'PU_SMB_PCH_PLD_3V3AUX_SCL'
 '@S9S_MB_2U_LIB.S9S_MB_2U(SCH_1):PU_SMB_PCH_PLD_3V3AUX_SCL':
 C_SIGNAL='@s9s_mb_2u_lib.s9s_mb_2u(sch_1):pu_smb_pch_pld_3v3aux_scl';
NODE_NAME     U4 AL1
 '@S9S_MB_2U_LIB.S9S_MB_2U(SCH_1):PAGE175_I93@PURE_QUANTA.EMMITSBURG_REV0P9(CHIPS)':
 'GPPC_C_19_MC_SMBCLK': CDS_PINID='GPPC_C_19_MC_SMBCLK';
NODE_NAME     R1581 1
 '@S9S_MB_2U_LIB.S9S_MB_2U(SCH_1):PAGE175_I142@PURE_QUANTA.Q_RES(CHIPS)':
 'A': CDS_PINID='A';
NET_NAME
'PU_SMB_PCH_PLD_3V3AUX_SDA'
 '@S9S_MB_2U_LIB.S9S_MB_2U(SCH_1):PU_SMB_PCH_PLD_3V3AUX_SDA':
 C_SIGNAL='@s9s_mb_2u_lib.s9s_mb_2u(sch_1):pu_smb_pch_pld_3v3aux_sda';
NODE_NAME     U4 AT1
 '@S9S_MB_2U_LIB.S9S_MB_2U(SCH_1):PAGE175_I93@PURE_QUANTA.EMMITSBURG_REV0P9(CHIPS)':
 'GPPC_C_20_MC_SMBDATA': CDS_PINID='GPPC_C_20_MC_SMBDATA';
NODE_NAME     R1582 1
 '@S9S_MB_2U_LIB.S9S_MB_2U(SCH_1):PAGE175_I141@PURE_QUANTA.Q_RES(CHIPS)':
 'A': CDS_PINID='A';
NET_NAME
'PU_SMB_SML3_3V3AUX_PCH_SCL'
 '@S9S_MB_2U_LIB.S9S_MB_2U(SCH_1):PU_SMB_SML3_3V3AUX_PCH_SCL':
 C_SIGNAL='@s9s_mb_2u_lib.s9s_mb_2u(sch_1):pu_smb_sml3_3v3aux_pch_scl';
NODE_NAME     U4 AN4
 '@S9S_MB_2U_LIB.S9S_MB_2U(SCH_1):PAGE175_I93@PURE_QUANTA.EMMITSBURG_REV0P9(CHIPS)':
 'GPPC_C_12_ME_SML3CLK': CDS_PINID='GPPC_C_12_ME_SML3CLK';
NODE_NAME     R1451 1
 '@S9S_MB_2U_LIB.S9S_MB_2U(SCH_1):PAGE175_I109@PURE_QUANTA.Q_RES(CHIPS)':
 'A': CDS_PINID='A';
NET_NAME
'PU_SMB_SML3_3V3AUX_PCH_SDA'
 '@S9S_MB_2U_LIB.S9S_MB_2U(SCH_1):PU_SMB_SML3_3V3AUX_PCH_SDA':
 C_SIGNAL='@s9s_mb_2u_lib.s9s_mb_2u(sch_1):pu_smb_sml3_3v3aux_pch_sda';
NODE_NAME     U4 AY1
 '@S9S_MB_2U_LIB.S9S_MB_2U(SCH_1):PAGE175_I93@PURE_QUANTA.EMMITSBURG_REV0P9(CHIPS)':
 'GPPC_C_13_ME_SML3DATA': CDS_PINID='GPPC_C_13_ME_SML3DATA';
NODE_NAME     R1452 1
 '@S9S_MB_2U_LIB.S9S_MB_2U(SCH_1):PAGE175_I112@PURE_QUANTA.Q_RES(CHIPS)':
 'A': CDS_PINID='A';
NET_NAME
'PU_SMB_SML4_3V3AUX_PCH_SCL'
 '@S9S_MB_2U_LIB.S9S_MB_2U(SCH_1):PU_SMB_SML4_3V3AUX_PCH_SCL':
 C_SIGNAL='@s9s_mb_2u_lib.s9s_mb_2u(sch_1):pu_smb_sml4_3v3aux_pch_scl';
NODE_NAME     U4 BA2
 '@S9S_MB_2U_LIB.S9S_MB_2U(SCH_1):PAGE175_I93@PURE_QUANTA.EMMITSBURG_REV0P9(CHIPS)':
 'GPPC_C_15_ME_SML4CLK': CDS_PINID='GPPC_C_15_ME_SML4CLK';
NODE_NAME     R1453 1
 '@S9S_MB_2U_LIB.S9S_MB_2U(SCH_1):PAGE175_I120@PURE_QUANTA.Q_RES(CHIPS)':
 'A': CDS_PINID='A';
NET_NAME
'PU_SMB_SML4_3V3AUX_PCH_SDA'
 '@S9S_MB_2U_LIB.S9S_MB_2U(SCH_1):PU_SMB_SML4_3V3AUX_PCH_SDA':
 C_SIGNAL='@s9s_mb_2u_lib.s9s_mb_2u(sch_1):pu_smb_sml4_3v3aux_pch_sda';
NODE_NAME     U4 AV1
 '@S9S_MB_2U_LIB.S9S_MB_2U(SCH_1):PAGE175_I93@PURE_QUANTA.EMMITSBURG_REV0P9(CHIPS)':
 'GPPC_C_16_ME_SML4DATA': CDS_PINID='GPPC_C_16_ME_SML4DATA';
NODE_NAME     R1454 1
 '@S9S_MB_2U_LIB.S9S_MB_2U(SCH_1):PAGE175_I121@PURE_QUANTA.Q_RES(CHIPS)':
 'A': CDS_PINID='A';
NET_NAME
'PU_SWAP_OVERRIDE_N'
 '@S9S_MB_2U_LIB.S9S_MB_2U(SCH_1):PU_SWAP_OVERRIDE_N':
 C_SIGNAL='@s9s_mb_2u_lib.s9s_mb_2u(sch_1):pu_swap_override_n';
NODE_NAME     R1320 2
 '@S9S_MB_2U_LIB.S9S_MB_2U(SCH_1):PAGE189_I89@PURE_QUANTA.Q_RES(CHIPS)':
 'B': CDS_PINID='B';
NODE_NAME     J104 5
 '@S9S_MB_2U_LIB.S9S_MB_2U(SCH_1):PAGE189_I134@PURE_QUANTA.CONN14_210HP207GBR1(CHIPS)':
 '5': CDS_PINID='\5\';
NET_NAME
'PU_TAP_ODT_CPU0_EN'
 '@S9S_MB_2U_LIB.S9S_MB_2U(SCH_1):PU_TAP_ODT_CPU0_EN':
 C_SIGNAL='@s9s_mb_2u_lib.s9s_mb_2u(sch_1):pu_tap_odt_cpu0_en';
NODE_NAME     U2 AY20
 '@S9S_MB_2U_LIB.S9S_MB_2U(SCH_1):PAGE14_I1@PURE_QUANTA.SOCKET4677_AZIF0045P001C01CS(CHIPS)':
 'TAP_ODT_EN': CDS_PINID='TAP_ODT_EN';
NODE_NAME     R1009 2
 '@S9S_MB_2U_LIB.S9S_MB_2U(SCH_1):PAGE119_I136@PURE_QUANTA.Q_RES(CHIPS)':
 'B': CDS_PINID='B';
NET_NAME
'PU_TAP_ODT_CPU1_EN'
 '@S9S_MB_2U_LIB.S9S_MB_2U(SCH_1):PU_TAP_ODT_CPU1_EN':
 C_SIGNAL='@s9s_mb_2u_lib.s9s_mb_2u(sch_1):pu_tap_odt_cpu1_en';
NODE_NAME     U1 AY20
 '@S9S_MB_2U_LIB.S9S_MB_2U(SCH_1):PAGE45_I29@PURE_QUANTA.SOCKET4677_AZIF0045P001C01CS(CHIPS)':
 'TAP_ODT_EN': CDS_PINID='TAP_ODT_EN';
NODE_NAME     R1008 2
 '@S9S_MB_2U_LIB.S9S_MB_2U(SCH_1):PAGE119_I139@PURE_QUANTA.Q_RES(CHIPS)':
 'B': CDS_PINID='B';
NET_NAME
'PU_TEST'
 '@S9S_MB_2U_LIB.S9S_MB_2U(SCH_1):PU_TEST':
 C_SIGNAL='@s9s_mb_2u_lib.s9s_mb_2u(sch_1):pu_test';
NODE_NAME     U237 5
 '@S9S_MB_2U_LIB.S9S_MB_2U(SCH_1):PAGE136_I50@PURE_QUANTA.PI3EQX12902AZLEX(CHIPS)':
 'TEST#': CDS_PINID='\test#\';
NODE_NAME     R3291 1
 '@S9S_MB_2U_LIB.S9S_MB_2U(SCH_1):PAGE136_I82@PURE_QUANTA.Q_RES(CHIPS)':
 'A': CDS_PINID='A';
NET_NAME
'PU_U181_INT'
 '@S9S_MB_2U_LIB.S9S_MB_2U(SCH_1):PU_U181_INT':
 C_SIGNAL='@s9s_mb_2u_lib.s9s_mb_2u(sch_1):pu_u181_int';
NODE_NAME     U181 1
 '@S9S_MB_2U_LIB.S9S_MB_2U(SCH_1):PAGE214_I66@PURE_QUANTA.PCA9539RPW(CHIPS)':
 'INT': CDS_PINID='INT';
NODE_NAME     R2923 2
 '@S9S_MB_2U_LIB.S9S_MB_2U(SCH_1):PAGE214_I90@PURE_QUANTA.Q_RES(CHIPS)':
 'B': CDS_PINID='B';
NET_NAME
'PVCC1_AUX'
 '@S9S_MB_2U_LIB.S9S_MB_2U(SCH_1):PVCC1_AUX':
 C_SIGNAL='@s9s_mb_2u_lib.s9s_mb_2u(sch_1):pvcc1_aux',
 CDS_GLOBAL_NET='TRUE';
NODE_NAME     PR395 2
 '@S9S_MB_2U_LIB.S9S_MB_2U(SCH_1):PAGE249_I8@PURE_QUANTA.Q_RES(CHIPS)':
 'B': CDS_PINID='B';
NODE_NAME     PR396 2
 '@S9S_MB_2U_LIB.S9S_MB_2U(SCH_1):PAGE249_I2@PURE_QUANTA.Q_RES(CHIPS)':
 'B': CDS_PINID='B';
NODE_NAME     PR1329 1
 '@S9S_MB_2U_LIB.S9S_MB_2U(SCH_1):PAGE249_I5@PURE_QUANTA.Q_RES(CHIPS)':
 'A': CDS_PINID='A';
NET_NAME
'PVCCD_HV_CPU0'
 '@S9S_MB_2U_LIB.S9S_MB_2U(SCH_1):PVCCD_HV_CPU0':
 C_SIGNAL='@s9s_mb_2u_lib.s9s_mb_2u(sch_1):pvccd_hv_cpu0',
 CDS_GLOBAL_NET='TRUE';
NODE_NAME     U2 AT36
 '@S9S_MB_2U_LIB.S9S_MB_2U(SCH_1):PAGE37_I8@PURE_QUANTA.SOCKET4677_AZIF0045P001C01CS(CHIPS)':
 'VCCD_HV0': CDS_PINID='VCCD_HV0';
NODE_NAME     U2 AT55
 '@S9S_MB_2U_LIB.S9S_MB_2U(SCH_1):PAGE37_I8@PURE_QUANTA.SOCKET4677_AZIF0045P001C01CS(CHIPS)':
 'VCCD_HV1': CDS_PINID='VCCD_HV1';
NODE_NAME     U2 AU3
 '@S9S_MB_2U_LIB.S9S_MB_2U(SCH_1):PAGE37_I8@PURE_QUANTA.SOCKET4677_AZIF0045P001C01CS(CHIPS)':
 'VCCD_HV2': CDS_PINID='VCCD_HV2';
NODE_NAME     U2 AU35
 '@S9S_MB_2U_LIB.S9S_MB_2U(SCH_1):PAGE37_I8@PURE_QUANTA.SOCKET4677_AZIF0045P001C01CS(CHIPS)':
 'VCCD_HV3': CDS_PINID='VCCD_HV3';
NODE_NAME     U2 AU54
 '@S9S_MB_2U_LIB.S9S_MB_2U(SCH_1):PAGE37_I8@PURE_QUANTA.SOCKET4677_AZIF0045P001C01CS(CHIPS)':
 'VCCD_HV4': CDS_PINID='VCCD_HV4';
NODE_NAME     U2 AU7
 '@S9S_MB_2U_LIB.S9S_MB_2U(SCH_1):PAGE37_I8@PURE_QUANTA.SOCKET4677_AZIF0045P001C01CS(CHIPS)':
 'VCCD_HV5': CDS_PINID='VCCD_HV5';
NODE_NAME     U2 AV34
 '@S9S_MB_2U_LIB.S9S_MB_2U(SCH_1):PAGE37_I8@PURE_QUANTA.SOCKET4677_AZIF0045P001C01CS(CHIPS)':
 'VCCD_HV6': CDS_PINID='VCCD_HV6';
NODE_NAME     U2 AV36
 '@S9S_MB_2U_LIB.S9S_MB_2U(SCH_1):PAGE37_I8@PURE_QUANTA.SOCKET4677_AZIF0045P001C01CS(CHIPS)':
 'VCCD_HV7': CDS_PINID='VCCD_HV7';
NODE_NAME     U2 AV53
 '@S9S_MB_2U_LIB.S9S_MB_2U(SCH_1):PAGE37_I8@PURE_QUANTA.SOCKET4677_AZIF0045P001C01CS(CHIPS)':
 'VCCD_HV8': CDS_PINID='VCCD_HV8';
NODE_NAME     U2 AV55
 '@S9S_MB_2U_LIB.S9S_MB_2U(SCH_1):PAGE37_I8@PURE_QUANTA.SOCKET4677_AZIF0045P001C01CS(CHIPS)':
 'VCCD_HV9': CDS_PINID='VCCD_HV9';
NODE_NAME     U2 BA3
 '@S9S_MB_2U_LIB.S9S_MB_2U(SCH_1):PAGE37_I8@PURE_QUANTA.SOCKET4677_AZIF0045P001C01CS(CHIPS)':
 'VCCD_HV10': CDS_PINID='VCCD_HV10';
NODE_NAME     U2 BA7
 '@S9S_MB_2U_LIB.S9S_MB_2U(SCH_1):PAGE37_I8@PURE_QUANTA.SOCKET4677_AZIF0045P001C01CS(CHIPS)':
 'VCCD_HV11': CDS_PINID='VCCD_HV11';
NODE_NAME     U2 BE11
 '@S9S_MB_2U_LIB.S9S_MB_2U(SCH_1):PAGE37_I8@PURE_QUANTA.SOCKET4677_AZIF0045P001C01CS(CHIPS)':
 'VCCD_HV12': CDS_PINID='VCCD_HV12';
NODE_NAME     U2 BE3
 '@S9S_MB_2U_LIB.S9S_MB_2U(SCH_1):PAGE37_I8@PURE_QUANTA.SOCKET4677_AZIF0045P001C01CS(CHIPS)':
 'VCCD_HV13': CDS_PINID='VCCD_HV13';
NODE_NAME     U2 BE7
 '@S9S_MB_2U_LIB.S9S_MB_2U(SCH_1):PAGE37_I8@PURE_QUANTA.SOCKET4677_AZIF0045P001C01CS(CHIPS)':
 'VCCD_HV14': CDS_PINID='VCCD_HV14';
NODE_NAME     U2 BJ11
 '@S9S_MB_2U_LIB.S9S_MB_2U(SCH_1):PAGE37_I8@PURE_QUANTA.SOCKET4677_AZIF0045P001C01CS(CHIPS)':
 'VCCD_HV15': CDS_PINID='VCCD_HV15';
NODE_NAME     U2 BJ3
 '@S9S_MB_2U_LIB.S9S_MB_2U(SCH_1):PAGE37_I8@PURE_QUANTA.SOCKET4677_AZIF0045P001C01CS(CHIPS)':
 'VCCD_HV16': CDS_PINID='VCCD_HV16';
NODE_NAME     U2 BJ7
 '@S9S_MB_2U_LIB.S9S_MB_2U(SCH_1):PAGE37_I8@PURE_QUANTA.SOCKET4677_AZIF0045P001C01CS(CHIPS)':
 'VCCD_HV17': CDS_PINID='VCCD_HV17';
NODE_NAME     U2 BN7
 '@S9S_MB_2U_LIB.S9S_MB_2U(SCH_1):PAGE37_I8@PURE_QUANTA.SOCKET4677_AZIF0045P001C01CS(CHIPS)':
 'VCCD_HV18': CDS_PINID='VCCD_HV18';
NODE_NAME     U2 CA7
 '@S9S_MB_2U_LIB.S9S_MB_2U(SCH_1):PAGE37_I8@PURE_QUANTA.SOCKET4677_AZIF0045P001C01CS(CHIPS)':
 'VCCD_HV19': CDS_PINID='VCCD_HV19';
NODE_NAME     U2 CE7
 '@S9S_MB_2U_LIB.S9S_MB_2U(SCH_1):PAGE37_I8@PURE_QUANTA.SOCKET4677_AZIF0045P001C01CS(CHIPS)':
 'VCCD_HV20': CDS_PINID='VCCD_HV20';
NODE_NAME     U2 CW35
 '@S9S_MB_2U_LIB.S9S_MB_2U(SCH_1):PAGE37_I8@PURE_QUANTA.SOCKET4677_AZIF0045P001C01CS(CHIPS)':
 'VCCD_HV21': CDS_PINID='VCCD_HV21';
NODE_NAME     U2 CW37
 '@S9S_MB_2U_LIB.S9S_MB_2U(SCH_1):PAGE37_I8@PURE_QUANTA.SOCKET4677_AZIF0045P001C01CS(CHIPS)':
 'VCCD_HV22': CDS_PINID='VCCD_HV22';
NODE_NAME     U2 CW52
 '@S9S_MB_2U_LIB.S9S_MB_2U(SCH_1):PAGE37_I8@PURE_QUANTA.SOCKET4677_AZIF0045P001C01CS(CHIPS)':
 'VCCD_HV23': CDS_PINID='VCCD_HV23';
NODE_NAME     U2 CW54
 '@S9S_MB_2U_LIB.S9S_MB_2U(SCH_1):PAGE37_I8@PURE_QUANTA.SOCKET4677_AZIF0045P001C01CS(CHIPS)':
 'VCCD_HV24': CDS_PINID='VCCD_HV24';
NODE_NAME     U2 CW56
 '@S9S_MB_2U_LIB.S9S_MB_2U(SCH_1):PAGE37_I8@PURE_QUANTA.SOCKET4677_AZIF0045P001C01CS(CHIPS)':
 'VCCD_HV25': CDS_PINID='VCCD_HV25';
NODE_NAME     U2 CY34
 '@S9S_MB_2U_LIB.S9S_MB_2U(SCH_1):PAGE37_I8@PURE_QUANTA.SOCKET4677_AZIF0045P001C01CS(CHIPS)':
 'VCCD_HV26': CDS_PINID='VCCD_HV26';
NODE_NAME     U2 CY36
 '@S9S_MB_2U_LIB.S9S_MB_2U(SCH_1):PAGE37_I8@PURE_QUANTA.SOCKET4677_AZIF0045P001C01CS(CHIPS)':
 'VCCD_HV27': CDS_PINID='VCCD_HV27';
NODE_NAME     U2 CY53
 '@S9S_MB_2U_LIB.S9S_MB_2U(SCH_1):PAGE37_I8@PURE_QUANTA.SOCKET4677_AZIF0045P001C01CS(CHIPS)':
 'VCCD_HV28': CDS_PINID='VCCD_HV28';
NODE_NAME     C401 1
 '@S9S_MB_2U_LIB.S9S_MB_2U(SCH_1):PAGE74_I17@PURE_QUANTA.Q_CAP(CHIPS)':
 'A': CDS_PINID='A';
NODE_NAME     C403 1
 '@S9S_MB_2U_LIB.S9S_MB_2U(SCH_1):PAGE74_I19@PURE_QUANTA.Q_CAP(CHIPS)':
 'A': CDS_PINID='A';
NODE_NAME     C499 1
 '@S9S_MB_2U_LIB.S9S_MB_2U(SCH_1):PAGE76_I18@PURE_QUANTA.Q_CAP(CHIPS)':
 'A': CDS_PINID='A';
NODE_NAME     C503 1
 '@S9S_MB_2U_LIB.S9S_MB_2U(SCH_1):PAGE76_I20@PURE_QUANTA.Q_CAP(CHIPS)':
 'A': CDS_PINID='A';
NODE_NAME     R181 2
 '@S9S_MB_2U_LIB.S9S_MB_2U(SCH_1):PAGE124_I68@PURE_QUANTA.Q_RES(CHIPS)':
 'B': CDS_PINID='B';
NODE_NAME     R179 2
 '@S9S_MB_2U_LIB.S9S_MB_2U(SCH_1):PAGE124_I70@PURE_QUANTA.Q_RES(CHIPS)':
 'B': CDS_PINID='B';
NODE_NAME     R177 2
 '@S9S_MB_2U_LIB.S9S_MB_2U(SCH_1):PAGE124_I72@PURE_QUANTA.Q_RES(CHIPS)':
 'B': CDS_PINID='B';
NODE_NAME     R840 1
 '@S9S_MB_2U_LIB.S9S_MB_2U(SCH_1):PAGE129_I119@PURE_QUANTA.Q_RES(CHIPS)':
 'A': CDS_PINID='A';
NODE_NAME     R841 1
 '@S9S_MB_2U_LIB.S9S_MB_2U(SCH_1):PAGE129_I121@PURE_QUANTA.Q_RES(CHIPS)':
 'A': CDS_PINID='A';
NODE_NAME     R842 1
 '@S9S_MB_2U_LIB.S9S_MB_2U(SCH_1):PAGE129_I123@PURE_QUANTA.Q_RES(CHIPS)':
 'A': CDS_PINID='A';
NODE_NAME     R839 1
 '@S9S_MB_2U_LIB.S9S_MB_2U(SCH_1):PAGE129_I125@PURE_QUANTA.Q_RES(CHIPS)':
 'A': CDS_PINID='A';
NODE_NAME     R175 2
 '@S9S_MB_2U_LIB.S9S_MB_2U(SCH_1):PAGE124_I76@PURE_QUANTA.Q_RES(CHIPS)':
 'B': CDS_PINID='B';
NODE_NAME     C399 1
 '@S9S_MB_2U_LIB.S9S_MB_2U(SCH_1):PAGE74_I11@PURE_QUANTA.Q_CAP(CHIPS)':
 'A': CDS_PINID='A';
NODE_NAME     C405 1
 '@S9S_MB_2U_LIB.S9S_MB_2U(SCH_1):PAGE74_I34@PURE_QUANTA.Q_CAP(CHIPS)':
 'A': CDS_PINID='A';
NODE_NAME     C491 1
 '@S9S_MB_2U_LIB.S9S_MB_2U(SCH_1):PAGE75_I13@PURE_QUANTA.Q_CAP(CHIPS)':
 'A': CDS_PINID='A';
NODE_NAME     C495 1
 '@S9S_MB_2U_LIB.S9S_MB_2U(SCH_1):PAGE75_I18@PURE_QUANTA.Q_CAP(CHIPS)':
 'A': CDS_PINID='A';
NODE_NAME     C515 1
 '@S9S_MB_2U_LIB.S9S_MB_2U(SCH_1):PAGE75_I19@PURE_QUANTA.Q_CAP(CHIPS)':
 'A': CDS_PINID='A';
NODE_NAME     C518 1
 '@S9S_MB_2U_LIB.S9S_MB_2U(SCH_1):PAGE75_I31@PURE_QUANTA.Q_CAP(CHIPS)':
 'A': CDS_PINID='A';
NODE_NAME     C507 1
 '@S9S_MB_2U_LIB.S9S_MB_2U(SCH_1):PAGE76_I21@PURE_QUANTA.Q_CAP(CHIPS)':
 'A': CDS_PINID='A';
NODE_NAME     C511 1
 '@S9S_MB_2U_LIB.S9S_MB_2U(SCH_1):PAGE76_I43@PURE_QUANTA.Q_CAP(CHIPS)':
 'A': CDS_PINID='A';
NODE_NAME     PR1785 2
 '@S9S_MB_2U_LIB.S9S_MB_2U(SCH_1):PAGE265_I17@PURE_QUANTA.Q_RES(CHIPS)':
 'B': CDS_PINID='B';
NODE_NAME     PC641 1
 '@S9S_MB_2U_LIB.S9S_MB_2U(SCH_1):PAGE265_I25@PURE_QUANTA.Q_CAP(CHIPS)':
 'A': CDS_PINID='A';
NODE_NAME     PC1910 1
 '@S9S_MB_2U_LIB.S9S_MB_2U(SCH_1):PAGE265_I26@PURE_QUANTA.Q_CAPP(CHIPS)':
 'A': CDS_PINID='A';
NODE_NAME     PC642 1
 '@S9S_MB_2U_LIB.S9S_MB_2U(SCH_1):PAGE265_I28@PURE_QUANTA.Q_CAP(CHIPS)':
 'A': CDS_PINID='A';
NODE_NAME     PC1 1
 '@S9S_MB_2U_LIB.S9S_MB_2U(SCH_1):PAGE265_I29@PURE_QUANTA.Q_CAP(CHIPS)':
 'A': CDS_PINID='A';
NODE_NAME     PC1645 1
 '@S9S_MB_2U_LIB.S9S_MB_2U(SCH_1):PAGE265_I34@PURE_QUANTA.Q_CAPP(CHIPS)':
 'A': CDS_PINID='A';
NODE_NAME     PR4237 1
 '@S9S_MB_2U_LIB.S9S_MB_2U(SCH_1):PAGE265_I37@PURE_QUANTA.Q_RES(CHIPS)':
 'A': CDS_PINID='A';
NODE_NAME     PC639 1
 '@S9S_MB_2U_LIB.S9S_MB_2U(SCH_1):PAGE265_I24@PURE_QUANTA.Q_CAP(CHIPS)':
 'A': CDS_PINID='A';
NODE_NAME     PC1644 1
 '@S9S_MB_2U_LIB.S9S_MB_2U(SCH_1):PAGE265_I27@PURE_QUANTA.Q_CAPP(CHIPS)':
 'A': CDS_PINID='A';
NODE_NAME     PR592 2
 '@S9S_MB_2U_LIB.S9S_MB_2U(SCH_1):PAGE264_I31@PURE_QUANTA.Q_RES(CHIPS)':
 'B': CDS_PINID='B';
NODE_NAME     PL35 2
 '@S9S_MB_2U_LIB.S9S_MB_2U(SCH_1):PAGE265_I30@PURE_QUANTA.Q_INDUCTOR(CHIPS)':
 '2': CDS_PINID='\2\';
NET_NAME
'PVCCD_HV_CPU0_ACSP1'
 '@S9S_MB_2U_LIB.S9S_MB_2U(SCH_1):PVCCD_HV_CPU0_ACSP1':
 C_SIGNAL='@s9s_mb_2u_lib.s9s_mb_2u(sch_1):pvccd_hv_cpu0_acsp1';
NODE_NAME     PU35 23
 '@S9S_MB_2U_LIB.S9S_MB_2U(SCH_1):PAGE264_I53@PURE_QUANTA.ISL69260IRAZT(CHIPS)':
 'CS7': CDS_PINID='CS7';
NODE_NAME     PU36 38
 '@S9S_MB_2U_LIB.S9S_MB_2U(SCH_1):PAGE265_I8@PURE_QUANTA.ISL99390FRZTR5935(CHIPS)':
 'IOUT': CDS_PINID='IOUT';
NET_NAME
'PVCCD_HV_CPU0_ADDR'
 '@S9S_MB_2U_LIB.S9S_MB_2U(SCH_1):PVCCD_HV_CPU0_ADDR':
 C_SIGNAL='@s9s_mb_2u_lib.s9s_mb_2u(sch_1):pvccd_hv_cpu0_addr';
NODE_NAME     PU35 34
 '@S9S_MB_2U_LIB.S9S_MB_2U(SCH_1):PAGE264_I53@PURE_QUANTA.ISL69260IRAZT(CHIPS)':
 'ADDR_CFG': CDS_PINID='ADDR_CFG';
NODE_NAME     PR357 2
 '@S9S_MB_2U_LIB.S9S_MB_2U(SCH_1):PAGE264_I5@PURE_QUANTA.Q_RES(CHIPS)':
 'B': CDS_PINID='B';
NODE_NAME     PR358 2
 '@S9S_MB_2U_LIB.S9S_MB_2U(SCH_1):PAGE264_I95@PURE_QUANTA.Q_RES(CHIPS)':
 'B': CDS_PINID='B';
NET_NAME
'PVCCD_HV_CPU0_APWM1'
 '@S9S_MB_2U_LIB.S9S_MB_2U(SCH_1):PVCCD_HV_CPU0_APWM1':
 C_SIGNAL='@s9s_mb_2u_lib.s9s_mb_2u(sch_1):pvccd_hv_cpu0_apwm1';
NODE_NAME     PU35 8
 '@S9S_MB_2U_LIB.S9S_MB_2U(SCH_1):PAGE264_I53@PURE_QUANTA.ISL69260IRAZT(CHIPS)':
 'PWM7': CDS_PINID='PWM7';
NODE_NAME     PU36 34
 '@S9S_MB_2U_LIB.S9S_MB_2U(SCH_1):PAGE265_I8@PURE_QUANTA.ISL99390FRZTR5935(CHIPS)':
 'PWM': CDS_PINID='PWM';
NET_NAME
'PVCCD_HV_CPU0_ATSEN'
 '@S9S_MB_2U_LIB.S9S_MB_2U(SCH_1):PVCCD_HV_CPU0_ATSEN':
 C_SIGNAL='@s9s_mb_2u_lib.s9s_mb_2u(sch_1):pvccd_hv_cpu0_atsen';
NODE_NAME     PU35 35
 '@S9S_MB_2U_LIB.S9S_MB_2U(SCH_1):PAGE264_I53@PURE_QUANTA.ISL69260IRAZT(CHIPS)':
 'TEMP0': CDS_PINID='TEMP0';
NODE_NAME     PU36 36
 '@S9S_MB_2U_LIB.S9S_MB_2U(SCH_1):PAGE265_I8@PURE_QUANTA.ISL99390FRZTR5935(CHIPS)':
 'TOUT_FLT': CDS_PINID='TOUT_FLT';
NODE_NAME     PR634 1
 '@S9S_MB_2U_LIB.S9S_MB_2U(SCH_1):PAGE264_I57@PURE_QUANTA.Q_RES(CHIPS)':
 'A': CDS_PINID='A';
NODE_NAME     PC631 1
 '@S9S_MB_2U_LIB.S9S_MB_2U(SCH_1):PAGE264_I56@PURE_QUANTA.Q_CAP(CHIPS)':
 'A': CDS_PINID='A';
NET_NAME
'PVCCD_HV_CPU0_EN_R'
 '@S9S_MB_2U_LIB.S9S_MB_2U(SCH_1):PVCCD_HV_CPU0_EN_R':
 C_SIGNAL='@s9s_mb_2u_lib.s9s_mb_2u(sch_1):pvccd_hv_cpu0_en_r';
NODE_NAME     R363 2
 '@S9S_MB_2U_LIB.S9S_MB_2U(SCH_1):PAGE264_I45@PURE_QUANTA.Q_RES(CHIPS)':
 'B': CDS_PINID='B';
NODE_NAME     PU35 13
 '@S9S_MB_2U_LIB.S9S_MB_2U(SCH_1):PAGE264_I53@PURE_QUANTA.ISL69260IRAZT(CHIPS)':
 'EN0': CDS_PINID='EN0';
NET_NAME
'PVCCD_HV_CPU0_FAULT'
 '@S9S_MB_2U_LIB.S9S_MB_2U(SCH_1):PVCCD_HV_CPU0_FAULT':
 C_SIGNAL='@s9s_mb_2u_lib.s9s_mb_2u(sch_1):pvccd_hv_cpu0_fault';
NODE_NAME     PU35 33
 '@S9S_MB_2U_LIB.S9S_MB_2U(SCH_1):PAGE264_I53@PURE_QUANTA.ISL69260IRAZT(CHIPS)':
 'CFP': CDS_PINID='CFP';
NODE_NAME     PR372 2
 '@S9S_MB_2U_LIB.S9S_MB_2U(SCH_1):PAGE264_I14@PURE_QUANTA.Q_RES(CHIPS)':
 'B': CDS_PINID='B';
NET_NAME
'PVCCD_HV_CPU0_ISENSE_N'
 '@S9S_MB_2U_LIB.S9S_MB_2U(SCH_1):PVCCD_HV_CPU0_ISENSE_N':
 C_SIGNAL='@s9s_mb_2u_lib.s9s_mb_2u(sch_1):pvccd_hv_cpu0_isense_n';
NODE_NAME     PR373 1
 '@S9S_MB_2U_LIB.S9S_MB_2U(SCH_1):PAGE264_I48@PURE_QUANTA.Q_RES(CHIPS)':
 'A': CDS_PINID='A';
NODE_NAME     PC628 1
 '@S9S_MB_2U_LIB.S9S_MB_2U(SCH_1):PAGE264_I50@PURE_QUANTA.Q_CAP(CHIPS)':
 'A': CDS_PINID='A';
NODE_NAME     PU35 38
 '@S9S_MB_2U_LIB.S9S_MB_2U(SCH_1):PAGE264_I53@PURE_QUANTA.ISL69260IRAZT(CHIPS)':
 'VINSEN||VSYS': CDS_PINID='\vinsen||vsys\';
NODE_NAME     PR1390 2
 '@S9S_MB_2U_LIB.S9S_MB_2U(SCH_1):PAGE264_I10@PURE_QUANTA.Q_RES(CHIPS)':
 'B': CDS_PINID='B';
NODE_NAME     PC813 1
 '@S9S_MB_2U_LIB.S9S_MB_2U(SCH_1):PAGE264_I51@PURE_QUANTA.Q_CAP(CHIPS)':
 'A': CDS_PINID='A';
NET_NAME
'PVCCD_HV_CPU0_ISENSE_P'
 '@S9S_MB_2U_LIB.S9S_MB_2U(SCH_1):PVCCD_HV_CPU0_ISENSE_P':
 C_SIGNAL='@s9s_mb_2u_lib.s9s_mb_2u(sch_1):pvccd_hv_cpu0_isense_p';
NODE_NAME     PU35 37
 '@S9S_MB_2U_LIB.S9S_MB_2U(SCH_1):PAGE264_I53@PURE_QUANTA.ISL69260IRAZT(CHIPS)':
 'VMON||IINSEN||VSYS||ISYS': CDS_PINID='\vmon||iinsen||vsys||isys\';
NODE_NAME     PR369 1
 '@S9S_MB_2U_LIB.S9S_MB_2U(SCH_1):PAGE264_I7@PURE_QUANTA.Q_RES(CHIPS)':
 'A': CDS_PINID='A';
NODE_NAME     PC624 1
 '@S9S_MB_2U_LIB.S9S_MB_2U(SCH_1):PAGE264_I9@PURE_QUANTA.Q_CAP(CHIPS)':
 'A': CDS_PINID='A';
NODE_NAME     PR1380 2
 '@S9S_MB_2U_LIB.S9S_MB_2U(SCH_1):PAGE264_I11@PURE_QUANTA.Q_RES(CHIPS)':
 'B': CDS_PINID='B';
NODE_NAME     PC813 2
 '@S9S_MB_2U_LIB.S9S_MB_2U(SCH_1):PAGE264_I51@PURE_QUANTA.Q_CAP(CHIPS)':
 'B': CDS_PINID='B';
NET_NAME
'PVCCD_HV_CPU0_ISYS_R'
 '@S9S_MB_2U_LIB.S9S_MB_2U(SCH_1):PVCCD_HV_CPU0_ISYS_R':
 C_SIGNAL='@s9s_mb_2u_lib.s9s_mb_2u(sch_1):pvccd_hv_cpu0_isys_r';
NODE_NAME     PU35 36
 '@S9S_MB_2U_LIB.S9S_MB_2U(SCH_1):PAGE264_I53@PURE_QUANTA.ISL69260IRAZT(CHIPS)':
 'TEMP1||ISYS': CDS_PINID='\temp1||isys\';
NODE_NAME     PR1311 1
 '@S9S_MB_2U_LIB.S9S_MB_2U(SCH_1):PAGE264_I59@PURE_QUANTA.Q_RES(CHIPS)':
 'A': CDS_PINID='A';
NODE_NAME     PR409 1
 '@S9S_MB_2U_LIB.S9S_MB_2U(SCH_1):PAGE264_I63@PURE_QUANTA.Q_RES(CHIPS)':
 'A': CDS_PINID='A';
NET_NAME
'PVCCD_HV_CPU0_LSET1'
 '@S9S_MB_2U_LIB.S9S_MB_2U(SCH_1):PVCCD_HV_CPU0_LSET1':
 C_SIGNAL='@s9s_mb_2u_lib.s9s_mb_2u(sch_1):pvccd_hv_cpu0_lset1';
NODE_NAME     PR2718 1
 '@S9S_MB_2U_LIB.S9S_MB_2U(SCH_1):PAGE265_I3@PURE_QUANTA.Q_RES(CHIPS)':
 'A': CDS_PINID='A';
NODE_NAME     PU36 37
 '@S9S_MB_2U_LIB.S9S_MB_2U(SCH_1):PAGE265_I8@PURE_QUANTA.ISL99390FRZTR5935(CHIPS)':
 'LSET': CDS_PINID='LSET';
NET_NAME
'PVCCD_HV_CPU0_NVDIMM_ISENSE'
 '@S9S_MB_2U_LIB.S9S_MB_2U(SCH_1):PVCCD_HV_CPU0_NVDIMM_ISENSE':
 C_SIGNAL='@s9s_mb_2u_lib.s9s_mb_2u(sch_1):pvccd_hv_cpu0_nvdimm_isense';
NODE_NAME     PR409 2
 '@S9S_MB_2U_LIB.S9S_MB_2U(SCH_1):PAGE264_I63@PURE_QUANTA.Q_RES(CHIPS)':
 'B': CDS_PINID='B';
NODE_NAME     U102 3
 '@S9S_MB_2U_LIB.S9S_MB_2U(SCH_1):PAGE240_I29@PURE_QUANTA.INA183A1IDBVR(CHIPS)':
 'OUT': CDS_PINID='\out\';
NET_NAME
'PVCCD_HV_CPU0_PIN_ALT'
 '@S9S_MB_2U_LIB.S9S_MB_2U(SCH_1):PVCCD_HV_CPU0_PIN_ALT':
 C_SIGNAL='@s9s_mb_2u_lib.s9s_mb_2u(sch_1):pvccd_hv_cpu0_pin_alt';
NODE_NAME     PU35 15
 '@S9S_MB_2U_LIB.S9S_MB_2U(SCH_1):PAGE264_I53@PURE_QUANTA.ISL69260IRAZT(CHIPS)':
 'NPINALERT#||NPSYSCRIT#': CDS_PINID='\npinalert#||npsyscrit#\';
NODE_NAME     PR370 2
 '@S9S_MB_2U_LIB.S9S_MB_2U(SCH_1):PAGE264_I13@PURE_QUANTA.Q_RES(CHIPS)':
 'B': CDS_PINID='B';
NET_NAME
'PVCCD_HV_CPU0_VCC'
 '@S9S_MB_2U_LIB.S9S_MB_2U(SCH_1):PVCCD_HV_CPU0_VCC':
 C_SIGNAL='@s9s_mb_2u_lib.s9s_mb_2u(sch_1):pvccd_hv_cpu0_vcc';
NODE_NAME     PC629 1
 '@S9S_MB_2U_LIB.S9S_MB_2U(SCH_1):PAGE264_I72@PURE_QUANTA.Q_CAP(CHIPS)':
 'A': CDS_PINID='A';
NODE_NAME     PU35 39
 '@S9S_MB_2U_LIB.S9S_MB_2U(SCH_1):PAGE264_I53@PURE_QUANTA.ISL69260IRAZT(CHIPS)':
 'VCC': CDS_PINID='VCC';
NODE_NAME     PC632 1
 '@S9S_MB_2U_LIB.S9S_MB_2U(SCH_1):PAGE264_I73@PURE_QUANTA.Q_CAP(CHIPS)':
 'A': CDS_PINID='A';
NODE_NAME     PR375 1
 '@S9S_MB_2U_LIB.S9S_MB_2U(SCH_1):PAGE264_I80@PURE_QUANTA.Q_RES(CHIPS)':
 'A': CDS_PINID='A';
NODE_NAME     PC2365 1
 '@S9S_MB_2U_LIB.S9S_MB_2U(SCH_1):PAGE264_I96@PURE_QUANTA.Q_CAP(CHIPS)':
 'A': CDS_PINID='A';
NET_NAME
'PVCCD_HV_CPU0_VDD1'
 '@S9S_MB_2U_LIB.S9S_MB_2U(SCH_1):PVCCD_HV_CPU0_VDD1':
 C_SIGNAL='@s9s_mb_2u_lib.s9s_mb_2u(sch_1):pvccd_hv_cpu0_vdd1';
NODE_NAME     PU36 35
 '@S9S_MB_2U_LIB.S9S_MB_2U(SCH_1):PAGE265_I8@PURE_QUANTA.ISL99390FRZTR5935(CHIPS)':
 'EN': CDS_PINID='EN';
NODE_NAME     PU36 3
 '@S9S_MB_2U_LIB.S9S_MB_2U(SCH_1):PAGE265_I8@PURE_QUANTA.ISL99390FRZTR5935(CHIPS)':
 'VCC': CDS_PINID='VCC';
NODE_NAME     PC633 1
 '@S9S_MB_2U_LIB.S9S_MB_2U(SCH_1):PAGE265_I11@PURE_QUANTA.Q_CAP(CHIPS)':
 'A': CDS_PINID='A';
NODE_NAME     PR380 2
 '@S9S_MB_2U_LIB.S9S_MB_2U(SCH_1):PAGE265_I12@PURE_QUANTA.Q_RES(CHIPS)':
 'B': CDS_PINID='B';
NET_NAME
'PVCCD_HV_CPU0_VOS'
 '@S9S_MB_2U_LIB.S9S_MB_2U(SCH_1):PVCCD_HV_CPU0_VOS':
 C_SIGNAL='@s9s_mb_2u_lib.s9s_mb_2u(sch_1):pvccd_hv_cpu0_vos';
NODE_NAME     PU36 1
 '@S9S_MB_2U_LIB.S9S_MB_2U(SCH_1):PAGE265_I8@PURE_QUANTA.ISL99390FRZTR5935(CHIPS)':
 'VOS': CDS_PINID='VOS';
NODE_NAME     PR1785 1
 '@S9S_MB_2U_LIB.S9S_MB_2U(SCH_1):PAGE265_I17@PURE_QUANTA.Q_RES(CHIPS)':
 'A': CDS_PINID='A';
NET_NAME
'PVCCD_HV_CPU0_VREF'
 '@S9S_MB_2U_LIB.S9S_MB_2U(SCH_1):PVCCD_HV_CPU0_VREF':
 C_SIGNAL='@s9s_mb_2u_lib.s9s_mb_2u(sch_1):pvccd_hv_cpu0_vref';
NODE_NAME     PU35 40
 '@S9S_MB_2U_LIB.S9S_MB_2U(SCH_1):PAGE264_I53@PURE_QUANTA.ISL69260IRAZT(CHIPS)':
 'VCCS': CDS_PINID='VCCS';
NODE_NAME     PU36 39
 '@S9S_MB_2U_LIB.S9S_MB_2U(SCH_1):PAGE265_I8@PURE_QUANTA.ISL99390FRZTR5935(CHIPS)':
 'REFIN': CDS_PINID='REFIN';
NODE_NAME     PC1354 2
 '@S9S_MB_2U_LIB.S9S_MB_2U(SCH_1):PAGE265_I7@PURE_QUANTA.Q_CAP(CHIPS)':
 'B': CDS_PINID='B';
NODE_NAME     PR357 1
 '@S9S_MB_2U_LIB.S9S_MB_2U(SCH_1):PAGE264_I5@PURE_QUANTA.Q_RES(CHIPS)':
 'A': CDS_PINID='A';
NODE_NAME     PC630 1
 '@S9S_MB_2U_LIB.S9S_MB_2U(SCH_1):PAGE264_I70@PURE_QUANTA.Q_CAP(CHIPS)':
 'A': CDS_PINID='A';
NODE_NAME     PC1196 1
 '@S9S_MB_2U_LIB.S9S_MB_2U(SCH_1):PAGE264_I71@PURE_QUANTA.Q_CAP(CHIPS)':
 'A': CDS_PINID='A';
NET_NAME
'PVCCD_HV_CPU1'
 '@S9S_MB_2U_LIB.S9S_MB_2U(SCH_1):PVCCD_HV_CPU1':
 C_SIGNAL='@s9s_mb_2u_lib.s9s_mb_2u(sch_1):pvccd_hv_cpu1',
 CDS_GLOBAL_NET='TRUE';
NODE_NAME     U1 AT36
 '@S9S_MB_2U_LIB.S9S_MB_2U(SCH_1):PAGE68_I8@PURE_QUANTA.SOCKET4677_AZIF0045P001C01CS(CHIPS)':
 'VCCD_HV0': CDS_PINID='VCCD_HV0';
NODE_NAME     U1 AT55
 '@S9S_MB_2U_LIB.S9S_MB_2U(SCH_1):PAGE68_I8@PURE_QUANTA.SOCKET4677_AZIF0045P001C01CS(CHIPS)':
 'VCCD_HV1': CDS_PINID='VCCD_HV1';
NODE_NAME     U1 AU3
 '@S9S_MB_2U_LIB.S9S_MB_2U(SCH_1):PAGE68_I8@PURE_QUANTA.SOCKET4677_AZIF0045P001C01CS(CHIPS)':
 'VCCD_HV2': CDS_PINID='VCCD_HV2';
NODE_NAME     U1 AU35
 '@S9S_MB_2U_LIB.S9S_MB_2U(SCH_1):PAGE68_I8@PURE_QUANTA.SOCKET4677_AZIF0045P001C01CS(CHIPS)':
 'VCCD_HV3': CDS_PINID='VCCD_HV3';
NODE_NAME     U1 AU54
 '@S9S_MB_2U_LIB.S9S_MB_2U(SCH_1):PAGE68_I8@PURE_QUANTA.SOCKET4677_AZIF0045P001C01CS(CHIPS)':
 'VCCD_HV4': CDS_PINID='VCCD_HV4';
NODE_NAME     U1 AU7
 '@S9S_MB_2U_LIB.S9S_MB_2U(SCH_1):PAGE68_I8@PURE_QUANTA.SOCKET4677_AZIF0045P001C01CS(CHIPS)':
 'VCCD_HV5': CDS_PINID='VCCD_HV5';
NODE_NAME     U1 AV34
 '@S9S_MB_2U_LIB.S9S_MB_2U(SCH_1):PAGE68_I8@PURE_QUANTA.SOCKET4677_AZIF0045P001C01CS(CHIPS)':
 'VCCD_HV6': CDS_PINID='VCCD_HV6';
NODE_NAME     U1 AV36
 '@S9S_MB_2U_LIB.S9S_MB_2U(SCH_1):PAGE68_I8@PURE_QUANTA.SOCKET4677_AZIF0045P001C01CS(CHIPS)':
 'VCCD_HV7': CDS_PINID='VCCD_HV7';
NODE_NAME     U1 AV53
 '@S9S_MB_2U_LIB.S9S_MB_2U(SCH_1):PAGE68_I8@PURE_QUANTA.SOCKET4677_AZIF0045P001C01CS(CHIPS)':
 'VCCD_HV8': CDS_PINID='VCCD_HV8';
NODE_NAME     U1 AV55
 '@S9S_MB_2U_LIB.S9S_MB_2U(SCH_1):PAGE68_I8@PURE_QUANTA.SOCKET4677_AZIF0045P001C01CS(CHIPS)':
 'VCCD_HV9': CDS_PINID='VCCD_HV9';
NODE_NAME     U1 BA3
 '@S9S_MB_2U_LIB.S9S_MB_2U(SCH_1):PAGE68_I8@PURE_QUANTA.SOCKET4677_AZIF0045P001C01CS(CHIPS)':
 'VCCD_HV10': CDS_PINID='VCCD_HV10';
NODE_NAME     U1 BA7
 '@S9S_MB_2U_LIB.S9S_MB_2U(SCH_1):PAGE68_I8@PURE_QUANTA.SOCKET4677_AZIF0045P001C01CS(CHIPS)':
 'VCCD_HV11': CDS_PINID='VCCD_HV11';
NODE_NAME     U1 BE11
 '@S9S_MB_2U_LIB.S9S_MB_2U(SCH_1):PAGE68_I8@PURE_QUANTA.SOCKET4677_AZIF0045P001C01CS(CHIPS)':
 'VCCD_HV12': CDS_PINID='VCCD_HV12';
NODE_NAME     U1 BE3
 '@S9S_MB_2U_LIB.S9S_MB_2U(SCH_1):PAGE68_I8@PURE_QUANTA.SOCKET4677_AZIF0045P001C01CS(CHIPS)':
 'VCCD_HV13': CDS_PINID='VCCD_HV13';
NODE_NAME     U1 BE7
 '@S9S_MB_2U_LIB.S9S_MB_2U(SCH_1):PAGE68_I8@PURE_QUANTA.SOCKET4677_AZIF0045P001C01CS(CHIPS)':
 'VCCD_HV14': CDS_PINID='VCCD_HV14';
NODE_NAME     U1 BJ11
 '@S9S_MB_2U_LIB.S9S_MB_2U(SCH_1):PAGE68_I8@PURE_QUANTA.SOCKET4677_AZIF0045P001C01CS(CHIPS)':
 'VCCD_HV15': CDS_PINID='VCCD_HV15';
NODE_NAME     U1 BJ3
 '@S9S_MB_2U_LIB.S9S_MB_2U(SCH_1):PAGE68_I8@PURE_QUANTA.SOCKET4677_AZIF0045P001C01CS(CHIPS)':
 'VCCD_HV16': CDS_PINID='VCCD_HV16';
NODE_NAME     U1 BJ7
 '@S9S_MB_2U_LIB.S9S_MB_2U(SCH_1):PAGE68_I8@PURE_QUANTA.SOCKET4677_AZIF0045P001C01CS(CHIPS)':
 'VCCD_HV17': CDS_PINID='VCCD_HV17';
NODE_NAME     U1 BN7
 '@S9S_MB_2U_LIB.S9S_MB_2U(SCH_1):PAGE68_I8@PURE_QUANTA.SOCKET4677_AZIF0045P001C01CS(CHIPS)':
 'VCCD_HV18': CDS_PINID='VCCD_HV18';
NODE_NAME     U1 CA7
 '@S9S_MB_2U_LIB.S9S_MB_2U(SCH_1):PAGE68_I8@PURE_QUANTA.SOCKET4677_AZIF0045P001C01CS(CHIPS)':
 'VCCD_HV19': CDS_PINID='VCCD_HV19';
NODE_NAME     U1 CE7
 '@S9S_MB_2U_LIB.S9S_MB_2U(SCH_1):PAGE68_I8@PURE_QUANTA.SOCKET4677_AZIF0045P001C01CS(CHIPS)':
 'VCCD_HV20': CDS_PINID='VCCD_HV20';
NODE_NAME     U1 CW35
 '@S9S_MB_2U_LIB.S9S_MB_2U(SCH_1):PAGE68_I8@PURE_QUANTA.SOCKET4677_AZIF0045P001C01CS(CHIPS)':
 'VCCD_HV21': CDS_PINID='VCCD_HV21';
NODE_NAME     U1 CW37
 '@S9S_MB_2U_LIB.S9S_MB_2U(SCH_1):PAGE68_I8@PURE_QUANTA.SOCKET4677_AZIF0045P001C01CS(CHIPS)':
 'VCCD_HV22': CDS_PINID='VCCD_HV22';
NODE_NAME     U1 CW52
 '@S9S_MB_2U_LIB.S9S_MB_2U(SCH_1):PAGE68_I8@PURE_QUANTA.SOCKET4677_AZIF0045P001C01CS(CHIPS)':
 'VCCD_HV23': CDS_PINID='VCCD_HV23';
NODE_NAME     U1 CW54
 '@S9S_MB_2U_LIB.S9S_MB_2U(SCH_1):PAGE68_I8@PURE_QUANTA.SOCKET4677_AZIF0045P001C01CS(CHIPS)':
 'VCCD_HV24': CDS_PINID='VCCD_HV24';
NODE_NAME     U1 CW56
 '@S9S_MB_2U_LIB.S9S_MB_2U(SCH_1):PAGE68_I8@PURE_QUANTA.SOCKET4677_AZIF0045P001C01CS(CHIPS)':
 'VCCD_HV25': CDS_PINID='VCCD_HV25';
NODE_NAME     U1 CY34
 '@S9S_MB_2U_LIB.S9S_MB_2U(SCH_1):PAGE68_I8@PURE_QUANTA.SOCKET4677_AZIF0045P001C01CS(CHIPS)':
 'VCCD_HV26': CDS_PINID='VCCD_HV26';
NODE_NAME     U1 CY36
 '@S9S_MB_2U_LIB.S9S_MB_2U(SCH_1):PAGE68_I8@PURE_QUANTA.SOCKET4677_AZIF0045P001C01CS(CHIPS)':
 'VCCD_HV27': CDS_PINID='VCCD_HV27';
NODE_NAME     U1 CY53
 '@S9S_MB_2U_LIB.S9S_MB_2U(SCH_1):PAGE68_I8@PURE_QUANTA.SOCKET4677_AZIF0045P001C01CS(CHIPS)':
 'VCCD_HV28': CDS_PINID='VCCD_HV28';
NODE_NAME     C423 1
 '@S9S_MB_2U_LIB.S9S_MB_2U(SCH_1):PAGE77_I7@PURE_QUANTA.Q_CAP(CHIPS)':
 'A': CDS_PINID='A';
NODE_NAME     C425 1
 '@S9S_MB_2U_LIB.S9S_MB_2U(SCH_1):PAGE77_I8@PURE_QUANTA.Q_CAP(CHIPS)':
 'A': CDS_PINID='A';
NODE_NAME     C427 1
 '@S9S_MB_2U_LIB.S9S_MB_2U(SCH_1):PAGE77_I15@PURE_QUANTA.Q_CAP(CHIPS)':
 'A': CDS_PINID='A';
NODE_NAME     C429 1
 '@S9S_MB_2U_LIB.S9S_MB_2U(SCH_1):PAGE77_I17@PURE_QUANTA.Q_CAP(CHIPS)':
 'A': CDS_PINID='A';
NODE_NAME     C451 1
 '@S9S_MB_2U_LIB.S9S_MB_2U(SCH_1):PAGE78_I24@PURE_QUANTA.Q_CAP(CHIPS)':
 'A': CDS_PINID='A';
NODE_NAME     C474 1
 '@S9S_MB_2U_LIB.S9S_MB_2U(SCH_1):PAGE78_I29@PURE_QUANTA.Q_CAP(CHIPS)':
 'A': CDS_PINID='A';
NODE_NAME     R153 2
 '@S9S_MB_2U_LIB.S9S_MB_2U(SCH_1):PAGE125_I56@PURE_QUANTA.Q_RES(CHIPS)':
 'B': CDS_PINID='B';
NODE_NAME     R151 2
 '@S9S_MB_2U_LIB.S9S_MB_2U(SCH_1):PAGE125_I58@PURE_QUANTA.Q_RES(CHIPS)':
 'B': CDS_PINID='B';
NODE_NAME     R137 2
 '@S9S_MB_2U_LIB.S9S_MB_2U(SCH_1):PAGE125_I60@PURE_QUANTA.Q_RES(CHIPS)':
 'B': CDS_PINID='B';
NODE_NAME     R135 2
 '@S9S_MB_2U_LIB.S9S_MB_2U(SCH_1):PAGE125_I62@PURE_QUANTA.Q_RES(CHIPS)':
 'B': CDS_PINID='B';
NODE_NAME     R820 1
 '@S9S_MB_2U_LIB.S9S_MB_2U(SCH_1):PAGE130_I82@PURE_QUANTA.Q_RES(CHIPS)':
 'A': CDS_PINID='A';
NODE_NAME     R821 1
 '@S9S_MB_2U_LIB.S9S_MB_2U(SCH_1):PAGE130_I84@PURE_QUANTA.Q_RES(CHIPS)':
 'A': CDS_PINID='A';
NODE_NAME     R822 1
 '@S9S_MB_2U_LIB.S9S_MB_2U(SCH_1):PAGE130_I88@PURE_QUANTA.Q_RES(CHIPS)':
 'A': CDS_PINID='A';
NODE_NAME     R819 1
 '@S9S_MB_2U_LIB.S9S_MB_2U(SCH_1):PAGE130_I90@PURE_QUANTA.Q_RES(CHIPS)':
 'A': CDS_PINID='A';
NODE_NAME     PC379 1
 '@S9S_MB_2U_LIB.S9S_MB_2U(SCH_1):PAGE283_I27@PURE_QUANTA.Q_CAP(CHIPS)':
 'A': CDS_PINID='A';
NODE_NAME     PC381 1
 '@S9S_MB_2U_LIB.S9S_MB_2U(SCH_1):PAGE283_I28@PURE_QUANTA.Q_CAP(CHIPS)':
 'A': CDS_PINID='A';
NODE_NAME     C447 1
 '@S9S_MB_2U_LIB.S9S_MB_2U(SCH_1):PAGE78_I12@PURE_QUANTA.Q_CAP(CHIPS)':
 'A': CDS_PINID='A';
NODE_NAME     C471 1
 '@S9S_MB_2U_LIB.S9S_MB_2U(SCH_1):PAGE78_I25@PURE_QUANTA.Q_CAP(CHIPS)':
 'A': CDS_PINID='A';
NODE_NAME     C455 1
 '@S9S_MB_2U_LIB.S9S_MB_2U(SCH_1):PAGE79_I19@PURE_QUANTA.Q_CAP(CHIPS)':
 'A': CDS_PINID='A';
NODE_NAME     C459 1
 '@S9S_MB_2U_LIB.S9S_MB_2U(SCH_1):PAGE79_I20@PURE_QUANTA.Q_CAP(CHIPS)':
 'A': CDS_PINID='A';
NODE_NAME     C463 1
 '@S9S_MB_2U_LIB.S9S_MB_2U(SCH_1):PAGE79_I21@PURE_QUANTA.Q_CAP(CHIPS)':
 'A': CDS_PINID='A';
NODE_NAME     C467 1
 '@S9S_MB_2U_LIB.S9S_MB_2U(SCH_1):PAGE79_I31@PURE_QUANTA.Q_CAP(CHIPS)':
 'A': CDS_PINID='A';
NODE_NAME     PR1805 2
 '@S9S_MB_2U_LIB.S9S_MB_2U(SCH_1):PAGE283_I12@PURE_QUANTA.Q_RES(CHIPS)':
 'B': CDS_PINID='B';
NODE_NAME     PR559 2
 '@S9S_MB_2U_LIB.S9S_MB_2U(SCH_1):PAGE282_I36@PURE_QUANTA.Q_RES(CHIPS)':
 'B': CDS_PINID='B';
NODE_NAME     PL17 2
 '@S9S_MB_2U_LIB.S9S_MB_2U(SCH_1):PAGE283_I14@PURE_QUANTA.Q_INDUCTOR(CHIPS)':
 '2': CDS_PINID='\2\';
NODE_NAME     PC382 1
 '@S9S_MB_2U_LIB.S9S_MB_2U(SCH_1):PAGE283_I29@PURE_QUANTA.Q_CAP(CHIPS)':
 'A': CDS_PINID='A';
NODE_NAME     PC2 1
 '@S9S_MB_2U_LIB.S9S_MB_2U(SCH_1):PAGE283_I30@PURE_QUANTA.Q_CAP(CHIPS)':
 'A': CDS_PINID='A';
NODE_NAME     PC385 1
 '@S9S_MB_2U_LIB.S9S_MB_2U(SCH_1):PAGE283_I32@PURE_QUANTA.Q_CAPP(CHIPS)':
 'A': CDS_PINID='A';
NODE_NAME     PC1940 1
 '@S9S_MB_2U_LIB.S9S_MB_2U(SCH_1):PAGE283_I25@PURE_QUANTA.Q_CAPP(CHIPS)':
 'A': CDS_PINID='A';
NODE_NAME     PC384 1
 '@S9S_MB_2U_LIB.S9S_MB_2U(SCH_1):PAGE283_I26@PURE_QUANTA.Q_CAPP(CHIPS)':
 'A': CDS_PINID='A';
NODE_NAME     PR4258 1
 '@S9S_MB_2U_LIB.S9S_MB_2U(SCH_1):PAGE283_I35@PURE_QUANTA.Q_RES(CHIPS)':
 'A': CDS_PINID='A';
NET_NAME
'PVCCD_HV_CPU1_ACSP1'
 '@S9S_MB_2U_LIB.S9S_MB_2U(SCH_1):PVCCD_HV_CPU1_ACSP1':
 C_SIGNAL='@s9s_mb_2u_lib.s9s_mb_2u(sch_1):pvccd_hv_cpu1_acsp1';
NODE_NAME     PU18 23
 '@S9S_MB_2U_LIB.S9S_MB_2U(SCH_1):PAGE282_I53@PURE_QUANTA.ISL69260IRAZT(CHIPS)':
 'CS7': CDS_PINID='CS7';
NODE_NAME     PU17 38
 '@S9S_MB_2U_LIB.S9S_MB_2U(SCH_1):PAGE283_I10@PURE_QUANTA.ISL99390FRZTR5935(CHIPS)':
 'IOUT': CDS_PINID='IOUT';
NET_NAME
'PVCCD_HV_CPU1_ADDR'
 '@S9S_MB_2U_LIB.S9S_MB_2U(SCH_1):PVCCD_HV_CPU1_ADDR':
 C_SIGNAL='@s9s_mb_2u_lib.s9s_mb_2u(sch_1):pvccd_hv_cpu1_addr';
NODE_NAME     PU18 34
 '@S9S_MB_2U_LIB.S9S_MB_2U(SCH_1):PAGE282_I53@PURE_QUANTA.ISL69260IRAZT(CHIPS)':
 'ADDR_CFG': CDS_PINID='ADDR_CFG';
NODE_NAME     PR202 2
 '@S9S_MB_2U_LIB.S9S_MB_2U(SCH_1):PAGE282_I8@PURE_QUANTA.Q_RES(CHIPS)':
 'B': CDS_PINID='B';
NODE_NAME     PR203 2
 '@S9S_MB_2U_LIB.S9S_MB_2U(SCH_1):PAGE282_I95@PURE_QUANTA.Q_RES(CHIPS)':
 'B': CDS_PINID='B';
NET_NAME
'PVCCD_HV_CPU1_APWM1'
 '@S9S_MB_2U_LIB.S9S_MB_2U(SCH_1):PVCCD_HV_CPU1_APWM1':
 C_SIGNAL='@s9s_mb_2u_lib.s9s_mb_2u(sch_1):pvccd_hv_cpu1_apwm1';
NODE_NAME     PU18 8
 '@S9S_MB_2U_LIB.S9S_MB_2U(SCH_1):PAGE282_I53@PURE_QUANTA.ISL69260IRAZT(CHIPS)':
 'PWM7': CDS_PINID='PWM7';
NODE_NAME     PU17 34
 '@S9S_MB_2U_LIB.S9S_MB_2U(SCH_1):PAGE283_I10@PURE_QUANTA.ISL99390FRZTR5935(CHIPS)':
 'PWM': CDS_PINID='PWM';
NET_NAME
'PVCCD_HV_CPU1_ATSEN'
 '@S9S_MB_2U_LIB.S9S_MB_2U(SCH_1):PVCCD_HV_CPU1_ATSEN':
 C_SIGNAL='@s9s_mb_2u_lib.s9s_mb_2u(sch_1):pvccd_hv_cpu1_atsen';
NODE_NAME     PU18 35
 '@S9S_MB_2U_LIB.S9S_MB_2U(SCH_1):PAGE282_I53@PURE_QUANTA.ISL69260IRAZT(CHIPS)':
 'TEMP0': CDS_PINID='TEMP0';
NODE_NAME     PR705 1
 '@S9S_MB_2U_LIB.S9S_MB_2U(SCH_1):PAGE282_I81@PURE_QUANTA.Q_RES(CHIPS)':
 'A': CDS_PINID='A';
NODE_NAME     PU17 36
 '@S9S_MB_2U_LIB.S9S_MB_2U(SCH_1):PAGE283_I10@PURE_QUANTA.ISL99390FRZTR5935(CHIPS)':
 'TOUT_FLT': CDS_PINID='TOUT_FLT';
NODE_NAME     PC393 1
 '@S9S_MB_2U_LIB.S9S_MB_2U(SCH_1):PAGE282_I57@PURE_QUANTA.Q_CAP(CHIPS)':
 'A': CDS_PINID='A';
NET_NAME
'PVCCD_HV_CPU1_EN_R'
 '@S9S_MB_2U_LIB.S9S_MB_2U(SCH_1):PVCCD_HV_CPU1_EN_R':
 C_SIGNAL='@s9s_mb_2u_lib.s9s_mb_2u(sch_1):pvccd_hv_cpu1_en_r';
NODE_NAME     PU18 13
 '@S9S_MB_2U_LIB.S9S_MB_2U(SCH_1):PAGE282_I53@PURE_QUANTA.ISL69260IRAZT(CHIPS)':
 'EN0': CDS_PINID='EN0';
NODE_NAME     R2577 2
 '@S9S_MB_2U_LIB.S9S_MB_2U(SCH_1):PAGE282_I43@PURE_QUANTA.Q_RES(CHIPS)':
 'B': CDS_PINID='B';
NET_NAME
'PVCCD_HV_CPU1_FAULT'
 '@S9S_MB_2U_LIB.S9S_MB_2U(SCH_1):PVCCD_HV_CPU1_FAULT':
 C_SIGNAL='@s9s_mb_2u_lib.s9s_mb_2u(sch_1):pvccd_hv_cpu1_fault';
NODE_NAME     PU18 33
 '@S9S_MB_2U_LIB.S9S_MB_2U(SCH_1):PAGE282_I53@PURE_QUANTA.ISL69260IRAZT(CHIPS)':
 'CFP': CDS_PINID='CFP';
NODE_NAME     PR217 2
 '@S9S_MB_2U_LIB.S9S_MB_2U(SCH_1):PAGE282_I20@PURE_QUANTA.Q_RES(CHIPS)':
 'B': CDS_PINID='B';
NET_NAME
'PVCCD_HV_CPU1_ISENSE_N'
 '@S9S_MB_2U_LIB.S9S_MB_2U(SCH_1):PVCCD_HV_CPU1_ISENSE_N':
 C_SIGNAL='@s9s_mb_2u_lib.s9s_mb_2u(sch_1):pvccd_hv_cpu1_isense_n';
NODE_NAME     PR218 1
 '@S9S_MB_2U_LIB.S9S_MB_2U(SCH_1):PAGE282_I48@PURE_QUANTA.Q_RES(CHIPS)':
 'A': CDS_PINID='A';
NODE_NAME     PC390 1
 '@S9S_MB_2U_LIB.S9S_MB_2U(SCH_1):PAGE282_I50@PURE_QUANTA.Q_CAP(CHIPS)':
 'A': CDS_PINID='A';
NODE_NAME     PU18 38
 '@S9S_MB_2U_LIB.S9S_MB_2U(SCH_1):PAGE282_I53@PURE_QUANTA.ISL69260IRAZT(CHIPS)':
 'VINSEN||VSYS': CDS_PINID='\vinsen||vsys\';
NODE_NAME     PC814 1
 '@S9S_MB_2U_LIB.S9S_MB_2U(SCH_1):PAGE282_I51@PURE_QUANTA.Q_CAP(CHIPS)':
 'A': CDS_PINID='A';
NODE_NAME     PR1410 2
 '@S9S_MB_2U_LIB.S9S_MB_2U(SCH_1):PAGE282_I10@PURE_QUANTA.Q_RES(CHIPS)':
 'B': CDS_PINID='B';
NET_NAME
'PVCCD_HV_CPU1_ISENSE_P'
 '@S9S_MB_2U_LIB.S9S_MB_2U(SCH_1):PVCCD_HV_CPU1_ISENSE_P':
 C_SIGNAL='@s9s_mb_2u_lib.s9s_mb_2u(sch_1):pvccd_hv_cpu1_isense_p';
NODE_NAME     PU18 37
 '@S9S_MB_2U_LIB.S9S_MB_2U(SCH_1):PAGE282_I53@PURE_QUANTA.ISL69260IRAZT(CHIPS)':
 'VMON||IINSEN||VSYS||ISYS': CDS_PINID='\vmon||iinsen||vsys||isys\';
NODE_NAME     PC386 1
 '@S9S_MB_2U_LIB.S9S_MB_2U(SCH_1):PAGE282_I13@PURE_QUANTA.Q_CAP(CHIPS)':
 'A': CDS_PINID='A';
NODE_NAME     PC814 2
 '@S9S_MB_2U_LIB.S9S_MB_2U(SCH_1):PAGE282_I51@PURE_QUANTA.Q_CAP(CHIPS)':
 'B': CDS_PINID='B';
NODE_NAME     PR1400 2
 '@S9S_MB_2U_LIB.S9S_MB_2U(SCH_1):PAGE282_I9@PURE_QUANTA.Q_RES(CHIPS)':
 'B': CDS_PINID='B';
NODE_NAME     PR214 1
 '@S9S_MB_2U_LIB.S9S_MB_2U(SCH_1):PAGE282_I11@PURE_QUANTA.Q_RES(CHIPS)':
 'A': CDS_PINID='A';
NET_NAME
'PVCCD_HV_CPU1_ISYS_R'
 '@S9S_MB_2U_LIB.S9S_MB_2U(SCH_1):PVCCD_HV_CPU1_ISYS_R':
 C_SIGNAL='@s9s_mb_2u_lib.s9s_mb_2u(sch_1):pvccd_hv_cpu1_isys_r';
NODE_NAME     PU18 36
 '@S9S_MB_2U_LIB.S9S_MB_2U(SCH_1):PAGE282_I53@PURE_QUANTA.ISL69260IRAZT(CHIPS)':
 'TEMP1||ISYS': CDS_PINID='\temp1||isys\';
NODE_NAME     PR1315 1
 '@S9S_MB_2U_LIB.S9S_MB_2U(SCH_1):PAGE282_I60@PURE_QUANTA.Q_RES(CHIPS)':
 'A': CDS_PINID='A';
NODE_NAME     PR410 1
 '@S9S_MB_2U_LIB.S9S_MB_2U(SCH_1):PAGE282_I61@PURE_QUANTA.Q_RES(CHIPS)':
 'A': CDS_PINID='A';
NET_NAME
'PVCCD_HV_CPU1_LSET1'
 '@S9S_MB_2U_LIB.S9S_MB_2U(SCH_1):PVCCD_HV_CPU1_LSET1':
 C_SIGNAL='@s9s_mb_2u_lib.s9s_mb_2u(sch_1):pvccd_hv_cpu1_lset1';
NODE_NAME     PR1746 1
 '@S9S_MB_2U_LIB.S9S_MB_2U(SCH_1):PAGE283_I3@PURE_QUANTA.Q_RES(CHIPS)':
 'A': CDS_PINID='A';
NODE_NAME     PU17 37
 '@S9S_MB_2U_LIB.S9S_MB_2U(SCH_1):PAGE283_I10@PURE_QUANTA.ISL99390FRZTR5935(CHIPS)':
 'LSET': CDS_PINID='LSET';
NET_NAME
'PVCCD_HV_CPU1_NVDIMM_ISENSE'
 '@S9S_MB_2U_LIB.S9S_MB_2U(SCH_1):PVCCD_HV_CPU1_NVDIMM_ISENSE':
 C_SIGNAL='@s9s_mb_2u_lib.s9s_mb_2u(sch_1):pvccd_hv_cpu1_nvdimm_isense';
NODE_NAME     U103 3
 '@S9S_MB_2U_LIB.S9S_MB_2U(SCH_1):PAGE240_I22@PURE_QUANTA.INA183A1IDBVR(CHIPS)':
 'OUT': CDS_PINID='\out\';
NODE_NAME     PR410 2
 '@S9S_MB_2U_LIB.S9S_MB_2U(SCH_1):PAGE282_I61@PURE_QUANTA.Q_RES(CHIPS)':
 'B': CDS_PINID='B';
NET_NAME
'PVCCD_HV_CPU1_PIN_ALT'
 '@S9S_MB_2U_LIB.S9S_MB_2U(SCH_1):PVCCD_HV_CPU1_PIN_ALT':
 C_SIGNAL='@s9s_mb_2u_lib.s9s_mb_2u(sch_1):pvccd_hv_cpu1_pin_alt';
NODE_NAME     PU18 15
 '@S9S_MB_2U_LIB.S9S_MB_2U(SCH_1):PAGE282_I53@PURE_QUANTA.ISL69260IRAZT(CHIPS)':
 'NPINALERT#||NPSYSCRIT#': CDS_PINID='\npinalert#||npsyscrit#\';
NODE_NAME     PR215 2
 '@S9S_MB_2U_LIB.S9S_MB_2U(SCH_1):PAGE282_I18@PURE_QUANTA.Q_RES(CHIPS)':
 'B': CDS_PINID='B';
NET_NAME
'PVCCD_HV_CPU1_VCC'
 '@S9S_MB_2U_LIB.S9S_MB_2U(SCH_1):PVCCD_HV_CPU1_VCC':
 C_SIGNAL='@s9s_mb_2u_lib.s9s_mb_2u(sch_1):pvccd_hv_cpu1_vcc';
NODE_NAME     PU18 39
 '@S9S_MB_2U_LIB.S9S_MB_2U(SCH_1):PAGE282_I53@PURE_QUANTA.ISL69260IRAZT(CHIPS)':
 'VCC': CDS_PINID='VCC';
NODE_NAME     PC391 1
 '@S9S_MB_2U_LIB.S9S_MB_2U(SCH_1):PAGE282_I69@PURE_QUANTA.Q_CAP(CHIPS)':
 'A': CDS_PINID='A';
NODE_NAME     PC394 1
 '@S9S_MB_2U_LIB.S9S_MB_2U(SCH_1):PAGE282_I77@PURE_QUANTA.Q_CAP(CHIPS)':
 'A': CDS_PINID='A';
NODE_NAME     PR220 1
 '@S9S_MB_2U_LIB.S9S_MB_2U(SCH_1):PAGE282_I78@PURE_QUANTA.Q_RES(CHIPS)':
 'A': CDS_PINID='A';
NODE_NAME     PC2368 1
 '@S9S_MB_2U_LIB.S9S_MB_2U(SCH_1):PAGE282_I96@PURE_QUANTA.Q_CAP(CHIPS)':
 'A': CDS_PINID='A';
NET_NAME
'PVCCD_HV_CPU1_VDD1'
 '@S9S_MB_2U_LIB.S9S_MB_2U(SCH_1):PVCCD_HV_CPU1_VDD1':
 C_SIGNAL='@s9s_mb_2u_lib.s9s_mb_2u(sch_1):pvccd_hv_cpu1_vdd1';
NODE_NAME     PC373 1
 '@S9S_MB_2U_LIB.S9S_MB_2U(SCH_1):PAGE283_I15@PURE_QUANTA.Q_CAP(CHIPS)':
 'A': CDS_PINID='A';
NODE_NAME     PU17 35
 '@S9S_MB_2U_LIB.S9S_MB_2U(SCH_1):PAGE283_I10@PURE_QUANTA.ISL99390FRZTR5935(CHIPS)':
 'EN': CDS_PINID='EN';
NODE_NAME     PU17 3
 '@S9S_MB_2U_LIB.S9S_MB_2U(SCH_1):PAGE283_I10@PURE_QUANTA.ISL99390FRZTR5935(CHIPS)':
 'VCC': CDS_PINID='VCC';
NODE_NAME     PR200 2
 '@S9S_MB_2U_LIB.S9S_MB_2U(SCH_1):PAGE283_I16@PURE_QUANTA.Q_RES(CHIPS)':
 'B': CDS_PINID='B';
NET_NAME
'PVCCD_HV_CPU1_VOS'
 '@S9S_MB_2U_LIB.S9S_MB_2U(SCH_1):PVCCD_HV_CPU1_VOS':
 C_SIGNAL='@s9s_mb_2u_lib.s9s_mb_2u(sch_1):pvccd_hv_cpu1_vos';
NODE_NAME     PR1805 1
 '@S9S_MB_2U_LIB.S9S_MB_2U(SCH_1):PAGE283_I12@PURE_QUANTA.Q_RES(CHIPS)':
 'A': CDS_PINID='A';
NODE_NAME     PU17 1
 '@S9S_MB_2U_LIB.S9S_MB_2U(SCH_1):PAGE283_I10@PURE_QUANTA.ISL99390FRZTR5935(CHIPS)':
 'VOS': CDS_PINID='VOS';
NET_NAME
'PVCCD_HV_CPU1_VREF'
 '@S9S_MB_2U_LIB.S9S_MB_2U(SCH_1):PVCCD_HV_CPU1_VREF':
 C_SIGNAL='@s9s_mb_2u_lib.s9s_mb_2u(sch_1):pvccd_hv_cpu1_vref';
NODE_NAME     PC1371 2
 '@S9S_MB_2U_LIB.S9S_MB_2U(SCH_1):PAGE283_I8@PURE_QUANTA.Q_CAP(CHIPS)':
 'B': CDS_PINID='B';
NODE_NAME     PU18 40
 '@S9S_MB_2U_LIB.S9S_MB_2U(SCH_1):PAGE282_I53@PURE_QUANTA.ISL69260IRAZT(CHIPS)':
 'VCCS': CDS_PINID='VCCS';
NODE_NAME     PU17 39
 '@S9S_MB_2U_LIB.S9S_MB_2U(SCH_1):PAGE283_I10@PURE_QUANTA.ISL99390FRZTR5935(CHIPS)':
 'REFIN': CDS_PINID='REFIN';
NODE_NAME     PC392 1
 '@S9S_MB_2U_LIB.S9S_MB_2U(SCH_1):PAGE282_I68@PURE_QUANTA.Q_CAP(CHIPS)':
 'A': CDS_PINID='A';
NODE_NAME     PC1289 1
 '@S9S_MB_2U_LIB.S9S_MB_2U(SCH_1):PAGE282_I74@PURE_QUANTA.Q_CAP(CHIPS)':
 'A': CDS_PINID='A';
NODE_NAME     PR202 1
 '@S9S_MB_2U_LIB.S9S_MB_2U(SCH_1):PAGE282_I8@PURE_QUANTA.Q_RES(CHIPS)':
 'A': CDS_PINID='A';
NET_NAME
'PVCCFA_EHV_CPU0'
 '@S9S_MB_2U_LIB.S9S_MB_2U(SCH_1):PVCCFA_EHV_CPU0':
 C_SIGNAL='@s9s_mb_2u_lib.s9s_mb_2u(sch_1):pvccfa_ehv_cpu0',
 CDS_GLOBAL_NET='TRUE';
NODE_NAME     U2 AA3
 '@S9S_MB_2U_LIB.S9S_MB_2U(SCH_1):PAGE37_I8@PURE_QUANTA.SOCKET4677_AZIF0045P001C01CS(CHIPS)':
 'VCCFA_EHV0': CDS_PINID='VCCFA_EHV0';
NODE_NAME     U2 AE3
 '@S9S_MB_2U_LIB.S9S_MB_2U(SCH_1):PAGE37_I8@PURE_QUANTA.SOCKET4677_AZIF0045P001C01CS(CHIPS)':
 'VCCFA_EHV1': CDS_PINID='VCCFA_EHV1';
NODE_NAME     U2 AJ3
 '@S9S_MB_2U_LIB.S9S_MB_2U(SCH_1):PAGE37_I8@PURE_QUANTA.SOCKET4677_AZIF0045P001C01CS(CHIPS)':
 'VCCFA_EHV2': CDS_PINID='VCCFA_EHV2';
NODE_NAME     U2 AN3
 '@S9S_MB_2U_LIB.S9S_MB_2U(SCH_1):PAGE37_I8@PURE_QUANTA.SOCKET4677_AZIF0045P001C01CS(CHIPS)':
 'VCCFA_EHV3': CDS_PINID='VCCFA_EHV3';
NODE_NAME     U2 AT61
 '@S9S_MB_2U_LIB.S9S_MB_2U(SCH_1):PAGE37_I8@PURE_QUANTA.SOCKET4677_AZIF0045P001C01CS(CHIPS)':
 'VCCFA_EHV4': CDS_PINID='VCCFA_EHV4';
NODE_NAME     U2 AU60
 '@S9S_MB_2U_LIB.S9S_MB_2U(SCH_1):PAGE37_I8@PURE_QUANTA.SOCKET4677_AZIF0045P001C01CS(CHIPS)':
 'VCCFA_EHV5': CDS_PINID='VCCFA_EHV5';
NODE_NAME     U2 AV61
 '@S9S_MB_2U_LIB.S9S_MB_2U(SCH_1):PAGE37_I8@PURE_QUANTA.SOCKET4677_AZIF0045P001C01CS(CHIPS)':
 'VCCFA_EHV6': CDS_PINID='VCCFA_EHV6';
NODE_NAME     U2 AW60
 '@S9S_MB_2U_LIB.S9S_MB_2U(SCH_1):PAGE37_I8@PURE_QUANTA.SOCKET4677_AZIF0045P001C01CS(CHIPS)':
 'VCCFA_EHV7': CDS_PINID='VCCFA_EHV7';
NODE_NAME     U2 N3
 '@S9S_MB_2U_LIB.S9S_MB_2U(SCH_1):PAGE37_I8@PURE_QUANTA.SOCKET4677_AZIF0045P001C01CS(CHIPS)':
 'VCCFA_EHV8': CDS_PINID='VCCFA_EHV8';
NODE_NAME     U2 U3
 '@S9S_MB_2U_LIB.S9S_MB_2U(SCH_1):PAGE37_I8@PURE_QUANTA.SOCKET4677_AZIF0045P001C01CS(CHIPS)':
 'VCCFA_EHV9': CDS_PINID='VCCFA_EHV9';
NODE_NAME     C419 1
 '@S9S_MB_2U_LIB.S9S_MB_2U(SCH_1):PAGE74_I98@PURE_QUANTA.Q_CAP(CHIPS)':
 'A': CDS_PINID='A';
NODE_NAME     C421 1
 '@S9S_MB_2U_LIB.S9S_MB_2U(SCH_1):PAGE74_I103@PURE_QUANTA.Q_CAP(CHIPS)':
 'A': CDS_PINID='A';
NODE_NAME     PC181 1
 '@S9S_MB_2U_LIB.S9S_MB_2U(SCH_1):PAGE262_I28@PURE_QUANTA.Q_CAP(CHIPS)':
 'A': CDS_PINID='A';
NODE_NAME     PC184 1
 '@S9S_MB_2U_LIB.S9S_MB_2U(SCH_1):PAGE262_I31@PURE_QUANTA.Q_CAP(CHIPS)':
 'A': CDS_PINID='A';
NODE_NAME     C420 1
 '@S9S_MB_2U_LIB.S9S_MB_2U(SCH_1):PAGE74_I100@PURE_QUANTA.Q_CAP(CHIPS)':
 'A': CDS_PINID='A';
NODE_NAME     C422 1
 '@S9S_MB_2U_LIB.S9S_MB_2U(SCH_1):PAGE74_I107@PURE_QUANTA.Q_CAP(CHIPS)':
 'A': CDS_PINID='A';
NODE_NAME     C492 1
 '@S9S_MB_2U_LIB.S9S_MB_2U(SCH_1):PAGE75_I11@PURE_QUANTA.Q_CAP(CHIPS)':
 'A': CDS_PINID='A';
NODE_NAME     C496 1
 '@S9S_MB_2U_LIB.S9S_MB_2U(SCH_1):PAGE75_I16@PURE_QUANTA.Q_CAP(CHIPS)':
 'A': CDS_PINID='A';
NODE_NAME     C500 1
 '@S9S_MB_2U_LIB.S9S_MB_2U(SCH_1):PAGE76_I9@PURE_QUANTA.Q_CAP(CHIPS)':
 'A': CDS_PINID='A';
NODE_NAME     C504 1
 '@S9S_MB_2U_LIB.S9S_MB_2U(SCH_1):PAGE76_I10@PURE_QUANTA.Q_CAP(CHIPS)':
 'A': CDS_PINID='A';
NODE_NAME     C508 1
 '@S9S_MB_2U_LIB.S9S_MB_2U(SCH_1):PAGE76_I11@PURE_QUANTA.Q_CAP(CHIPS)':
 'A': CDS_PINID='A';
NODE_NAME     C512 1
 '@S9S_MB_2U_LIB.S9S_MB_2U(SCH_1):PAGE76_I32@PURE_QUANTA.Q_CAP(CHIPS)':
 'A': CDS_PINID='A';
NODE_NAME     C516 1
 '@S9S_MB_2U_LIB.S9S_MB_2U(SCH_1):PAGE76_I33@PURE_QUANTA.Q_CAP(CHIPS)':
 'A': CDS_PINID='A';
NODE_NAME     C519 1
 '@S9S_MB_2U_LIB.S9S_MB_2U(SCH_1):PAGE76_I35@PURE_QUANTA.Q_CAP(CHIPS)':
 'A': CDS_PINID='A';
NODE_NAME     PR522 2
 '@S9S_MB_2U_LIB.S9S_MB_2U(SCH_1):PAGE260_I40@PURE_QUANTA.Q_RES(CHIPS)':
 'B': CDS_PINID='B';
NODE_NAME     PL3 2
 '@S9S_MB_2U_LIB.S9S_MB_2U(SCH_1):PAGE262_I29@PURE_QUANTA.Q_INDUCTOR(CHIPS)':
 '2': CDS_PINID='\2\';
NODE_NAME     PC2180 1
 '@S9S_MB_2U_LIB.S9S_MB_2U(SCH_1):PAGE262_I33@PURE_QUANTA.Q_CAPP(CHIPS)':
 'A': CDS_PINID='A';
NODE_NAME     PC186 1
 '@S9S_MB_2U_LIB.S9S_MB_2U(SCH_1):PAGE262_I32@PURE_QUANTA.Q_CAP(CHIPS)':
 'A': CDS_PINID='A';
NODE_NAME     PC1900 1
 '@S9S_MB_2U_LIB.S9S_MB_2U(SCH_1):PAGE262_I34@PURE_QUANTA.Q_CAPP(CHIPS)':
 'A': CDS_PINID='A';
NODE_NAME     PR4229 1
 '@S9S_MB_2U_LIB.S9S_MB_2U(SCH_1):PAGE262_I36@PURE_QUANTA.Q_RES(CHIPS)':
 'A': CDS_PINID='A';
NET_NAME
'PVCCFA_EHV_CPU0_BCSP1'
 '@S9S_MB_2U_LIB.S9S_MB_2U(SCH_1):PVCCFA_EHV_CPU0_BCSP1':
 C_SIGNAL='@s9s_mb_2u_lib.s9s_mb_2u(sch_1):pvccfa_ehv_cpu0_bcsp1';
NODE_NAME     PU5 30
 '@S9S_MB_2U_LIB.S9S_MB_2U(SCH_1):PAGE260_I65@PURE_QUANTA.ISL69260IRAZT(CHIPS)':
 'CS0': CDS_PINID='CS0';
NODE_NAME     PU42 25
 '@S9S_MB_2U_LIB.S9S_MB_2U(SCH_1):PAGE262_I14@PURE_QUANTA.RAA2213404GNPHB0(CHIPS)':
 'IMON': CDS_PINID='IMON';
NET_NAME
'PVCCFA_EHV_CPU0_BPWM1'
 '@S9S_MB_2U_LIB.S9S_MB_2U(SCH_1):PVCCFA_EHV_CPU0_BPWM1':
 C_SIGNAL='@s9s_mb_2u_lib.s9s_mb_2u(sch_1):pvccfa_ehv_cpu0_bpwm1';
NODE_NAME     PU5 1
 '@S9S_MB_2U_LIB.S9S_MB_2U(SCH_1):PAGE260_I65@PURE_QUANTA.ISL69260IRAZT(CHIPS)':
 'PWM0': CDS_PINID='PWM0';
NODE_NAME     PU42 21
 '@S9S_MB_2U_LIB.S9S_MB_2U(SCH_1):PAGE262_I14@PURE_QUANTA.RAA2213404GNPHB0(CHIPS)':
 'PWM': CDS_PINID='PWM';
NET_NAME
'PVCCFA_EHV_CPU0_BTSEN'
 '@S9S_MB_2U_LIB.S9S_MB_2U(SCH_1):PVCCFA_EHV_CPU0_BTSEN':
 C_SIGNAL='@s9s_mb_2u_lib.s9s_mb_2u(sch_1):pvccfa_ehv_cpu0_btsen';
NODE_NAME     PU5 36
 '@S9S_MB_2U_LIB.S9S_MB_2U(SCH_1):PAGE260_I65@PURE_QUANTA.ISL69260IRAZT(CHIPS)':
 'TEMP1||ISYS': CDS_PINID='\temp1||isys\';
NODE_NAME     PU42 1
 '@S9S_MB_2U_LIB.S9S_MB_2U(SCH_1):PAGE262_I14@PURE_QUANTA.RAA2213404GNPHB0(CHIPS)':
 'TMON': CDS_PINID='TMON';
NODE_NAME     PC1271 1
 '@S9S_MB_2U_LIB.S9S_MB_2U(SCH_1):PAGE260_I73@PURE_QUANTA.Q_CAP(CHIPS)':
 'A': CDS_PINID='A';
NODE_NAME     PR436 1
 '@S9S_MB_2U_LIB.S9S_MB_2U(SCH_1):PAGE260_I106@PURE_QUANTA.Q_RES(CHIPS)':
 'A': CDS_PINID='A';
NET_NAME
'PVCCFA_EHV_CPU0_EN_R'
 '@S9S_MB_2U_LIB.S9S_MB_2U(SCH_1):PVCCFA_EHV_CPU0_EN_R':
 C_SIGNAL='@s9s_mb_2u_lib.s9s_mb_2u(sch_1):pvccfa_ehv_cpu0_en_r';
NODE_NAME     PU5 20
 '@S9S_MB_2U_LIB.S9S_MB_2U(SCH_1):PAGE260_I65@PURE_QUANTA.ISL69260IRAZT(CHIPS)':
 'EN1': CDS_PINID='EN1';
NODE_NAME     R2394 2
 '@S9S_MB_2U_LIB.S9S_MB_2U(SCH_1):PAGE260_I14@PURE_QUANTA.Q_RES(CHIPS)':
 'B': CDS_PINID='B';
NODE_NAME     C3275 1
 '@S9S_MB_2U_LIB.S9S_MB_2U(SCH_1):PAGE260_I23@PURE_QUANTA.Q_CAP(CHIPS)':
 'A': CDS_PINID='A';
NET_NAME
'PVCCFA_EHV_CPU0_FAULT'
 '@S9S_MB_2U_LIB.S9S_MB_2U(SCH_1):PVCCFA_EHV_CPU0_FAULT':
 C_SIGNAL='@s9s_mb_2u_lib.s9s_mb_2u(sch_1):pvccfa_ehv_cpu0_fault';
NODE_NAME     PR4228 1
 '@S9S_MB_2U_LIB.S9S_MB_2U(SCH_1):PAGE262_I15@PURE_QUANTA.Q_RES(CHIPS)':
 'A': CDS_PINID='A';
NODE_NAME     PU42 2
 '@S9S_MB_2U_LIB.S9S_MB_2U(SCH_1):PAGE262_I14@PURE_QUANTA.RAA2213404GNPHB0(CHIPS)':
 'FAULT#': CDS_PINID='\fault#\';
NET_NAME
'PVCCFA_EHV_CPU0_LSET1'
 '@S9S_MB_2U_LIB.S9S_MB_2U(SCH_1):PVCCFA_EHV_CPU0_LSET1':
 C_SIGNAL='@s9s_mb_2u_lib.s9s_mb_2u(sch_1):pvccfa_ehv_cpu0_lset1';
NODE_NAME     PR1709 1
 '@S9S_MB_2U_LIB.S9S_MB_2U(SCH_1):PAGE262_I2@PURE_QUANTA.Q_RES(CHIPS)':
 'A': CDS_PINID='A';
NODE_NAME     PU42 5
 '@S9S_MB_2U_LIB.S9S_MB_2U(SCH_1):PAGE262_I14@PURE_QUANTA.RAA2213404GNPHB0(CHIPS)':
 'GL1': CDS_PINID='GL1';
NET_NAME
'PVCCFA_EHV_CPU0_NC1'
 '@S9S_MB_2U_LIB.S9S_MB_2U(SCH_1):PVCCFA_EHV_CPU0_NC1':
 C_SIGNAL='@s9s_mb_2u_lib.s9s_mb_2u(sch_1):pvccfa_ehv_cpu0_nc1';
NODE_NAME     PU42 3
 '@S9S_MB_2U_LIB.S9S_MB_2U(SCH_1):PAGE262_I14@PURE_QUANTA.RAA2213404GNPHB0(CHIPS)':
 'LGCTRL': CDS_PINID='LGCTRL';
NODE_NAME     PR1779 1
 '@S9S_MB_2U_LIB.S9S_MB_2U(SCH_1):PAGE262_I16@PURE_QUANTA.Q_RES(CHIPS)':
 'A': CDS_PINID='A';
NET_NAME
'PVCCFA_EHV_CPU0_NC2'
 '@S9S_MB_2U_LIB.S9S_MB_2U(SCH_1):PVCCFA_EHV_CPU0_NC2':
 C_SIGNAL='@s9s_mb_2u_lib.s9s_mb_2u(sch_1):pvccfa_ehv_cpu0_nc2';
NODE_NAME     PR4227 2
 '@S9S_MB_2U_LIB.S9S_MB_2U(SCH_1):PAGE262_I13@PURE_QUANTA.Q_RES(CHIPS)':
 'B': CDS_PINID='B';
NODE_NAME     PU42 22
 '@S9S_MB_2U_LIB.S9S_MB_2U(SCH_1):PAGE262_I14@PURE_QUANTA.RAA2213404GNPHB0(CHIPS)':
 'NC1': CDS_PINID='NC1';
NET_NAME
'PVCCFA_EHV_CPU0_PVCC'
 '@S9S_MB_2U_LIB.S9S_MB_2U(SCH_1):PVCCFA_EHV_CPU0_PVCC':
 C_SIGNAL='@s9s_mb_2u_lib.s9s_mb_2u(sch_1):pvccfa_ehv_cpu0_pvcc',
 CDS_GLOBAL_NET='TRUE';
NODE_NAME     PR97 1
 '@S9S_MB_2U_LIB.S9S_MB_2U(SCH_1):PAGE262_I21@PURE_QUANTA.Q_RES(CHIPS)':
 'A': CDS_PINID='A';
NODE_NAME     PU44_P0_2 4
 '@S9S_MB_2U_LIB.S9S_MB_2U(SCH_1):PAGE261_I12@PURE_QUANTA.ISL99390FRZTR5935(CHIPS)':
 'PVCC': CDS_PINID='PVCC';
NODE_NAME     PR101 1
 '@S9S_MB_2U_LIB.S9S_MB_2U(SCH_1):PAGE261_I26@PURE_QUANTA.Q_RES(CHIPS)':
 'A': CDS_PINID='A';
NODE_NAME     PU36 4
 '@S9S_MB_2U_LIB.S9S_MB_2U(SCH_1):PAGE265_I8@PURE_QUANTA.ISL99390FRZTR5935(CHIPS)':
 'PVCC': CDS_PINID='PVCC';
NODE_NAME     PR102 1
 '@S9S_MB_2U_LIB.S9S_MB_2U(SCH_1):PAGE261_I14@PURE_QUANTA.Q_RES(CHIPS)':
 'A': CDS_PINID='A';
NODE_NAME     PC2947 1
 '@S9S_MB_2U_LIB.S9S_MB_2U(SCH_1):PAGE261_I29@PURE_QUANTA.Q_CAP(CHIPS)':
 'A': CDS_PINID='A';
NODE_NAME     PU43_P0_1 4
 '@S9S_MB_2U_LIB.S9S_MB_2U(SCH_1):PAGE261_I79@PURE_QUANTA.ISL99390FRZTR5935(CHIPS)':
 'PVCC': CDS_PINID='PVCC';
NODE_NAME     PR442 2
 '@S9S_MB_2U_LIB.S9S_MB_2U(SCH_1):PAGE262_I8@PURE_QUANTA.Q_RES(CHIPS)':
 'B': CDS_PINID='B';
NODE_NAME     PR380 1
 '@S9S_MB_2U_LIB.S9S_MB_2U(SCH_1):PAGE265_I12@PURE_QUANTA.Q_RES(CHIPS)':
 'A': CDS_PINID='A';
NODE_NAME     PC2948 1
 '@S9S_MB_2U_LIB.S9S_MB_2U(SCH_1):PAGE265_I14@PURE_QUANTA.Q_CAP(CHIPS)':
 'A': CDS_PINID='A';
NODE_NAME     PR443 2
 '@S9S_MB_2U_LIB.S9S_MB_2U(SCH_1):PAGE262_I22@PURE_QUANTA.Q_RES(CHIPS)':
 'B': CDS_PINID='B';
NODE_NAME     PC2946 1
 '@S9S_MB_2U_LIB.S9S_MB_2U(SCH_1):PAGE261_I16@PURE_QUANTA.Q_CAP(CHIPS)':
 'A': CDS_PINID='A';
NET_NAME
'PVCCFA_EHV_CPU0_VDD1'
 '@S9S_MB_2U_LIB.S9S_MB_2U(SCH_1):PVCCFA_EHV_CPU0_VDD1':
 C_SIGNAL='@s9s_mb_2u_lib.s9s_mb_2u(sch_1):pvccfa_ehv_cpu0_vdd1',
 CDS_GLOBAL_NET='TRUE';
NODE_NAME     PR97 2
 '@S9S_MB_2U_LIB.S9S_MB_2U(SCH_1):PAGE262_I21@PURE_QUANTA.Q_RES(CHIPS)':
 'B': CDS_PINID='B';
NODE_NAME     PC175 1
 '@S9S_MB_2U_LIB.S9S_MB_2U(SCH_1):PAGE262_I12@PURE_QUANTA.Q_CAP(CHIPS)':
 'A': CDS_PINID='A';
NODE_NAME     PR4227 1
 '@S9S_MB_2U_LIB.S9S_MB_2U(SCH_1):PAGE262_I13@PURE_QUANTA.Q_RES(CHIPS)':
 'A': CDS_PINID='A';
NODE_NAME     PU42 4
 '@S9S_MB_2U_LIB.S9S_MB_2U(SCH_1):PAGE262_I14@PURE_QUANTA.RAA2213404GNPHB0(CHIPS)':
 'VCC': CDS_PINID='VCC';
NODE_NAME     PR1779 2
 '@S9S_MB_2U_LIB.S9S_MB_2U(SCH_1):PAGE262_I16@PURE_QUANTA.Q_RES(CHIPS)':
 'B': CDS_PINID='B';
NET_NAME
'PVCCFA_EHV_CPU1'
 '@S9S_MB_2U_LIB.S9S_MB_2U(SCH_1):PVCCFA_EHV_CPU1':
 C_SIGNAL='@s9s_mb_2u_lib.s9s_mb_2u(sch_1):pvccfa_ehv_cpu1',
 CDS_GLOBAL_NET='TRUE';
NODE_NAME     U1 AA3
 '@S9S_MB_2U_LIB.S9S_MB_2U(SCH_1):PAGE68_I8@PURE_QUANTA.SOCKET4677_AZIF0045P001C01CS(CHIPS)':
 'VCCFA_EHV0': CDS_PINID='VCCFA_EHV0';
NODE_NAME     U1 AE3
 '@S9S_MB_2U_LIB.S9S_MB_2U(SCH_1):PAGE68_I8@PURE_QUANTA.SOCKET4677_AZIF0045P001C01CS(CHIPS)':
 'VCCFA_EHV1': CDS_PINID='VCCFA_EHV1';
NODE_NAME     U1 AJ3
 '@S9S_MB_2U_LIB.S9S_MB_2U(SCH_1):PAGE68_I8@PURE_QUANTA.SOCKET4677_AZIF0045P001C01CS(CHIPS)':
 'VCCFA_EHV2': CDS_PINID='VCCFA_EHV2';
NODE_NAME     U1 AN3
 '@S9S_MB_2U_LIB.S9S_MB_2U(SCH_1):PAGE68_I8@PURE_QUANTA.SOCKET4677_AZIF0045P001C01CS(CHIPS)':
 'VCCFA_EHV3': CDS_PINID='VCCFA_EHV3';
NODE_NAME     U1 AT61
 '@S9S_MB_2U_LIB.S9S_MB_2U(SCH_1):PAGE68_I8@PURE_QUANTA.SOCKET4677_AZIF0045P001C01CS(CHIPS)':
 'VCCFA_EHV4': CDS_PINID='VCCFA_EHV4';
NODE_NAME     U1 AU60
 '@S9S_MB_2U_LIB.S9S_MB_2U(SCH_1):PAGE68_I8@PURE_QUANTA.SOCKET4677_AZIF0045P001C01CS(CHIPS)':
 'VCCFA_EHV5': CDS_PINID='VCCFA_EHV5';
NODE_NAME     U1 AV61
 '@S9S_MB_2U_LIB.S9S_MB_2U(SCH_1):PAGE68_I8@PURE_QUANTA.SOCKET4677_AZIF0045P001C01CS(CHIPS)':
 'VCCFA_EHV6': CDS_PINID='VCCFA_EHV6';
NODE_NAME     U1 AW60
 '@S9S_MB_2U_LIB.S9S_MB_2U(SCH_1):PAGE68_I8@PURE_QUANTA.SOCKET4677_AZIF0045P001C01CS(CHIPS)':
 'VCCFA_EHV7': CDS_PINID='VCCFA_EHV7';
NODE_NAME     U1 N3
 '@S9S_MB_2U_LIB.S9S_MB_2U(SCH_1):PAGE68_I8@PURE_QUANTA.SOCKET4677_AZIF0045P001C01CS(CHIPS)':
 'VCCFA_EHV8': CDS_PINID='VCCFA_EHV8';
NODE_NAME     U1 U3
 '@S9S_MB_2U_LIB.S9S_MB_2U(SCH_1):PAGE68_I8@PURE_QUANTA.SOCKET4677_AZIF0045P001C01CS(CHIPS)':
 'VCCFA_EHV9': CDS_PINID='VCCFA_EHV9';
NODE_NAME     C444 1
 '@S9S_MB_2U_LIB.S9S_MB_2U(SCH_1):PAGE77_I109@PURE_QUANTA.Q_CAP(CHIPS)':
 'A': CDS_PINID='A';
NODE_NAME     C445 1
 '@S9S_MB_2U_LIB.S9S_MB_2U(SCH_1):PAGE77_I110@PURE_QUANTA.Q_CAP(CHIPS)':
 'A': CDS_PINID='A';
NODE_NAME     C446 1
 '@S9S_MB_2U_LIB.S9S_MB_2U(SCH_1):PAGE77_I113@PURE_QUANTA.Q_CAP(CHIPS)':
 'A': CDS_PINID='A';
NODE_NAME     PL20 2
 '@S9S_MB_2U_LIB.S9S_MB_2U(SCH_1):PAGE280_I23@PURE_QUANTA.Q_INDUCTOR(CHIPS)':
 '2': CDS_PINID='\2\';
NODE_NAME     PC435 1
 '@S9S_MB_2U_LIB.S9S_MB_2U(SCH_1):PAGE280_I30@PURE_QUANTA.Q_CAP(CHIPS)':
 'A': CDS_PINID='A';
NODE_NAME     PC437 1
 '@S9S_MB_2U_LIB.S9S_MB_2U(SCH_1):PAGE280_I31@PURE_QUANTA.Q_CAP(CHIPS)':
 'A': CDS_PINID='A';
NODE_NAME     C443 1
 '@S9S_MB_2U_LIB.S9S_MB_2U(SCH_1):PAGE77_I67@PURE_QUANTA.Q_CAP(CHIPS)':
 'A': CDS_PINID='A';
NODE_NAME     C448 1
 '@S9S_MB_2U_LIB.S9S_MB_2U(SCH_1):PAGE78_I10@PURE_QUANTA.Q_CAP(CHIPS)':
 'A': CDS_PINID='A';
NODE_NAME     C452 1
 '@S9S_MB_2U_LIB.S9S_MB_2U(SCH_1):PAGE78_I21@PURE_QUANTA.Q_CAP(CHIPS)':
 'A': CDS_PINID='A';
NODE_NAME     C456 1
 '@S9S_MB_2U_LIB.S9S_MB_2U(SCH_1):PAGE79_I15@PURE_QUANTA.Q_CAP(CHIPS)':
 'A': CDS_PINID='A';
NODE_NAME     C460 1
 '@S9S_MB_2U_LIB.S9S_MB_2U(SCH_1):PAGE79_I16@PURE_QUANTA.Q_CAP(CHIPS)':
 'A': CDS_PINID='A';
NODE_NAME     C464 1
 '@S9S_MB_2U_LIB.S9S_MB_2U(SCH_1):PAGE79_I17@PURE_QUANTA.Q_CAP(CHIPS)':
 'A': CDS_PINID='A';
NODE_NAME     C468 1
 '@S9S_MB_2U_LIB.S9S_MB_2U(SCH_1):PAGE79_I26@PURE_QUANTA.Q_CAP(CHIPS)':
 'A': CDS_PINID='A';
NODE_NAME     C472 1
 '@S9S_MB_2U_LIB.S9S_MB_2U(SCH_1):PAGE79_I27@PURE_QUANTA.Q_CAP(CHIPS)':
 'A': CDS_PINID='A';
NODE_NAME     C475 1
 '@S9S_MB_2U_LIB.S9S_MB_2U(SCH_1):PAGE79_I29@PURE_QUANTA.Q_CAP(CHIPS)':
 'A': CDS_PINID='A';
NODE_NAME     PC434 1
 '@S9S_MB_2U_LIB.S9S_MB_2U(SCH_1):PAGE280_I29@PURE_QUANTA.Q_CAP(CHIPS)':
 'A': CDS_PINID='A';
NODE_NAME     PC2199 1
 '@S9S_MB_2U_LIB.S9S_MB_2U(SCH_1):PAGE280_I32@PURE_QUANTA.Q_CAPP(CHIPS)':
 'A': CDS_PINID='A';
NODE_NAME     PR569 2
 '@S9S_MB_2U_LIB.S9S_MB_2U(SCH_1):PAGE278_I45@PURE_QUANTA.Q_RES(CHIPS)':
 'B': CDS_PINID='B';
NODE_NAME     PC1930 1
 '@S9S_MB_2U_LIB.S9S_MB_2U(SCH_1):PAGE280_I33@PURE_QUANTA.Q_CAPP(CHIPS)':
 'A': CDS_PINID='A';
NODE_NAME     PR4250 1
 '@S9S_MB_2U_LIB.S9S_MB_2U(SCH_1):PAGE280_I37@PURE_QUANTA.Q_RES(CHIPS)':
 'A': CDS_PINID='A';
NET_NAME
'PVCCFA_EHV_CPU1_BCSP1'
 '@S9S_MB_2U_LIB.S9S_MB_2U(SCH_1):PVCCFA_EHV_CPU1_BCSP1':
 C_SIGNAL='@s9s_mb_2u_lib.s9s_mb_2u(sch_1):pvccfa_ehv_cpu1_bcsp1';
NODE_NAME     PU49 25
 '@S9S_MB_2U_LIB.S9S_MB_2U(SCH_1):PAGE280_I14@PURE_QUANTA.RAA2213404GNPHB0(CHIPS)':
 'IMON': CDS_PINID='IMON';
NODE_NAME     PU22 30
 '@S9S_MB_2U_LIB.S9S_MB_2U(SCH_1):PAGE278_I38@PURE_QUANTA.ISL69260IRAZT(CHIPS)':
 'CS0': CDS_PINID='CS0';
NET_NAME
'PVCCFA_EHV_CPU1_BPWM1'
 '@S9S_MB_2U_LIB.S9S_MB_2U(SCH_1):PVCCFA_EHV_CPU1_BPWM1':
 C_SIGNAL='@s9s_mb_2u_lib.s9s_mb_2u(sch_1):pvccfa_ehv_cpu1_bpwm1';
NODE_NAME     PU49 21
 '@S9S_MB_2U_LIB.S9S_MB_2U(SCH_1):PAGE280_I14@PURE_QUANTA.RAA2213404GNPHB0(CHIPS)':
 'PWM': CDS_PINID='PWM';
NODE_NAME     PU22 1
 '@S9S_MB_2U_LIB.S9S_MB_2U(SCH_1):PAGE278_I38@PURE_QUANTA.ISL69260IRAZT(CHIPS)':
 'PWM0': CDS_PINID='PWM0';
NET_NAME
'PVCCFA_EHV_CPU1_BTSEN'
 '@S9S_MB_2U_LIB.S9S_MB_2U(SCH_1):PVCCFA_EHV_CPU1_BTSEN':
 C_SIGNAL='@s9s_mb_2u_lib.s9s_mb_2u(sch_1):pvccfa_ehv_cpu1_btsen';
NODE_NAME     PU49 1
 '@S9S_MB_2U_LIB.S9S_MB_2U(SCH_1):PAGE280_I14@PURE_QUANTA.RAA2213404GNPHB0(CHIPS)':
 'TMON': CDS_PINID='TMON';
NODE_NAME     PC1292 1
 '@S9S_MB_2U_LIB.S9S_MB_2U(SCH_1):PAGE278_I69@PURE_QUANTA.Q_CAP(CHIPS)':
 'A': CDS_PINID='A';
NODE_NAME     PU22 36
 '@S9S_MB_2U_LIB.S9S_MB_2U(SCH_1):PAGE278_I38@PURE_QUANTA.ISL69260IRAZT(CHIPS)':
 'TEMP1||ISYS': CDS_PINID='\temp1||isys\';
NODE_NAME     PR667 1
 '@S9S_MB_2U_LIB.S9S_MB_2U(SCH_1):PAGE278_I75@PURE_QUANTA.Q_RES(CHIPS)':
 'A': CDS_PINID='A';
NET_NAME
'PVCCFA_EHV_CPU1_EN_R'
 '@S9S_MB_2U_LIB.S9S_MB_2U(SCH_1):PVCCFA_EHV_CPU1_EN_R':
 C_SIGNAL='@s9s_mb_2u_lib.s9s_mb_2u(sch_1):pvccfa_ehv_cpu1_en_r';
NODE_NAME     R2570 2
 '@S9S_MB_2U_LIB.S9S_MB_2U(SCH_1):PAGE278_I31@PURE_QUANTA.Q_RES(CHIPS)':
 'B': CDS_PINID='B';
NODE_NAME     C2452 1
 '@S9S_MB_2U_LIB.S9S_MB_2U(SCH_1):PAGE278_I33@PURE_QUANTA.Q_CAP(CHIPS)':
 'A': CDS_PINID='A';
NODE_NAME     PU22 20
 '@S9S_MB_2U_LIB.S9S_MB_2U(SCH_1):PAGE278_I38@PURE_QUANTA.ISL69260IRAZT(CHIPS)':
 'EN1': CDS_PINID='EN1';
NET_NAME
'PVCCFA_EHV_CPU1_FAULT'
 '@S9S_MB_2U_LIB.S9S_MB_2U(SCH_1):PVCCFA_EHV_CPU1_FAULT':
 C_SIGNAL='@s9s_mb_2u_lib.s9s_mb_2u(sch_1):pvccfa_ehv_cpu1_fault';
NODE_NAME     PU49 2
 '@S9S_MB_2U_LIB.S9S_MB_2U(SCH_1):PAGE280_I14@PURE_QUANTA.RAA2213404GNPHB0(CHIPS)':
 'FAULT#': CDS_PINID='\fault#\';
NODE_NAME     PR4249 1
 '@S9S_MB_2U_LIB.S9S_MB_2U(SCH_1):PAGE280_I18@PURE_QUANTA.Q_RES(CHIPS)':
 'A': CDS_PINID='A';
NET_NAME
'PVCCFA_EHV_CPU1_LSET1'
 '@S9S_MB_2U_LIB.S9S_MB_2U(SCH_1):PVCCFA_EHV_CPU1_LSET1':
 C_SIGNAL='@s9s_mb_2u_lib.s9s_mb_2u(sch_1):pvccfa_ehv_cpu1_lset1';
NODE_NAME     PU49 5
 '@S9S_MB_2U_LIB.S9S_MB_2U(SCH_1):PAGE280_I14@PURE_QUANTA.RAA2213404GNPHB0(CHIPS)':
 'GL1': CDS_PINID='GL1';
NODE_NAME     PR1728 1
 '@S9S_MB_2U_LIB.S9S_MB_2U(SCH_1):PAGE280_I1@PURE_QUANTA.Q_RES(CHIPS)':
 'A': CDS_PINID='A';
NET_NAME
'PVCCFA_EHV_CPU1_NC1'
 '@S9S_MB_2U_LIB.S9S_MB_2U(SCH_1):PVCCFA_EHV_CPU1_NC1':
 C_SIGNAL='@s9s_mb_2u_lib.s9s_mb_2u(sch_1):pvccfa_ehv_cpu1_nc1';
NODE_NAME     PU49 3
 '@S9S_MB_2U_LIB.S9S_MB_2U(SCH_1):PAGE280_I14@PURE_QUANTA.RAA2213404GNPHB0(CHIPS)':
 'LGCTRL': CDS_PINID='LGCTRL';
NODE_NAME     PR1799 1
 '@S9S_MB_2U_LIB.S9S_MB_2U(SCH_1):PAGE280_I20@PURE_QUANTA.Q_RES(CHIPS)':
 'A': CDS_PINID='A';
NET_NAME
'PVCCFA_EHV_CPU1_NC2'
 '@S9S_MB_2U_LIB.S9S_MB_2U(SCH_1):PVCCFA_EHV_CPU1_NC2':
 C_SIGNAL='@s9s_mb_2u_lib.s9s_mb_2u(sch_1):pvccfa_ehv_cpu1_nc2';
NODE_NAME     PU49 22
 '@S9S_MB_2U_LIB.S9S_MB_2U(SCH_1):PAGE280_I14@PURE_QUANTA.RAA2213404GNPHB0(CHIPS)':
 'NC1': CDS_PINID='NC1';
NODE_NAME     PR4248 1
 '@S9S_MB_2U_LIB.S9S_MB_2U(SCH_1):PAGE280_I13@PURE_QUANTA.Q_RES(CHIPS)':
 'A': CDS_PINID='A';
NET_NAME
'PVCCFA_EHV_CPU1_PVCC'
 '@S9S_MB_2U_LIB.S9S_MB_2U(SCH_1):PVCCFA_EHV_CPU1_PVCC':
 C_SIGNAL='@s9s_mb_2u_lib.s9s_mb_2u(sch_1):pvccfa_ehv_cpu1_pvcc',
 CDS_GLOBAL_NET='TRUE';
NODE_NAME     PR255 1
 '@S9S_MB_2U_LIB.S9S_MB_2U(SCH_1):PAGE279_I11@PURE_QUANTA.Q_RES(CHIPS)':
 'A': CDS_PINID='A';
NODE_NAME     PU50_P1_1 4
 '@S9S_MB_2U_LIB.S9S_MB_2U(SCH_1):PAGE279_I38@PURE_QUANTA.ISL99390FRZTR5935(CHIPS)':
 'PVCC': CDS_PINID='PVCC';
NODE_NAME     PC2951 1
 '@S9S_MB_2U_LIB.S9S_MB_2U(SCH_1):PAGE283_I18@PURE_QUANTA.Q_CAP(CHIPS)':
 'A': CDS_PINID='A';
NODE_NAME     PR254 1
 '@S9S_MB_2U_LIB.S9S_MB_2U(SCH_1):PAGE279_I25@PURE_QUANTA.Q_RES(CHIPS)':
 'A': CDS_PINID='A';
NODE_NAME     PU51_P1_2 4
 '@S9S_MB_2U_LIB.S9S_MB_2U(SCH_1):PAGE279_I29@PURE_QUANTA.ISL99390FRZTR5935(CHIPS)':
 'PVCC': CDS_PINID='PVCC';
NODE_NAME     PR678 2
 '@S9S_MB_2U_LIB.S9S_MB_2U(SCH_1):PAGE280_I4@PURE_QUANTA.Q_RES(CHIPS)':
 'B': CDS_PINID='B';
NODE_NAME     PR250 1
 '@S9S_MB_2U_LIB.S9S_MB_2U(SCH_1):PAGE280_I15@PURE_QUANTA.Q_RES(CHIPS)':
 'A': CDS_PINID='A';
NODE_NAME     PU17 4
 '@S9S_MB_2U_LIB.S9S_MB_2U(SCH_1):PAGE283_I10@PURE_QUANTA.ISL99390FRZTR5935(CHIPS)':
 'PVCC': CDS_PINID='PVCC';
NODE_NAME     PR200 1
 '@S9S_MB_2U_LIB.S9S_MB_2U(SCH_1):PAGE283_I16@PURE_QUANTA.Q_RES(CHIPS)':
 'A': CDS_PINID='A';
NODE_NAME     PC2949 1
 '@S9S_MB_2U_LIB.S9S_MB_2U(SCH_1):PAGE279_I13@PURE_QUANTA.Q_CAP(CHIPS)':
 'A': CDS_PINID='A';
NODE_NAME     PC2950 1
 '@S9S_MB_2U_LIB.S9S_MB_2U(SCH_1):PAGE279_I26@PURE_QUANTA.Q_CAP(CHIPS)':
 'A': CDS_PINID='A';
NODE_NAME     PR699 2
 '@S9S_MB_2U_LIB.S9S_MB_2U(SCH_1):PAGE280_I16@PURE_QUANTA.Q_RES(CHIPS)':
 'B': CDS_PINID='B';
NET_NAME
'PVCCFA_EHV_CPU1_VDD1'
 '@S9S_MB_2U_LIB.S9S_MB_2U(SCH_1):PVCCFA_EHV_CPU1_VDD1':
 C_SIGNAL='@s9s_mb_2u_lib.s9s_mb_2u(sch_1):pvccfa_ehv_cpu1_vdd1',
 CDS_GLOBAL_NET='TRUE';
NODE_NAME     PU49 4
 '@S9S_MB_2U_LIB.S9S_MB_2U(SCH_1):PAGE280_I14@PURE_QUANTA.RAA2213404GNPHB0(CHIPS)':
 'VCC': CDS_PINID='VCC';
NODE_NAME     PR250 2
 '@S9S_MB_2U_LIB.S9S_MB_2U(SCH_1):PAGE280_I15@PURE_QUANTA.Q_RES(CHIPS)':
 'B': CDS_PINID='B';
NODE_NAME     PC428 1
 '@S9S_MB_2U_LIB.S9S_MB_2U(SCH_1):PAGE280_I11@PURE_QUANTA.Q_CAP(CHIPS)':
 'A': CDS_PINID='A';
NODE_NAME     PR4248 2
 '@S9S_MB_2U_LIB.S9S_MB_2U(SCH_1):PAGE280_I13@PURE_QUANTA.Q_RES(CHIPS)':
 'B': CDS_PINID='B';
NODE_NAME     PR1799 2
 '@S9S_MB_2U_LIB.S9S_MB_2U(SCH_1):PAGE280_I20@PURE_QUANTA.Q_RES(CHIPS)':
 'B': CDS_PINID='B';
NET_NAME
'PVCCFA_EHV_FIVRA_CPU0'
 '@S9S_MB_2U_LIB.S9S_MB_2U(SCH_1):PVCCFA_EHV_FIVRA_CPU0':
 C_SIGNAL='@s9s_mb_2u_lib.s9s_mb_2u(sch_1):pvccfa_ehv_fivra_cpu0',
 CDS_GLOBAL_NET='TRUE';
NODE_NAME     U2 AA11
 '@S9S_MB_2U_LIB.S9S_MB_2U(SCH_1):PAGE38_I4@PURE_QUANTA.SOCKET4677_AZIF0045P001C01CS(CHIPS)':
 'VCCFA_EHV_FIVRA0': CDS_PINID='VCCFA_EHV_FIVRA0';
NODE_NAME     U2 AA15
 '@S9S_MB_2U_LIB.S9S_MB_2U(SCH_1):PAGE38_I4@PURE_QUANTA.SOCKET4677_AZIF0045P001C01CS(CHIPS)':
 'VCCFA_EHV_FIVRA1': CDS_PINID='VCCFA_EHV_FIVRA1';
NODE_NAME     U2 AA7
 '@S9S_MB_2U_LIB.S9S_MB_2U(SCH_1):PAGE38_I4@PURE_QUANTA.SOCKET4677_AZIF0045P001C01CS(CHIPS)':
 'VCCFA_EHV_FIVRA2': CDS_PINID='VCCFA_EHV_FIVRA2';
NODE_NAME     U2 AD85
 '@S9S_MB_2U_LIB.S9S_MB_2U(SCH_1):PAGE38_I4@PURE_QUANTA.SOCKET4677_AZIF0045P001C01CS(CHIPS)':
 'VCCFA_EHV_FIVRA3': CDS_PINID='VCCFA_EHV_FIVRA3';
NODE_NAME     U2 AD89
 '@S9S_MB_2U_LIB.S9S_MB_2U(SCH_1):PAGE38_I4@PURE_QUANTA.SOCKET4677_AZIF0045P001C01CS(CHIPS)':
 'VCCFA_EHV_FIVRA4': CDS_PINID='VCCFA_EHV_FIVRA4';
NODE_NAME     U2 AE11
 '@S9S_MB_2U_LIB.S9S_MB_2U(SCH_1):PAGE38_I4@PURE_QUANTA.SOCKET4677_AZIF0045P001C01CS(CHIPS)':
 'VCCFA_EHV_FIVRA5': CDS_PINID='VCCFA_EHV_FIVRA5';
NODE_NAME     U2 AE15
 '@S9S_MB_2U_LIB.S9S_MB_2U(SCH_1):PAGE38_I4@PURE_QUANTA.SOCKET4677_AZIF0045P001C01CS(CHIPS)':
 'VCCFA_EHV_FIVRA6': CDS_PINID='VCCFA_EHV_FIVRA6';
NODE_NAME     U2 AE7
 '@S9S_MB_2U_LIB.S9S_MB_2U(SCH_1):PAGE38_I4@PURE_QUANTA.SOCKET4677_AZIF0045P001C01CS(CHIPS)':
 'VCCFA_EHV_FIVRA7': CDS_PINID='VCCFA_EHV_FIVRA7';
NODE_NAME     U2 AF77
 '@S9S_MB_2U_LIB.S9S_MB_2U(SCH_1):PAGE38_I4@PURE_QUANTA.SOCKET4677_AZIF0045P001C01CS(CHIPS)':
 'VCCFA_EHV_FIVRA8': CDS_PINID='VCCFA_EHV_FIVRA8';
NODE_NAME     U2 AG78
 '@S9S_MB_2U_LIB.S9S_MB_2U(SCH_1):PAGE38_I4@PURE_QUANTA.SOCKET4677_AZIF0045P001C01CS(CHIPS)':
 'VCCFA_EHV_FIVRA9': CDS_PINID='VCCFA_EHV_FIVRA9';
NODE_NAME     U2 AH85
 '@S9S_MB_2U_LIB.S9S_MB_2U(SCH_1):PAGE38_I4@PURE_QUANTA.SOCKET4677_AZIF0045P001C01CS(CHIPS)':
 'VCCFA_EHV_FIVRA10': CDS_PINID='VCCFA_EHV_FIVRA10';
NODE_NAME     U2 AH89
 '@S9S_MB_2U_LIB.S9S_MB_2U(SCH_1):PAGE38_I4@PURE_QUANTA.SOCKET4677_AZIF0045P001C01CS(CHIPS)':
 'VCCFA_EHV_FIVRA11': CDS_PINID='VCCFA_EHV_FIVRA11';
NODE_NAME     U2 AJ11
 '@S9S_MB_2U_LIB.S9S_MB_2U(SCH_1):PAGE38_I4@PURE_QUANTA.SOCKET4677_AZIF0045P001C01CS(CHIPS)':
 'VCCFA_EHV_FIVRA12': CDS_PINID='VCCFA_EHV_FIVRA12';
NODE_NAME     U2 AJ15
 '@S9S_MB_2U_LIB.S9S_MB_2U(SCH_1):PAGE38_I4@PURE_QUANTA.SOCKET4677_AZIF0045P001C01CS(CHIPS)':
 'VCCFA_EHV_FIVRA13': CDS_PINID='VCCFA_EHV_FIVRA13';
NODE_NAME     U2 AJ7
 '@S9S_MB_2U_LIB.S9S_MB_2U(SCH_1):PAGE38_I4@PURE_QUANTA.SOCKET4677_AZIF0045P001C01CS(CHIPS)':
 'VCCFA_EHV_FIVRA14': CDS_PINID='VCCFA_EHV_FIVRA14';
NODE_NAME     U2 AM79
 '@S9S_MB_2U_LIB.S9S_MB_2U(SCH_1):PAGE38_I4@PURE_QUANTA.SOCKET4677_AZIF0045P001C01CS(CHIPS)':
 'VCCFA_EHV_FIVRA15': CDS_PINID='VCCFA_EHV_FIVRA15';
NODE_NAME     U2 AM85
 '@S9S_MB_2U_LIB.S9S_MB_2U(SCH_1):PAGE38_I4@PURE_QUANTA.SOCKET4677_AZIF0045P001C01CS(CHIPS)':
 'VCCFA_EHV_FIVRA16': CDS_PINID='VCCFA_EHV_FIVRA16';
NODE_NAME     U2 AM89
 '@S9S_MB_2U_LIB.S9S_MB_2U(SCH_1):PAGE38_I4@PURE_QUANTA.SOCKET4677_AZIF0045P001C01CS(CHIPS)':
 'VCCFA_EHV_FIVRA17': CDS_PINID='VCCFA_EHV_FIVRA17';
NODE_NAME     U2 AN11
 '@S9S_MB_2U_LIB.S9S_MB_2U(SCH_1):PAGE38_I4@PURE_QUANTA.SOCKET4677_AZIF0045P001C01CS(CHIPS)':
 'VCCFA_EHV_FIVRA18': CDS_PINID='VCCFA_EHV_FIVRA18';
NODE_NAME     U2 AN15
 '@S9S_MB_2U_LIB.S9S_MB_2U(SCH_1):PAGE38_I4@PURE_QUANTA.SOCKET4677_AZIF0045P001C01CS(CHIPS)':
 'VCCFA_EHV_FIVRA19': CDS_PINID='VCCFA_EHV_FIVRA19';
NODE_NAME     U2 AN7
 '@S9S_MB_2U_LIB.S9S_MB_2U(SCH_1):PAGE38_I4@PURE_QUANTA.SOCKET4677_AZIF0045P001C01CS(CHIPS)':
 'VCCFA_EHV_FIVRA20': CDS_PINID='VCCFA_EHV_FIVRA20';
NODE_NAME     U2 AN80
 '@S9S_MB_2U_LIB.S9S_MB_2U(SCH_1):PAGE38_I4@PURE_QUANTA.SOCKET4677_AZIF0045P001C01CS(CHIPS)':
 'VCCFA_EHV_FIVRA21': CDS_PINID='VCCFA_EHV_FIVRA21';
NODE_NAME     U2 AT73
 '@S9S_MB_2U_LIB.S9S_MB_2U(SCH_1):PAGE38_I4@PURE_QUANTA.SOCKET4677_AZIF0045P001C01CS(CHIPS)':
 'VCCFA_EHV_FIVRA22': CDS_PINID='VCCFA_EHV_FIVRA22';
NODE_NAME     U2 AT89
 '@S9S_MB_2U_LIB.S9S_MB_2U(SCH_1):PAGE38_I4@PURE_QUANTA.SOCKET4677_AZIF0045P001C01CS(CHIPS)':
 'VCCFA_EHV_FIVRA23': CDS_PINID='VCCFA_EHV_FIVRA23';
NODE_NAME     U2 AU15
 '@S9S_MB_2U_LIB.S9S_MB_2U(SCH_1):PAGE38_I4@PURE_QUANTA.SOCKET4677_AZIF0045P001C01CS(CHIPS)':
 'VCCFA_EHV_FIVRA24': CDS_PINID='VCCFA_EHV_FIVRA24';
NODE_NAME     U2 AW76
 '@S9S_MB_2U_LIB.S9S_MB_2U(SCH_1):PAGE38_I4@PURE_QUANTA.SOCKET4677_AZIF0045P001C01CS(CHIPS)':
 'VCCFA_EHV_FIVRA25': CDS_PINID='VCCFA_EHV_FIVRA25';
NODE_NAME     U2 AY89
 '@S9S_MB_2U_LIB.S9S_MB_2U(SCH_1):PAGE38_I4@PURE_QUANTA.SOCKET4677_AZIF0045P001C01CS(CHIPS)':
 'VCCFA_EHV_FIVRA26': CDS_PINID='VCCFA_EHV_FIVRA26';
NODE_NAME     U2 BE72
 '@S9S_MB_2U_LIB.S9S_MB_2U(SCH_1):PAGE38_I4@PURE_QUANTA.SOCKET4677_AZIF0045P001C01CS(CHIPS)':
 'VCCFA_EHV_FIVRA27': CDS_PINID='VCCFA_EHV_FIVRA27';
NODE_NAME     U2 BF77
 '@S9S_MB_2U_LIB.S9S_MB_2U(SCH_1):PAGE38_I4@PURE_QUANTA.SOCKET4677_AZIF0045P001C01CS(CHIPS)':
 'VCCFA_EHV_FIVRA28': CDS_PINID='VCCFA_EHV_FIVRA28';
NODE_NAME     U2 BH79
 '@S9S_MB_2U_LIB.S9S_MB_2U(SCH_1):PAGE38_I4@PURE_QUANTA.SOCKET4677_AZIF0045P001C01CS(CHIPS)':
 'VCCFA_EHV_FIVRA29': CDS_PINID='VCCFA_EHV_FIVRA29';
NODE_NAME     U2 BJ72
 '@S9S_MB_2U_LIB.S9S_MB_2U(SCH_1):PAGE38_I4@PURE_QUANTA.SOCKET4677_AZIF0045P001C01CS(CHIPS)':
 'VCCFA_EHV_FIVRA30': CDS_PINID='VCCFA_EHV_FIVRA30';
NODE_NAME     U2 BJ78
 '@S9S_MB_2U_LIB.S9S_MB_2U(SCH_1):PAGE38_I4@PURE_QUANTA.SOCKET4677_AZIF0045P001C01CS(CHIPS)':
 'VCCFA_EHV_FIVRA31': CDS_PINID='VCCFA_EHV_FIVRA31';
NODE_NAME     U2 C84
 '@S9S_MB_2U_LIB.S9S_MB_2U(SCH_1):PAGE38_I4@PURE_QUANTA.SOCKET4677_AZIF0045P001C01CS(CHIPS)':
 'VCCFA_EHV_FIVRA32': CDS_PINID='VCCFA_EHV_FIVRA32';
NODE_NAME     U2 C88
 '@S9S_MB_2U_LIB.S9S_MB_2U(SCH_1):PAGE38_I4@PURE_QUANTA.SOCKET4677_AZIF0045P001C01CS(CHIPS)':
 'VCCFA_EHV_FIVRA33': CDS_PINID='VCCFA_EHV_FIVRA33';
NODE_NAME     U2 CE74
 '@S9S_MB_2U_LIB.S9S_MB_2U(SCH_1):PAGE38_I4@PURE_QUANTA.SOCKET4677_AZIF0045P001C01CS(CHIPS)':
 'VCCFA_EHV_FIVRA34': CDS_PINID='VCCFA_EHV_FIVRA34';
NODE_NAME     U2 CK73
 '@S9S_MB_2U_LIB.S9S_MB_2U(SCH_1):PAGE38_I4@PURE_QUANTA.SOCKET4677_AZIF0045P001C01CS(CHIPS)':
 'VCCFA_EHV_FIVRA35': CDS_PINID='VCCFA_EHV_FIVRA35';
NODE_NAME     U2 CK79
 '@S9S_MB_2U_LIB.S9S_MB_2U(SCH_1):PAGE38_I4@PURE_QUANTA.SOCKET4677_AZIF0045P001C01CS(CHIPS)':
 'VCCFA_EHV_FIVRA36': CDS_PINID='VCCFA_EHV_FIVRA36';
NODE_NAME     U2 CM73
 '@S9S_MB_2U_LIB.S9S_MB_2U(SCH_1):PAGE38_I4@PURE_QUANTA.SOCKET4677_AZIF0045P001C01CS(CHIPS)':
 'VCCFA_EHV_FIVRA37': CDS_PINID='VCCFA_EHV_FIVRA37';
NODE_NAME     U2 CN78
 '@S9S_MB_2U_LIB.S9S_MB_2U(SCH_1):PAGE38_I4@PURE_QUANTA.SOCKET4677_AZIF0045P001C01CS(CHIPS)':
 'VCCFA_EHV_FIVRA38': CDS_PINID='VCCFA_EHV_FIVRA38';
NODE_NAME     U2 CP73
 '@S9S_MB_2U_LIB.S9S_MB_2U(SCH_1):PAGE38_I4@PURE_QUANTA.SOCKET4677_AZIF0045P001C01CS(CHIPS)':
 'VCCFA_EHV_FIVRA39': CDS_PINID='VCCFA_EHV_FIVRA39';
NODE_NAME     U2 CT77
 '@S9S_MB_2U_LIB.S9S_MB_2U(SCH_1):PAGE38_I4@PURE_QUANTA.SOCKET4677_AZIF0045P001C01CS(CHIPS)':
 'VCCFA_EHV_FIVRA40': CDS_PINID='VCCFA_EHV_FIVRA40';
NODE_NAME     U2 CT85
 '@S9S_MB_2U_LIB.S9S_MB_2U(SCH_1):PAGE38_I4@PURE_QUANTA.SOCKET4677_AZIF0045P001C01CS(CHIPS)':
 'VCCFA_EHV_FIVRA41': CDS_PINID='VCCFA_EHV_FIVRA41';
NODE_NAME     U2 CY75
 '@S9S_MB_2U_LIB.S9S_MB_2U(SCH_1):PAGE38_I4@PURE_QUANTA.SOCKET4677_AZIF0045P001C01CS(CHIPS)':
 'VCCFA_EHV_FIVRA42': CDS_PINID='VCCFA_EHV_FIVRA42';
NODE_NAME     U2 CY79
 '@S9S_MB_2U_LIB.S9S_MB_2U(SCH_1):PAGE38_I4@PURE_QUANTA.SOCKET4677_AZIF0045P001C01CS(CHIPS)':
 'VCCFA_EHV_FIVRA43': CDS_PINID='VCCFA_EHV_FIVRA43';
NODE_NAME     U2 CY85
 '@S9S_MB_2U_LIB.S9S_MB_2U(SCH_1):PAGE38_I4@PURE_QUANTA.SOCKET4677_AZIF0045P001C01CS(CHIPS)':
 'VCCFA_EHV_FIVRA44': CDS_PINID='VCCFA_EHV_FIVRA44';
NODE_NAME     U2 CY89
 '@S9S_MB_2U_LIB.S9S_MB_2U(SCH_1):PAGE38_I4@PURE_QUANTA.SOCKET4677_AZIF0045P001C01CS(CHIPS)':
 'VCCFA_EHV_FIVRA45': CDS_PINID='VCCFA_EHV_FIVRA45';
NODE_NAME     U2 DD77
 '@S9S_MB_2U_LIB.S9S_MB_2U(SCH_1):PAGE38_I4@PURE_QUANTA.SOCKET4677_AZIF0045P001C01CS(CHIPS)':
 'VCCFA_EHV_FIVRA46': CDS_PINID='VCCFA_EHV_FIVRA46';
NODE_NAME     U2 DD83
 '@S9S_MB_2U_LIB.S9S_MB_2U(SCH_1):PAGE38_I4@PURE_QUANTA.SOCKET4677_AZIF0045P001C01CS(CHIPS)':
 'VCCFA_EHV_FIVRA47': CDS_PINID='VCCFA_EHV_FIVRA47';
NODE_NAME     U2 DD85
 '@S9S_MB_2U_LIB.S9S_MB_2U(SCH_1):PAGE38_I4@PURE_QUANTA.SOCKET4677_AZIF0045P001C01CS(CHIPS)':
 'VCCFA_EHV_FIVRA48': CDS_PINID='VCCFA_EHV_FIVRA48';
NODE_NAME     U2 DD89
 '@S9S_MB_2U_LIB.S9S_MB_2U(SCH_1):PAGE38_I4@PURE_QUANTA.SOCKET4677_AZIF0045P001C01CS(CHIPS)':
 'VCCFA_EHV_FIVRA49': CDS_PINID='VCCFA_EHV_FIVRA49';
NODE_NAME     U2 DH89
 '@S9S_MB_2U_LIB.S9S_MB_2U(SCH_1):PAGE38_I4@PURE_QUANTA.SOCKET4677_AZIF0045P001C01CS(CHIPS)':
 'VCCFA_EHV_FIVRA50': CDS_PINID='VCCFA_EHV_FIVRA50';
NODE_NAME     U2 DM83
 '@S9S_MB_2U_LIB.S9S_MB_2U(SCH_1):PAGE38_I4@PURE_QUANTA.SOCKET4677_AZIF0045P001C01CS(CHIPS)':
 'VCCFA_EHV_FIVRA51': CDS_PINID='VCCFA_EHV_FIVRA51';
NODE_NAME     U2 DM85
 '@S9S_MB_2U_LIB.S9S_MB_2U(SCH_1):PAGE38_I4@PURE_QUANTA.SOCKET4677_AZIF0045P001C01CS(CHIPS)':
 'VCCFA_EHV_FIVRA52': CDS_PINID='VCCFA_EHV_FIVRA52';
NODE_NAME     U2 DM89
 '@S9S_MB_2U_LIB.S9S_MB_2U(SCH_1):PAGE38_I4@PURE_QUANTA.SOCKET4677_AZIF0045P001C01CS(CHIPS)':
 'VCCFA_EHV_FIVRA53': CDS_PINID='VCCFA_EHV_FIVRA53';
NODE_NAME     U2 DN11
 '@S9S_MB_2U_LIB.S9S_MB_2U(SCH_1):PAGE38_I4@PURE_QUANTA.SOCKET4677_AZIF0045P001C01CS(CHIPS)':
 'VCCFA_EHV_FIVRA54': CDS_PINID='VCCFA_EHV_FIVRA54';
NODE_NAME     U2 DN15
 '@S9S_MB_2U_LIB.S9S_MB_2U(SCH_1):PAGE38_I4@PURE_QUANTA.SOCKET4677_AZIF0045P001C01CS(CHIPS)':
 'VCCFA_EHV_FIVRA55': CDS_PINID='VCCFA_EHV_FIVRA55';
NODE_NAME     U2 DN3
 '@S9S_MB_2U_LIB.S9S_MB_2U(SCH_1):PAGE38_I4@PURE_QUANTA.SOCKET4677_AZIF0045P001C01CS(CHIPS)':
 'VCCFA_EHV_FIVRA56': CDS_PINID='VCCFA_EHV_FIVRA56';
NODE_NAME     U2 DN7
 '@S9S_MB_2U_LIB.S9S_MB_2U(SCH_1):PAGE38_I4@PURE_QUANTA.SOCKET4677_AZIF0045P001C01CS(CHIPS)':
 'VCCFA_EHV_FIVRA57': CDS_PINID='VCCFA_EHV_FIVRA57';
NODE_NAME     U2 DT79
 '@S9S_MB_2U_LIB.S9S_MB_2U(SCH_1):PAGE38_I4@PURE_QUANTA.SOCKET4677_AZIF0045P001C01CS(CHIPS)':
 'VCCFA_EHV_FIVRA58': CDS_PINID='VCCFA_EHV_FIVRA58';
NODE_NAME     U2 DT85
 '@S9S_MB_2U_LIB.S9S_MB_2U(SCH_1):PAGE38_I4@PURE_QUANTA.SOCKET4677_AZIF0045P001C01CS(CHIPS)':
 'VCCFA_EHV_FIVRA59': CDS_PINID='VCCFA_EHV_FIVRA59';
NODE_NAME     U2 DT89
 '@S9S_MB_2U_LIB.S9S_MB_2U(SCH_1):PAGE38_I4@PURE_QUANTA.SOCKET4677_AZIF0045P001C01CS(CHIPS)':
 'VCCFA_EHV_FIVRA60': CDS_PINID='VCCFA_EHV_FIVRA60';
NODE_NAME     U2 DU11
 '@S9S_MB_2U_LIB.S9S_MB_2U(SCH_1):PAGE38_I4@PURE_QUANTA.SOCKET4677_AZIF0045P001C01CS(CHIPS)':
 'VCCFA_EHV_FIVRA61': CDS_PINID='VCCFA_EHV_FIVRA61';
NODE_NAME     U2 DU15
 '@S9S_MB_2U_LIB.S9S_MB_2U(SCH_1):PAGE38_I4@PURE_QUANTA.SOCKET4677_AZIF0045P001C01CS(CHIPS)':
 'VCCFA_EHV_FIVRA62': CDS_PINID='VCCFA_EHV_FIVRA62';
NODE_NAME     U2 DU3
 '@S9S_MB_2U_LIB.S9S_MB_2U(SCH_1):PAGE38_I4@PURE_QUANTA.SOCKET4677_AZIF0045P001C01CS(CHIPS)':
 'VCCFA_EHV_FIVRA63': CDS_PINID='VCCFA_EHV_FIVRA63';
NODE_NAME     U2 DU7
 '@S9S_MB_2U_LIB.S9S_MB_2U(SCH_1):PAGE38_I4@PURE_QUANTA.SOCKET4677_AZIF0045P001C01CS(CHIPS)':
 'VCCFA_EHV_FIVRA64': CDS_PINID='VCCFA_EHV_FIVRA64';
NODE_NAME     U2 DY85
 '@S9S_MB_2U_LIB.S9S_MB_2U(SCH_1):PAGE38_I4@PURE_QUANTA.SOCKET4677_AZIF0045P001C01CS(CHIPS)':
 'VCCFA_EHV_FIVRA65': CDS_PINID='VCCFA_EHV_FIVRA65';
NODE_NAME     U2 DY89
 '@S9S_MB_2U_LIB.S9S_MB_2U(SCH_1):PAGE38_I4@PURE_QUANTA.SOCKET4677_AZIF0045P001C01CS(CHIPS)':
 'VCCFA_EHV_FIVRA66': CDS_PINID='VCCFA_EHV_FIVRA66';
NODE_NAME     U2 EA11
 '@S9S_MB_2U_LIB.S9S_MB_2U(SCH_1):PAGE38_I4@PURE_QUANTA.SOCKET4677_AZIF0045P001C01CS(CHIPS)':
 'VCCFA_EHV_FIVRA67': CDS_PINID='VCCFA_EHV_FIVRA67';
NODE_NAME     U2 EA15
 '@S9S_MB_2U_LIB.S9S_MB_2U(SCH_1):PAGE38_I4@PURE_QUANTA.SOCKET4677_AZIF0045P001C01CS(CHIPS)':
 'VCCFA_EHV_FIVRA68': CDS_PINID='VCCFA_EHV_FIVRA68';
NODE_NAME     U2 EA3
 '@S9S_MB_2U_LIB.S9S_MB_2U(SCH_1):PAGE38_I4@PURE_QUANTA.SOCKET4677_AZIF0045P001C01CS(CHIPS)':
 'VCCFA_EHV_FIVRA69': CDS_PINID='VCCFA_EHV_FIVRA69';
NODE_NAME     U2 EA7
 '@S9S_MB_2U_LIB.S9S_MB_2U(SCH_1):PAGE38_I4@PURE_QUANTA.SOCKET4677_AZIF0045P001C01CS(CHIPS)':
 'VCCFA_EHV_FIVRA70': CDS_PINID='VCCFA_EHV_FIVRA70';
NODE_NAME     U2 EC78
 '@S9S_MB_2U_LIB.S9S_MB_2U(SCH_1):PAGE38_I4@PURE_QUANTA.SOCKET4677_AZIF0045P001C01CS(CHIPS)':
 'VCCFA_EHV_FIVRA71': CDS_PINID='VCCFA_EHV_FIVRA71';
NODE_NAME     U2 ED79
 '@S9S_MB_2U_LIB.S9S_MB_2U(SCH_1):PAGE38_I4@PURE_QUANTA.SOCKET4677_AZIF0045P001C01CS(CHIPS)':
 'VCCFA_EHV_FIVRA72': CDS_PINID='VCCFA_EHV_FIVRA72';
NODE_NAME     U2 ED85
 '@S9S_MB_2U_LIB.S9S_MB_2U(SCH_1):PAGE38_I4@PURE_QUANTA.SOCKET4677_AZIF0045P001C01CS(CHIPS)':
 'VCCFA_EHV_FIVRA73': CDS_PINID='VCCFA_EHV_FIVRA73';
NODE_NAME     U2 ED89
 '@S9S_MB_2U_LIB.S9S_MB_2U(SCH_1):PAGE38_I4@PURE_QUANTA.SOCKET4677_AZIF0045P001C01CS(CHIPS)':
 'VCCFA_EHV_FIVRA74': CDS_PINID='VCCFA_EHV_FIVRA74';
NODE_NAME     U2 EE11
 '@S9S_MB_2U_LIB.S9S_MB_2U(SCH_1):PAGE38_I4@PURE_QUANTA.SOCKET4677_AZIF0045P001C01CS(CHIPS)':
 'VCCFA_EHV_FIVRA75': CDS_PINID='VCCFA_EHV_FIVRA75';
NODE_NAME     U2 EE15
 '@S9S_MB_2U_LIB.S9S_MB_2U(SCH_1):PAGE38_I4@PURE_QUANTA.SOCKET4677_AZIF0045P001C01CS(CHIPS)':
 'VCCFA_EHV_FIVRA76': CDS_PINID='VCCFA_EHV_FIVRA76';
NODE_NAME     U2 EE7
 '@S9S_MB_2U_LIB.S9S_MB_2U(SCH_1):PAGE38_I4@PURE_QUANTA.SOCKET4677_AZIF0045P001C01CS(CHIPS)':
 'VCCFA_EHV_FIVRA77': CDS_PINID='VCCFA_EHV_FIVRA77';
NODE_NAME     U2 EE84
 '@S9S_MB_2U_LIB.S9S_MB_2U(SCH_1):PAGE38_I4@PURE_QUANTA.SOCKET4677_AZIF0045P001C01CS(CHIPS)':
 'VCCFA_EHV_FIVRA78': CDS_PINID='VCCFA_EHV_FIVRA78';
NODE_NAME     U2 EF79
 '@S9S_MB_2U_LIB.S9S_MB_2U(SCH_1):PAGE38_I4@PURE_QUANTA.SOCKET4677_AZIF0045P001C01CS(CHIPS)':
 'VCCFA_EHV_FIVRA79': CDS_PINID='VCCFA_EHV_FIVRA79';
NODE_NAME     U2 EG80
 '@S9S_MB_2U_LIB.S9S_MB_2U(SCH_1):PAGE38_I4@PURE_QUANTA.SOCKET4677_AZIF0045P001C01CS(CHIPS)':
 'VCCFA_EHV_FIVRA80': CDS_PINID='VCCFA_EHV_FIVRA80';
NODE_NAME     U2 EJ15
 '@S9S_MB_2U_LIB.S9S_MB_2U(SCH_1):PAGE38_I4@PURE_QUANTA.SOCKET4677_AZIF0045P001C01CS(CHIPS)':
 'VCCFA_EHV_FIVRA81': CDS_PINID='VCCFA_EHV_FIVRA81';
NODE_NAME     U2 EJ84
 '@S9S_MB_2U_LIB.S9S_MB_2U(SCH_1):PAGE38_I4@PURE_QUANTA.SOCKET4677_AZIF0045P001C01CS(CHIPS)':
 'VCCFA_EHV_FIVRA82': CDS_PINID='VCCFA_EHV_FIVRA82';
NODE_NAME     U2 EN84
 '@S9S_MB_2U_LIB.S9S_MB_2U(SCH_1):PAGE38_I4@PURE_QUANTA.SOCKET4677_AZIF0045P001C01CS(CHIPS)':
 'VCCFA_EHV_FIVRA83': CDS_PINID='VCCFA_EHV_FIVRA83';
NODE_NAME     U2 H89
 '@S9S_MB_2U_LIB.S9S_MB_2U(SCH_1):PAGE38_I4@PURE_QUANTA.SOCKET4677_AZIF0045P001C01CS(CHIPS)':
 'VCCFA_EHV_FIVRA84': CDS_PINID='VCCFA_EHV_FIVRA84';
NODE_NAME     U2 J11
 '@S9S_MB_2U_LIB.S9S_MB_2U(SCH_1):PAGE38_I4@PURE_QUANTA.SOCKET4677_AZIF0045P001C01CS(CHIPS)':
 'VCCFA_EHV_FIVRA85': CDS_PINID='VCCFA_EHV_FIVRA85';
NODE_NAME     U2 J7
 '@S9S_MB_2U_LIB.S9S_MB_2U(SCH_1):PAGE38_I4@PURE_QUANTA.SOCKET4677_AZIF0045P001C01CS(CHIPS)':
 'VCCFA_EHV_FIVRA86': CDS_PINID='VCCFA_EHV_FIVRA86';
NODE_NAME     U2 J80
 '@S9S_MB_2U_LIB.S9S_MB_2U(SCH_1):PAGE38_I4@PURE_QUANTA.SOCKET4677_AZIF0045P001C01CS(CHIPS)':
 'VCCFA_EHV_FIVRA87': CDS_PINID='VCCFA_EHV_FIVRA87';
NODE_NAME     U2 K87
 '@S9S_MB_2U_LIB.S9S_MB_2U(SCH_1):PAGE38_I4@PURE_QUANTA.SOCKET4677_AZIF0045P001C01CS(CHIPS)':
 'VCCFA_EHV_FIVRA88': CDS_PINID='VCCFA_EHV_FIVRA88';
NODE_NAME     U2 L84
 '@S9S_MB_2U_LIB.S9S_MB_2U(SCH_1):PAGE38_I4@PURE_QUANTA.SOCKET4677_AZIF0045P001C01CS(CHIPS)':
 'VCCFA_EHV_FIVRA89': CDS_PINID='VCCFA_EHV_FIVRA89';
NODE_NAME     U2 M85
 '@S9S_MB_2U_LIB.S9S_MB_2U(SCH_1):PAGE38_I4@PURE_QUANTA.SOCKET4677_AZIF0045P001C01CS(CHIPS)':
 'VCCFA_EHV_FIVRA90': CDS_PINID='VCCFA_EHV_FIVRA90';
NODE_NAME     U2 M89
 '@S9S_MB_2U_LIB.S9S_MB_2U(SCH_1):PAGE38_I4@PURE_QUANTA.SOCKET4677_AZIF0045P001C01CS(CHIPS)':
 'VCCFA_EHV_FIVRA91': CDS_PINID='VCCFA_EHV_FIVRA91';
NODE_NAME     U2 N11
 '@S9S_MB_2U_LIB.S9S_MB_2U(SCH_1):PAGE38_I4@PURE_QUANTA.SOCKET4677_AZIF0045P001C01CS(CHIPS)':
 'VCCFA_EHV_FIVRA92': CDS_PINID='VCCFA_EHV_FIVRA92';
NODE_NAME     U2 N7
 '@S9S_MB_2U_LIB.S9S_MB_2U(SCH_1):PAGE38_I4@PURE_QUANTA.SOCKET4677_AZIF0045P001C01CS(CHIPS)':
 'VCCFA_EHV_FIVRA93': CDS_PINID='VCCFA_EHV_FIVRA93';
NODE_NAME     U2 P79
 '@S9S_MB_2U_LIB.S9S_MB_2U(SCH_1):PAGE38_I4@PURE_QUANTA.SOCKET4677_AZIF0045P001C01CS(CHIPS)':
 'VCCFA_EHV_FIVRA94': CDS_PINID='VCCFA_EHV_FIVRA94';
NODE_NAME     U2 R80
 '@S9S_MB_2U_LIB.S9S_MB_2U(SCH_1):PAGE38_I4@PURE_QUANTA.SOCKET4677_AZIF0045P001C01CS(CHIPS)':
 'VCCFA_EHV_FIVRA95': CDS_PINID='VCCFA_EHV_FIVRA95';
NODE_NAME     U2 T85
 '@S9S_MB_2U_LIB.S9S_MB_2U(SCH_1):PAGE38_I4@PURE_QUANTA.SOCKET4677_AZIF0045P001C01CS(CHIPS)':
 'VCCFA_EHV_FIVRA96': CDS_PINID='VCCFA_EHV_FIVRA96';
NODE_NAME     U2 T89
 '@S9S_MB_2U_LIB.S9S_MB_2U(SCH_1):PAGE38_I4@PURE_QUANTA.SOCKET4677_AZIF0045P001C01CS(CHIPS)':
 'VCCFA_EHV_FIVRA97': CDS_PINID='VCCFA_EHV_FIVRA97';
NODE_NAME     U2 U11
 '@S9S_MB_2U_LIB.S9S_MB_2U(SCH_1):PAGE38_I4@PURE_QUANTA.SOCKET4677_AZIF0045P001C01CS(CHIPS)':
 'VCCFA_EHV_FIVRA98': CDS_PINID='VCCFA_EHV_FIVRA98';
NODE_NAME     U2 U15
 '@S9S_MB_2U_LIB.S9S_MB_2U(SCH_1):PAGE38_I4@PURE_QUANTA.SOCKET4677_AZIF0045P001C01CS(CHIPS)':
 'VCCFA_EHV_FIVRA99': CDS_PINID='VCCFA_EHV_FIVRA99';
NODE_NAME     U2 U7
 '@S9S_MB_2U_LIB.S9S_MB_2U(SCH_1):PAGE38_I4@PURE_QUANTA.SOCKET4677_AZIF0045P001C01CS(CHIPS)':
 'VCCFA_EHV_FIVRA100': CDS_PINID='VCCFA_EHV_FIVRA100';
NODE_NAME     U2 W80
 '@S9S_MB_2U_LIB.S9S_MB_2U(SCH_1):PAGE38_I4@PURE_QUANTA.SOCKET4677_AZIF0045P001C01CS(CHIPS)':
 'VCCFA_EHV_FIVRA101': CDS_PINID='VCCFA_EHV_FIVRA101';
NODE_NAME     U2 Y79
 '@S9S_MB_2U_LIB.S9S_MB_2U(SCH_1):PAGE38_I4@PURE_QUANTA.SOCKET4677_AZIF0045P001C01CS(CHIPS)':
 'VCCFA_EHV_FIVRA102': CDS_PINID='VCCFA_EHV_FIVRA102';
NODE_NAME     U2 Y85
 '@S9S_MB_2U_LIB.S9S_MB_2U(SCH_1):PAGE38_I4@PURE_QUANTA.SOCKET4677_AZIF0045P001C01CS(CHIPS)':
 'VCCFA_EHV_FIVRA103': CDS_PINID='VCCFA_EHV_FIVRA103';
NODE_NAME     U2 Y89
 '@S9S_MB_2U_LIB.S9S_MB_2U(SCH_1):PAGE38_I4@PURE_QUANTA.SOCKET4677_AZIF0045P001C01CS(CHIPS)':
 'VCCFA_EHV_FIVRA104': CDS_PINID='VCCFA_EHV_FIVRA104';
NODE_NAME     C407 1
 '@S9S_MB_2U_LIB.S9S_MB_2U(SCH_1):PAGE74_I7@PURE_QUANTA.Q_CAP(CHIPS)':
 'A': CDS_PINID='A';
NODE_NAME     C409 1
 '@S9S_MB_2U_LIB.S9S_MB_2U(SCH_1):PAGE74_I8@PURE_QUANTA.Q_CAP(CHIPS)':
 'A': CDS_PINID='A';
NODE_NAME     C411 1
 '@S9S_MB_2U_LIB.S9S_MB_2U(SCH_1):PAGE74_I9@PURE_QUANTA.Q_CAP(CHIPS)':
 'A': CDS_PINID='A';
NODE_NAME     C413 1
 '@S9S_MB_2U_LIB.S9S_MB_2U(SCH_1):PAGE74_I10@PURE_QUANTA.Q_CAP(CHIPS)':
 'A': CDS_PINID='A';
NODE_NAME     C415 1
 '@S9S_MB_2U_LIB.S9S_MB_2U(SCH_1):PAGE74_I64@PURE_QUANTA.Q_CAP(CHIPS)':
 'A': CDS_PINID='A';
NODE_NAME     C417 1
 '@S9S_MB_2U_LIB.S9S_MB_2U(SCH_1):PAGE74_I65@PURE_QUANTA.Q_CAP(CHIPS)':
 'A': CDS_PINID='A';
NODE_NAME     C418 1
 '@S9S_MB_2U_LIB.S9S_MB_2U(SCH_1):PAGE74_I68@PURE_QUANTA.Q_CAP(CHIPS)':
 'A': CDS_PINID='A';
NODE_NAME     C493 1
 '@S9S_MB_2U_LIB.S9S_MB_2U(SCH_1):PAGE75_I1@PURE_QUANTA.Q_CAP(CHIPS)':
 'A': CDS_PINID='A';
NODE_NAME     C497 1
 '@S9S_MB_2U_LIB.S9S_MB_2U(SCH_1):PAGE75_I3@PURE_QUANTA.Q_CAP(CHIPS)':
 'A': CDS_PINID='A';
NODE_NAME     C501 1
 '@S9S_MB_2U_LIB.S9S_MB_2U(SCH_1):PAGE75_I4@PURE_QUANTA.Q_CAP(CHIPS)':
 'A': CDS_PINID='A';
NODE_NAME     C494 1
 '@S9S_MB_2U_LIB.S9S_MB_2U(SCH_1):PAGE76_I1@PURE_QUANTA.Q_CAP(CHIPS)':
 'A': CDS_PINID='A';
NODE_NAME     C510 1
 '@S9S_MB_2U_LIB.S9S_MB_2U(SCH_1):PAGE76_I27@PURE_QUANTA.Q_CAP(CHIPS)':
 'A': CDS_PINID='A';
NODE_NAME     C514 1
 '@S9S_MB_2U_LIB.S9S_MB_2U(SCH_1):PAGE76_I28@PURE_QUANTA.Q_CAP(CHIPS)':
 'A': CDS_PINID='A';
NODE_NAME     C517 1
 '@S9S_MB_2U_LIB.S9S_MB_2U(SCH_1):PAGE76_I29@PURE_QUANTA.Q_CAP(CHIPS)':
 'A': CDS_PINID='A';
NODE_NAME     C529 1
 '@S9S_MB_2U_LIB.S9S_MB_2U(SCH_1):PAGE76_I41@PURE_QUANTA.Q_CAP(CHIPS)':
 'A': CDS_PINID='A';
NODE_NAME     PL34 2
 '@S9S_MB_2U_LIB.S9S_MB_2U(SCH_1):PAGE257_I49@PURE_QUANTA.Q_INDUCTOR(CHIPS)':
 '2': CDS_PINID='\2\';
NODE_NAME     PR1323 2
 '@S9S_MB_2U_LIB.S9S_MB_2U(SCH_1):PAGE257_I50@PURE_QUANTA.Q_RES(CHIPS)':
 'B': CDS_PINID='B';
NODE_NAME     PC618_P0_2 1
 '@S9S_MB_2U_LIB.S9S_MB_2U(SCH_1):PAGE257_I59@PURE_QUANTA.Q_CAP(CHIPS)':
 'A': CDS_PINID='A';
NODE_NAME     PC621 1
 '@S9S_MB_2U_LIB.S9S_MB_2U(SCH_1):PAGE257_I62@PURE_QUANTA.Q_CAPP(CHIPS)':
 'A': CDS_PINID='A';
NODE_NAME     PL210 2
 '@S9S_MB_2U_LIB.S9S_MB_2U(SCH_1):PAGE258_I39@PURE_QUANTA.Q_INDUCTOR(CHIPS)':
 '2': CDS_PINID='\2\';
NODE_NAME     PC1183_P0_4 1
 '@S9S_MB_2U_LIB.S9S_MB_2U(SCH_1):PAGE258_I40@PURE_QUANTA.Q_CAP(CHIPS)':
 'A': CDS_PINID='A';
NODE_NAME     PC1183_P0_3 1
 '@S9S_MB_2U_LIB.S9S_MB_2U(SCH_1):PAGE258_I55@PURE_QUANTA.Q_CAP(CHIPS)':
 'A': CDS_PINID='A';
NODE_NAME     PC1188_P0_4 1
 '@S9S_MB_2U_LIB.S9S_MB_2U(SCH_1):PAGE258_I61@PURE_QUANTA.Q_CAP(CHIPS)':
 'A': CDS_PINID='A';
NODE_NAME     PC1186 1
 '@S9S_MB_2U_LIB.S9S_MB_2U(SCH_1):PAGE258_I68@PURE_QUANTA.Q_CAPP(CHIPS)':
 'A': CDS_PINID='A';
NODE_NAME     PL2 2
 '@S9S_MB_2U_LIB.S9S_MB_2U(SCH_1):PAGE258_I51@PURE_QUANTA.Q_INDUCTOR(CHIPS)':
 '2': CDS_PINID='\2\';
NODE_NAME     C400 1
 '@S9S_MB_2U_LIB.S9S_MB_2U(SCH_1):PAGE74_I1@PURE_QUANTA.Q_CAP(CHIPS)':
 'A': CDS_PINID='A';
NODE_NAME     C402 1
 '@S9S_MB_2U_LIB.S9S_MB_2U(SCH_1):PAGE74_I3@PURE_QUANTA.Q_CAP(CHIPS)':
 'A': CDS_PINID='A';
NODE_NAME     C404 1
 '@S9S_MB_2U_LIB.S9S_MB_2U(SCH_1):PAGE74_I4@PURE_QUANTA.Q_CAP(CHIPS)':
 'A': CDS_PINID='A';
NODE_NAME     C406 1
 '@S9S_MB_2U_LIB.S9S_MB_2U(SCH_1):PAGE74_I5@PURE_QUANTA.Q_CAP(CHIPS)':
 'A': CDS_PINID='A';
NODE_NAME     C505 1
 '@S9S_MB_2U_LIB.S9S_MB_2U(SCH_1):PAGE75_I6@PURE_QUANTA.Q_CAP(CHIPS)':
 'A': CDS_PINID='A';
NODE_NAME     C509 1
 '@S9S_MB_2U_LIB.S9S_MB_2U(SCH_1):PAGE75_I8@PURE_QUANTA.Q_CAP(CHIPS)':
 'A': CDS_PINID='A';
NODE_NAME     C498 1
 '@S9S_MB_2U_LIB.S9S_MB_2U(SCH_1):PAGE76_I2@PURE_QUANTA.Q_CAP(CHIPS)':
 'A': CDS_PINID='A';
NODE_NAME     C502 1
 '@S9S_MB_2U_LIB.S9S_MB_2U(SCH_1):PAGE76_I3@PURE_QUANTA.Q_CAP(CHIPS)':
 'A': CDS_PINID='A';
NODE_NAME     C506 1
 '@S9S_MB_2U_LIB.S9S_MB_2U(SCH_1):PAGE76_I26@PURE_QUANTA.Q_CAP(CHIPS)':
 'A': CDS_PINID='A';
NODE_NAME     C520 1
 '@S9S_MB_2U_LIB.S9S_MB_2U(SCH_1):PAGE76_I36@PURE_QUANTA.Q_CAP(CHIPS)':
 'A': CDS_PINID='A';
NODE_NAME     C521 1
 '@S9S_MB_2U_LIB.S9S_MB_2U(SCH_1):PAGE76_I37@PURE_QUANTA.Q_CAP(CHIPS)':
 'A': CDS_PINID='A';
NODE_NAME     C523 1
 '@S9S_MB_2U_LIB.S9S_MB_2U(SCH_1):PAGE76_I38@PURE_QUANTA.Q_CAP(CHIPS)':
 'A': CDS_PINID='A';
NODE_NAME     C526 1
 '@S9S_MB_2U_LIB.S9S_MB_2U(SCH_1):PAGE76_I39@PURE_QUANTA.Q_CAP(CHIPS)':
 'A': CDS_PINID='A';
NODE_NAME     PC613_P0_2 1
 '@S9S_MB_2U_LIB.S9S_MB_2U(SCH_1):PAGE257_I51@PURE_QUANTA.Q_CAP(CHIPS)':
 'A': CDS_PINID='A';
NODE_NAME     PR1325 2
 '@S9S_MB_2U_LIB.S9S_MB_2U(SCH_1):PAGE258_I38@PURE_QUANTA.Q_RES(CHIPS)':
 'B': CDS_PINID='B';
NODE_NAME     PC1185_P0_3 1
 '@S9S_MB_2U_LIB.S9S_MB_2U(SCH_1):PAGE258_I72@PURE_QUANTA.Q_CAP(CHIPS)':
 'A': CDS_PINID='A';
NODE_NAME     PR1322 2
 '@S9S_MB_2U_LIB.S9S_MB_2U(SCH_1):PAGE257_I69@PURE_QUANTA.Q_RES(CHIPS)':
 'B': CDS_PINID='B';
NODE_NAME     PC615_P0_1 1
 '@S9S_MB_2U_LIB.S9S_MB_2U(SCH_1):PAGE257_I77@PURE_QUANTA.Q_CAP(CHIPS)':
 'A': CDS_PINID='A';
NODE_NAME     PR1324 2
 '@S9S_MB_2U_LIB.S9S_MB_2U(SCH_1):PAGE258_I50@PURE_QUANTA.Q_RES(CHIPS)':
 'B': CDS_PINID='B';
NODE_NAME     PC1186_P0_4 1
 '@S9S_MB_2U_LIB.S9S_MB_2U(SCH_1):PAGE258_I60@PURE_QUANTA.Q_CAP(CHIPS)':
 'A': CDS_PINID='A';
NODE_NAME     PC616_P0_2 1
 '@S9S_MB_2U_LIB.S9S_MB_2U(SCH_1):PAGE257_I52@PURE_QUANTA.Q_CAP(CHIPS)':
 'A': CDS_PINID='A';
NODE_NAME     PC619 1
 '@S9S_MB_2U_LIB.S9S_MB_2U(SCH_1):PAGE257_I57@PURE_QUANTA.Q_CAPP(CHIPS)':
 'A': CDS_PINID='A';
NODE_NAME     PC620 1
 '@S9S_MB_2U_LIB.S9S_MB_2U(SCH_1):PAGE257_I58@PURE_QUANTA.Q_CAPP(CHIPS)':
 'A': CDS_PINID='A';
NODE_NAME     PL33 2
 '@S9S_MB_2U_LIB.S9S_MB_2U(SCH_1):PAGE257_I70@PURE_QUANTA.Q_INDUCTOR(CHIPS)':
 '2': CDS_PINID='\2\';
NODE_NAME     PR4265 1
 '@S9S_MB_2U_LIB.S9S_MB_2U(SCH_1):PAGE257_I60@PURE_QUANTA.Q_RES(CHIPS)':
 'A': CDS_PINID='A';
NODE_NAME     PC623 1
 '@S9S_MB_2U_LIB.S9S_MB_2U(SCH_1):PAGE257_I63@PURE_QUANTA.Q_CAPP(CHIPS)':
 'A': CDS_PINID='A';
NODE_NAME     PC2645 1
 '@S9S_MB_2U_LIB.S9S_MB_2U(SCH_1):PAGE257_I67@PURE_QUANTA.Q_CAPP(CHIPS)':
 'A': CDS_PINID='A';
NODE_NAME     PC612_P0_1 1
 '@S9S_MB_2U_LIB.S9S_MB_2U(SCH_1):PAGE257_I75@PURE_QUANTA.Q_CAP(CHIPS)':
 'A': CDS_PINID='A';
NODE_NAME     PC617_P0_1 1
 '@S9S_MB_2U_LIB.S9S_MB_2U(SCH_1):PAGE257_I81@PURE_QUANTA.Q_CAP(CHIPS)':
 'A': CDS_PINID='A';
NODE_NAME     PC1183 1
 '@S9S_MB_2U_LIB.S9S_MB_2U(SCH_1):PAGE258_I64@PURE_QUANTA.Q_CAPP(CHIPS)':
 'A': CDS_PINID='A';
NODE_NAME     PC1185 1
 '@S9S_MB_2U_LIB.S9S_MB_2U(SCH_1):PAGE258_I65@PURE_QUANTA.Q_CAPP(CHIPS)':
 'A': CDS_PINID='A';
NODE_NAME     PC1187 1
 '@S9S_MB_2U_LIB.S9S_MB_2U(SCH_1):PAGE258_I69@PURE_QUANTA.Q_CAPP(CHIPS)':
 'A': CDS_PINID='A';
NODE_NAME     PC2170 1
 '@S9S_MB_2U_LIB.S9S_MB_2U(SCH_1):PAGE258_I70@PURE_QUANTA.Q_CAPP(CHIPS)':
 'A': CDS_PINID='A';
NODE_NAME     PC1187_P0_3 1
 '@S9S_MB_2U_LIB.S9S_MB_2U(SCH_1):PAGE258_I73@PURE_QUANTA.Q_CAP(CHIPS)':
 'A': CDS_PINID='A';
NODE_NAME     PR587 2
 '@S9S_MB_2U_LIB.S9S_MB_2U(SCH_1):PAGE252_I25@PURE_QUANTA.Q_RES(CHIPS)':
 'B': CDS_PINID='B';
NET_NAME
'PVCCFA_EHV_FIVRA_CPU0_BTSEN'
 '@S9S_MB_2U_LIB.S9S_MB_2U(SCH_1):PVCCFA_EHV_FIVRA_CPU0_BTSEN':
 C_SIGNAL='@s9s_mb_2u_lib.s9s_mb_2u(sch_1):pvccfa_ehv_fivra_cpu0_btsen';
NODE_NAME     PU14 44
 '@S9S_MB_2U_LIB.S9S_MB_2U(SCH_1):PAGE252_I63@PURE_QUANTA.RAA229126GNPHA0(CHIPS)':
 'TEMP1||ISYS': CDS_PINID='\temp1||isys\';
NODE_NAME     PU70_P0_2 36
 '@S9S_MB_2U_LIB.S9S_MB_2U(SCH_1):PAGE257_I16@PURE_QUANTA.ISL99390FRZTR5935(CHIPS)':
 'TOUT_FLT': CDS_PINID='TOUT_FLT';
NODE_NAME     PU71_P0_3 36
 '@S9S_MB_2U_LIB.S9S_MB_2U(SCH_1):PAGE258_I82@PURE_QUANTA.ISL99390FRZTR5935(CHIPS)':
 'TOUT_FLT': CDS_PINID='TOUT_FLT';
NODE_NAME     PU69_P0_1 36
 '@S9S_MB_2U_LIB.S9S_MB_2U(SCH_1):PAGE257_I25@PURE_QUANTA.ISL99390FRZTR5935(CHIPS)':
 'TOUT_FLT': CDS_PINID='TOUT_FLT';
NODE_NAME     PU72_P0_4 36
 '@S9S_MB_2U_LIB.S9S_MB_2U(SCH_1):PAGE258_I10@PURE_QUANTA.ISL99390FRZTR5935(CHIPS)':
 'TOUT_FLT': CDS_PINID='TOUT_FLT';
NODE_NAME     PC100 1
 '@S9S_MB_2U_LIB.S9S_MB_2U(SCH_1):PAGE252_I116@PURE_QUANTA.Q_CAP(CHIPS)':
 'A': CDS_PINID='A';
NODE_NAME     PR451 1
 '@S9S_MB_2U_LIB.S9S_MB_2U(SCH_1):PAGE252_I121@PURE_QUANTA.Q_RES(CHIPS)':
 'A': CDS_PINID='A';
NET_NAME
'PVCCFA_EHV_FIVRA_CPU0_EN_R'
 '@S9S_MB_2U_LIB.S9S_MB_2U(SCH_1):PVCCFA_EHV_FIVRA_CPU0_EN_R':
 C_SIGNAL='@s9s_mb_2u_lib.s9s_mb_2u(sch_1):pvccfa_ehv_fivra_cpu0_en_r';
NODE_NAME     PU14 24
 '@S9S_MB_2U_LIB.S9S_MB_2U(SCH_1):PAGE252_I63@PURE_QUANTA.RAA229126GNPHA0(CHIPS)':
 'EN1': CDS_PINID='EN1';
NODE_NAME     C3268 1
 '@S9S_MB_2U_LIB.S9S_MB_2U(SCH_1):PAGE252_I58@PURE_QUANTA.Q_CAP(CHIPS)':
 'A': CDS_PINID='A';
NODE_NAME     R4216 2
 '@S9S_MB_2U_LIB.S9S_MB_2U(SCH_1):PAGE252_I56@PURE_QUANTA.Q_RES(CHIPS)':
 'B': CDS_PINID='B';
NET_NAME
'PVCCFA_EHV_FIVRA_CPU0_IMON1'
 '@S9S_MB_2U_LIB.S9S_MB_2U(SCH_1):PVCCFA_EHV_FIVRA_CPU0_IMON1':
 C_SIGNAL='@s9s_mb_2u_lib.s9s_mb_2u(sch_1):pvccfa_ehv_fivra_cpu0_imon1';
NODE_NAME     PU14 38
 '@S9S_MB_2U_LIB.S9S_MB_2U(SCH_1):PAGE252_I63@PURE_QUANTA.RAA229126GNPHA0(CHIPS)':
 'CS0': CDS_PINID='CS0';
NODE_NAME     PU69_P0_1 38
 '@S9S_MB_2U_LIB.S9S_MB_2U(SCH_1):PAGE257_I25@PURE_QUANTA.ISL99390FRZTR5935(CHIPS)':
 'IOUT': CDS_PINID='IOUT';
NET_NAME
'PVCCFA_EHV_FIVRA_CPU0_IMON2'
 '@S9S_MB_2U_LIB.S9S_MB_2U(SCH_1):PVCCFA_EHV_FIVRA_CPU0_IMON2':
 C_SIGNAL='@s9s_mb_2u_lib.s9s_mb_2u(sch_1):pvccfa_ehv_fivra_cpu0_imon2';
NODE_NAME     PU14 37
 '@S9S_MB_2U_LIB.S9S_MB_2U(SCH_1):PAGE252_I63@PURE_QUANTA.RAA229126GNPHA0(CHIPS)':
 'CS1': CDS_PINID='CS1';
NODE_NAME     PU70_P0_2 38
 '@S9S_MB_2U_LIB.S9S_MB_2U(SCH_1):PAGE257_I16@PURE_QUANTA.ISL99390FRZTR5935(CHIPS)':
 'IOUT': CDS_PINID='IOUT';
NET_NAME
'PVCCFA_EHV_FIVRA_CPU0_IMON3'
 '@S9S_MB_2U_LIB.S9S_MB_2U(SCH_1):PVCCFA_EHV_FIVRA_CPU0_IMON3':
 C_SIGNAL='@s9s_mb_2u_lib.s9s_mb_2u(sch_1):pvccfa_ehv_fivra_cpu0_imon3';
NODE_NAME     PU14 36
 '@S9S_MB_2U_LIB.S9S_MB_2U(SCH_1):PAGE252_I63@PURE_QUANTA.RAA229126GNPHA0(CHIPS)':
 'CS2': CDS_PINID='CS2';
NODE_NAME     PU71_P0_3 38
 '@S9S_MB_2U_LIB.S9S_MB_2U(SCH_1):PAGE258_I82@PURE_QUANTA.ISL99390FRZTR5935(CHIPS)':
 'IOUT': CDS_PINID='IOUT';
NODE_NAME     PR4218 1
 '@S9S_MB_2U_LIB.S9S_MB_2U(SCH_1):PAGE252_I73@PURE_QUANTA.Q_RES(CHIPS)':
 'A': CDS_PINID='A';
NET_NAME
'PVCCFA_EHV_FIVRA_CPU0_IMON4'
 '@S9S_MB_2U_LIB.S9S_MB_2U(SCH_1):PVCCFA_EHV_FIVRA_CPU0_IMON4':
 C_SIGNAL='@s9s_mb_2u_lib.s9s_mb_2u(sch_1):pvccfa_ehv_fivra_cpu0_imon4';
NODE_NAME     PR4217 1
 '@S9S_MB_2U_LIB.S9S_MB_2U(SCH_1):PAGE252_I74@PURE_QUANTA.Q_RES(CHIPS)':
 'A': CDS_PINID='A';
NODE_NAME     PU14 35
 '@S9S_MB_2U_LIB.S9S_MB_2U(SCH_1):PAGE252_I63@PURE_QUANTA.RAA229126GNPHA0(CHIPS)':
 'CS3': CDS_PINID='CS3';
NODE_NAME     PU72_P0_4 38
 '@S9S_MB_2U_LIB.S9S_MB_2U(SCH_1):PAGE258_I10@PURE_QUANTA.ISL99390FRZTR5935(CHIPS)':
 'IOUT': CDS_PINID='IOUT';
NET_NAME
'PVCCFA_EHV_FIVRA_CPU0_LSET1'
 '@S9S_MB_2U_LIB.S9S_MB_2U(SCH_1):PVCCFA_EHV_FIVRA_CPU0_LSET1':
 C_SIGNAL='@s9s_mb_2u_lib.s9s_mb_2u(sch_1):pvccfa_ehv_fivra_cpu0_lset1';
NODE_NAME     PR354 1
 '@S9S_MB_2U_LIB.S9S_MB_2U(SCH_1):PAGE257_I8@PURE_QUANTA.Q_RES(CHIPS)':
 'A': CDS_PINID='A';
NODE_NAME     PU69_P0_1 37
 '@S9S_MB_2U_LIB.S9S_MB_2U(SCH_1):PAGE257_I25@PURE_QUANTA.ISL99390FRZTR5935(CHIPS)':
 'LSET': CDS_PINID='LSET';
NET_NAME
'PVCCFA_EHV_FIVRA_CPU0_LSET2'
 '@S9S_MB_2U_LIB.S9S_MB_2U(SCH_1):PVCCFA_EHV_FIVRA_CPU0_LSET2':
 C_SIGNAL='@s9s_mb_2u_lib.s9s_mb_2u(sch_1):pvccfa_ehv_fivra_cpu0_lset2';
NODE_NAME     PR353 1
 '@S9S_MB_2U_LIB.S9S_MB_2U(SCH_1):PAGE257_I2@PURE_QUANTA.Q_RES(CHIPS)':
 'A': CDS_PINID='A';
NODE_NAME     PU70_P0_2 37
 '@S9S_MB_2U_LIB.S9S_MB_2U(SCH_1):PAGE257_I16@PURE_QUANTA.ISL99390FRZTR5935(CHIPS)':
 'LSET': CDS_PINID='LSET';
NET_NAME
'PVCCFA_EHV_FIVRA_CPU0_LSET3'
 '@S9S_MB_2U_LIB.S9S_MB_2U(SCH_1):PVCCFA_EHV_FIVRA_CPU0_LSET3':
 C_SIGNAL='@s9s_mb_2u_lib.s9s_mb_2u(sch_1):pvccfa_ehv_fivra_cpu0_lset3';
NODE_NAME     PR1298 1
 '@S9S_MB_2U_LIB.S9S_MB_2U(SCH_1):PAGE258_I15@PURE_QUANTA.Q_RES(CHIPS)':
 'A': CDS_PINID='A';
NODE_NAME     PU71_P0_3 37
 '@S9S_MB_2U_LIB.S9S_MB_2U(SCH_1):PAGE258_I82@PURE_QUANTA.ISL99390FRZTR5935(CHIPS)':
 'LSET': CDS_PINID='LSET';
NET_NAME
'PVCCFA_EHV_FIVRA_CPU0_LSET4'
 '@S9S_MB_2U_LIB.S9S_MB_2U(SCH_1):PVCCFA_EHV_FIVRA_CPU0_LSET4':
 C_SIGNAL='@s9s_mb_2u_lib.s9s_mb_2u(sch_1):pvccfa_ehv_fivra_cpu0_lset4';
NODE_NAME     PR1297 1
 '@S9S_MB_2U_LIB.S9S_MB_2U(SCH_1):PAGE258_I3@PURE_QUANTA.Q_RES(CHIPS)':
 'A': CDS_PINID='A';
NODE_NAME     PU72_P0_4 37
 '@S9S_MB_2U_LIB.S9S_MB_2U(SCH_1):PAGE258_I10@PURE_QUANTA.ISL99390FRZTR5935(CHIPS)':
 'LSET': CDS_PINID='LSET';
NET_NAME
'PVCCFA_EHV_FIVRA_CPU0_PVCC1'
 '@S9S_MB_2U_LIB.S9S_MB_2U(SCH_1):PVCCFA_EHV_FIVRA_CPU0_PVCC1':
 C_SIGNAL='@s9s_mb_2u_lib.s9s_mb_2u(sch_1):pvccfa_ehv_fivra_cpu0_pvcc1',
 CDS_GLOBAL_NET='TRUE';
NODE_NAME     PR355 1
 '@S9S_MB_2U_LIB.S9S_MB_2U(SCH_1):PAGE257_I39@PURE_QUANTA.Q_RES(CHIPS)':
 'A': CDS_PINID='A';
NODE_NAME     PU71_P0_3 4
 '@S9S_MB_2U_LIB.S9S_MB_2U(SCH_1):PAGE258_I82@PURE_QUANTA.ISL99390FRZTR5935(CHIPS)':
 'PVCC': CDS_PINID='PVCC';
NODE_NAME     PR444 2
 '@S9S_MB_2U_LIB.S9S_MB_2U(SCH_1):PAGE257_I9@PURE_QUANTA.Q_RES(CHIPS)':
 'B': CDS_PINID='B';
NODE_NAME     PU69_P0_1 4
 '@S9S_MB_2U_LIB.S9S_MB_2U(SCH_1):PAGE257_I25@PURE_QUANTA.ISL99390FRZTR5935(CHIPS)':
 'PVCC': CDS_PINID='PVCC';
NODE_NAME     PR632 2
 '@S9S_MB_2U_LIB.S9S_MB_2U(SCH_1):PAGE257_I40@PURE_QUANTA.Q_RES(CHIPS)':
 'B': CDS_PINID='B';
NODE_NAME     PC1211_P0_1 1
 '@S9S_MB_2U_LIB.S9S_MB_2U(SCH_1):PAGE257_I42@PURE_QUANTA.Q_CAP(CHIPS)':
 'A': CDS_PINID='A';
NODE_NAME     PR1299 1
 '@S9S_MB_2U_LIB.S9S_MB_2U(SCH_1):PAGE258_I26@PURE_QUANTA.Q_RES(CHIPS)':
 'A': CDS_PINID='A';
NODE_NAME     PC1213_P0_3 1
 '@S9S_MB_2U_LIB.S9S_MB_2U(SCH_1):PAGE258_I28@PURE_QUANTA.Q_CAP(CHIPS)':
 'A': CDS_PINID='A';
NET_NAME
'PVCCFA_EHV_FIVRA_CPU0_PVCC2'
 '@S9S_MB_2U_LIB.S9S_MB_2U(SCH_1):PVCCFA_EHV_FIVRA_CPU0_PVCC2':
 C_SIGNAL='@s9s_mb_2u_lib.s9s_mb_2u(sch_1):pvccfa_ehv_fivra_cpu0_pvcc2',
 CDS_GLOBAL_NET='TRUE';
NODE_NAME     PR633 2
 '@S9S_MB_2U_LIB.S9S_MB_2U(SCH_1):PAGE257_I22@PURE_QUANTA.Q_RES(CHIPS)':
 'B': CDS_PINID='B';
NODE_NAME     PR1300 1
 '@S9S_MB_2U_LIB.S9S_MB_2U(SCH_1):PAGE258_I11@PURE_QUANTA.Q_RES(CHIPS)':
 'A': CDS_PINID='A';
NODE_NAME     PU70_P0_2 4
 '@S9S_MB_2U_LIB.S9S_MB_2U(SCH_1):PAGE257_I16@PURE_QUANTA.ISL99390FRZTR5935(CHIPS)':
 'PVCC': CDS_PINID='PVCC';
NODE_NAME     PR447 2
 '@S9S_MB_2U_LIB.S9S_MB_2U(SCH_1):PAGE257_I4@PURE_QUANTA.Q_RES(CHIPS)':
 'B': CDS_PINID='B';
NODE_NAME     PR356 1
 '@S9S_MB_2U_LIB.S9S_MB_2U(SCH_1):PAGE257_I19@PURE_QUANTA.Q_RES(CHIPS)':
 'A': CDS_PINID='A';
NODE_NAME     PC1212_P0_2 1
 '@S9S_MB_2U_LIB.S9S_MB_2U(SCH_1):PAGE257_I21@PURE_QUANTA.Q_CAP(CHIPS)':
 'A': CDS_PINID='A';
NODE_NAME     PU72_P0_4 4
 '@S9S_MB_2U_LIB.S9S_MB_2U(SCH_1):PAGE258_I10@PURE_QUANTA.ISL99390FRZTR5935(CHIPS)':
 'PVCC': CDS_PINID='PVCC';
NODE_NAME     PC1214_P0_4 1
 '@S9S_MB_2U_LIB.S9S_MB_2U(SCH_1):PAGE258_I18@PURE_QUANTA.Q_CAP(CHIPS)':
 'A': CDS_PINID='A';
NET_NAME
'PVCCFA_EHV_FIVRA_CPU0_PWM1'
 '@S9S_MB_2U_LIB.S9S_MB_2U(SCH_1):PVCCFA_EHV_FIVRA_CPU0_PWM1':
 C_SIGNAL='@s9s_mb_2u_lib.s9s_mb_2u(sch_1):pvccfa_ehv_fivra_cpu0_pwm1';
NODE_NAME     PU14 1
 '@S9S_MB_2U_LIB.S9S_MB_2U(SCH_1):PAGE252_I63@PURE_QUANTA.RAA229126GNPHA0(CHIPS)':
 'PWM0': CDS_PINID='PWM0';
NODE_NAME     PU69_P0_1 34
 '@S9S_MB_2U_LIB.S9S_MB_2U(SCH_1):PAGE257_I25@PURE_QUANTA.ISL99390FRZTR5935(CHIPS)':
 'PWM': CDS_PINID='PWM';
NET_NAME
'PVCCFA_EHV_FIVRA_CPU0_PWM2'
 '@S9S_MB_2U_LIB.S9S_MB_2U(SCH_1):PVCCFA_EHV_FIVRA_CPU0_PWM2':
 C_SIGNAL='@s9s_mb_2u_lib.s9s_mb_2u(sch_1):pvccfa_ehv_fivra_cpu0_pwm2';
NODE_NAME     PU14 2
 '@S9S_MB_2U_LIB.S9S_MB_2U(SCH_1):PAGE252_I63@PURE_QUANTA.RAA229126GNPHA0(CHIPS)':
 'PWM1': CDS_PINID='PWM1';
NODE_NAME     PU70_P0_2 34
 '@S9S_MB_2U_LIB.S9S_MB_2U(SCH_1):PAGE257_I16@PURE_QUANTA.ISL99390FRZTR5935(CHIPS)':
 'PWM': CDS_PINID='PWM';
NET_NAME
'PVCCFA_EHV_FIVRA_CPU0_PWM3'
 '@S9S_MB_2U_LIB.S9S_MB_2U(SCH_1):PVCCFA_EHV_FIVRA_CPU0_PWM3':
 C_SIGNAL='@s9s_mb_2u_lib.s9s_mb_2u(sch_1):pvccfa_ehv_fivra_cpu0_pwm3';
NODE_NAME     PU14 3
 '@S9S_MB_2U_LIB.S9S_MB_2U(SCH_1):PAGE252_I63@PURE_QUANTA.RAA229126GNPHA0(CHIPS)':
 'PWM2': CDS_PINID='PWM2';
NODE_NAME     PU71_P0_3 34
 '@S9S_MB_2U_LIB.S9S_MB_2U(SCH_1):PAGE258_I82@PURE_QUANTA.ISL99390FRZTR5935(CHIPS)':
 'PWM': CDS_PINID='PWM';
NET_NAME
'PVCCFA_EHV_FIVRA_CPU0_PWM4'
 '@S9S_MB_2U_LIB.S9S_MB_2U(SCH_1):PVCCFA_EHV_FIVRA_CPU0_PWM4':
 C_SIGNAL='@s9s_mb_2u_lib.s9s_mb_2u(sch_1):pvccfa_ehv_fivra_cpu0_pwm4';
NODE_NAME     PU14 4
 '@S9S_MB_2U_LIB.S9S_MB_2U(SCH_1):PAGE252_I63@PURE_QUANTA.RAA229126GNPHA0(CHIPS)':
 'PWM3': CDS_PINID='PWM3';
NODE_NAME     PU72_P0_4 34
 '@S9S_MB_2U_LIB.S9S_MB_2U(SCH_1):PAGE258_I10@PURE_QUANTA.ISL99390FRZTR5935(CHIPS)':
 'PWM': CDS_PINID='PWM';
NET_NAME
'PVCCFA_EHV_FIVRA_CPU0_VDD1'
 '@S9S_MB_2U_LIB.S9S_MB_2U(SCH_1):PVCCFA_EHV_FIVRA_CPU0_VDD1':
 C_SIGNAL='@s9s_mb_2u_lib.s9s_mb_2u(sch_1):pvccfa_ehv_fivra_cpu0_vdd1';
NODE_NAME     PR355 2
 '@S9S_MB_2U_LIB.S9S_MB_2U(SCH_1):PAGE257_I39@PURE_QUANTA.Q_RES(CHIPS)':
 'B': CDS_PINID='B';
NODE_NAME     PU69_P0_1 35
 '@S9S_MB_2U_LIB.S9S_MB_2U(SCH_1):PAGE257_I25@PURE_QUANTA.ISL99390FRZTR5935(CHIPS)':
 'EN': CDS_PINID='EN';
NODE_NAME     PU69_P0_1 3
 '@S9S_MB_2U_LIB.S9S_MB_2U(SCH_1):PAGE257_I25@PURE_QUANTA.ISL99390FRZTR5935(CHIPS)':
 'VCC': CDS_PINID='VCC';
NODE_NAME     PC600 1
 '@S9S_MB_2U_LIB.S9S_MB_2U(SCH_1):PAGE257_I37@PURE_QUANTA.Q_CAP(CHIPS)':
 'A': CDS_PINID='A';
NET_NAME
'PVCCFA_EHV_FIVRA_CPU0_VDD2'
 '@S9S_MB_2U_LIB.S9S_MB_2U(SCH_1):PVCCFA_EHV_FIVRA_CPU0_VDD2':
 C_SIGNAL='@s9s_mb_2u_lib.s9s_mb_2u(sch_1):pvccfa_ehv_fivra_cpu0_vdd2';
NODE_NAME     PU70_P0_2 35
 '@S9S_MB_2U_LIB.S9S_MB_2U(SCH_1):PAGE257_I16@PURE_QUANTA.ISL99390FRZTR5935(CHIPS)':
 'EN': CDS_PINID='EN';
NODE_NAME     PU70_P0_2 3
 '@S9S_MB_2U_LIB.S9S_MB_2U(SCH_1):PAGE257_I16@PURE_QUANTA.ISL99390FRZTR5935(CHIPS)':
 'VCC': CDS_PINID='VCC';
NODE_NAME     PC601 1
 '@S9S_MB_2U_LIB.S9S_MB_2U(SCH_1):PAGE257_I18@PURE_QUANTA.Q_CAP(CHIPS)':
 'A': CDS_PINID='A';
NODE_NAME     PR356 2
 '@S9S_MB_2U_LIB.S9S_MB_2U(SCH_1):PAGE257_I19@PURE_QUANTA.Q_RES(CHIPS)':
 'B': CDS_PINID='B';
NET_NAME
'PVCCFA_EHV_FIVRA_CPU0_VDD3'
 '@S9S_MB_2U_LIB.S9S_MB_2U(SCH_1):PVCCFA_EHV_FIVRA_CPU0_VDD3':
 C_SIGNAL='@s9s_mb_2u_lib.s9s_mb_2u(sch_1):pvccfa_ehv_fivra_cpu0_vdd3';
NODE_NAME     PC1171 1
 '@S9S_MB_2U_LIB.S9S_MB_2U(SCH_1):PAGE258_I23@PURE_QUANTA.Q_CAP(CHIPS)':
 'A': CDS_PINID='A';
NODE_NAME     PU71_P0_3 35
 '@S9S_MB_2U_LIB.S9S_MB_2U(SCH_1):PAGE258_I82@PURE_QUANTA.ISL99390FRZTR5935(CHIPS)':
 'EN': CDS_PINID='EN';
NODE_NAME     PU71_P0_3 3
 '@S9S_MB_2U_LIB.S9S_MB_2U(SCH_1):PAGE258_I82@PURE_QUANTA.ISL99390FRZTR5935(CHIPS)':
 'VCC': CDS_PINID='VCC';
NODE_NAME     PR1299 2
 '@S9S_MB_2U_LIB.S9S_MB_2U(SCH_1):PAGE258_I26@PURE_QUANTA.Q_RES(CHIPS)':
 'B': CDS_PINID='B';
NET_NAME
'PVCCFA_EHV_FIVRA_CPU0_VDD4'
 '@S9S_MB_2U_LIB.S9S_MB_2U(SCH_1):PVCCFA_EHV_FIVRA_CPU0_VDD4':
 C_SIGNAL='@s9s_mb_2u_lib.s9s_mb_2u(sch_1):pvccfa_ehv_fivra_cpu0_vdd4';
NODE_NAME     PR1300 2
 '@S9S_MB_2U_LIB.S9S_MB_2U(SCH_1):PAGE258_I11@PURE_QUANTA.Q_RES(CHIPS)':
 'B': CDS_PINID='B';
NODE_NAME     PU72_P0_4 35
 '@S9S_MB_2U_LIB.S9S_MB_2U(SCH_1):PAGE258_I10@PURE_QUANTA.ISL99390FRZTR5935(CHIPS)':
 'EN': CDS_PINID='EN';
NODE_NAME     PU72_P0_4 3
 '@S9S_MB_2U_LIB.S9S_MB_2U(SCH_1):PAGE258_I10@PURE_QUANTA.ISL99390FRZTR5935(CHIPS)':
 'VCC': CDS_PINID='VCC';
NODE_NAME     PC1172 1
 '@S9S_MB_2U_LIB.S9S_MB_2U(SCH_1):PAGE258_I13@PURE_QUANTA.Q_CAP(CHIPS)':
 'A': CDS_PINID='A';
NET_NAME
'PVCCFA_EHV_FIVRA_CPU0_VOS1'
 '@S9S_MB_2U_LIB.S9S_MB_2U(SCH_1):PVCCFA_EHV_FIVRA_CPU0_VOS1':
 C_SIGNAL='@s9s_mb_2u_lib.s9s_mb_2u(sch_1):pvccfa_ehv_fivra_cpu0_vos1';
NODE_NAME     PR1322 1
 '@S9S_MB_2U_LIB.S9S_MB_2U(SCH_1):PAGE257_I69@PURE_QUANTA.Q_RES(CHIPS)':
 'A': CDS_PINID='A';
NODE_NAME     PU69_P0_1 1
 '@S9S_MB_2U_LIB.S9S_MB_2U(SCH_1):PAGE257_I25@PURE_QUANTA.ISL99390FRZTR5935(CHIPS)':
 'VOS': CDS_PINID='VOS';
NET_NAME
'PVCCFA_EHV_FIVRA_CPU0_VOS2'
 '@S9S_MB_2U_LIB.S9S_MB_2U(SCH_1):PVCCFA_EHV_FIVRA_CPU0_VOS2':
 C_SIGNAL='@s9s_mb_2u_lib.s9s_mb_2u(sch_1):pvccfa_ehv_fivra_cpu0_vos2';
NODE_NAME     PR1323 1
 '@S9S_MB_2U_LIB.S9S_MB_2U(SCH_1):PAGE257_I50@PURE_QUANTA.Q_RES(CHIPS)':
 'A': CDS_PINID='A';
NODE_NAME     PU70_P0_2 1
 '@S9S_MB_2U_LIB.S9S_MB_2U(SCH_1):PAGE257_I16@PURE_QUANTA.ISL99390FRZTR5935(CHIPS)':
 'VOS': CDS_PINID='VOS';
NET_NAME
'PVCCFA_EHV_FIVRA_CPU0_VOS3'
 '@S9S_MB_2U_LIB.S9S_MB_2U(SCH_1):PVCCFA_EHV_FIVRA_CPU0_VOS3':
 C_SIGNAL='@s9s_mb_2u_lib.s9s_mb_2u(sch_1):pvccfa_ehv_fivra_cpu0_vos3';
NODE_NAME     PR1324 1
 '@S9S_MB_2U_LIB.S9S_MB_2U(SCH_1):PAGE258_I50@PURE_QUANTA.Q_RES(CHIPS)':
 'A': CDS_PINID='A';
NODE_NAME     PU71_P0_3 1
 '@S9S_MB_2U_LIB.S9S_MB_2U(SCH_1):PAGE258_I82@PURE_QUANTA.ISL99390FRZTR5935(CHIPS)':
 'VOS': CDS_PINID='VOS';
NET_NAME
'PVCCFA_EHV_FIVRA_CPU0_VOS4'
 '@S9S_MB_2U_LIB.S9S_MB_2U(SCH_1):PVCCFA_EHV_FIVRA_CPU0_VOS4':
 C_SIGNAL='@s9s_mb_2u_lib.s9s_mb_2u(sch_1):pvccfa_ehv_fivra_cpu0_vos4';
NODE_NAME     PR1325 1
 '@S9S_MB_2U_LIB.S9S_MB_2U(SCH_1):PAGE258_I38@PURE_QUANTA.Q_RES(CHIPS)':
 'A': CDS_PINID='A';
NODE_NAME     PU72_P0_4 1
 '@S9S_MB_2U_LIB.S9S_MB_2U(SCH_1):PAGE258_I10@PURE_QUANTA.ISL99390FRZTR5935(CHIPS)':
 'VOS': CDS_PINID='VOS';
NET_NAME
'PVCCFA_EHV_FIVRA_CPU1'
 '@S9S_MB_2U_LIB.S9S_MB_2U(SCH_1):PVCCFA_EHV_FIVRA_CPU1':
 C_SIGNAL='@s9s_mb_2u_lib.s9s_mb_2u(sch_1):pvccfa_ehv_fivra_cpu1',
 CDS_GLOBAL_NET='TRUE';
NODE_NAME     U1 AA11
 '@S9S_MB_2U_LIB.S9S_MB_2U(SCH_1):PAGE69_I1@PURE_QUANTA.SOCKET4677_AZIF0045P001C01CS(CHIPS)':
 'VCCFA_EHV_FIVRA0': CDS_PINID='VCCFA_EHV_FIVRA0';
NODE_NAME     U1 AA15
 '@S9S_MB_2U_LIB.S9S_MB_2U(SCH_1):PAGE69_I1@PURE_QUANTA.SOCKET4677_AZIF0045P001C01CS(CHIPS)':
 'VCCFA_EHV_FIVRA1': CDS_PINID='VCCFA_EHV_FIVRA1';
NODE_NAME     U1 AA7
 '@S9S_MB_2U_LIB.S9S_MB_2U(SCH_1):PAGE69_I1@PURE_QUANTA.SOCKET4677_AZIF0045P001C01CS(CHIPS)':
 'VCCFA_EHV_FIVRA2': CDS_PINID='VCCFA_EHV_FIVRA2';
NODE_NAME     U1 AD85
 '@S9S_MB_2U_LIB.S9S_MB_2U(SCH_1):PAGE69_I1@PURE_QUANTA.SOCKET4677_AZIF0045P001C01CS(CHIPS)':
 'VCCFA_EHV_FIVRA3': CDS_PINID='VCCFA_EHV_FIVRA3';
NODE_NAME     U1 AD89
 '@S9S_MB_2U_LIB.S9S_MB_2U(SCH_1):PAGE69_I1@PURE_QUANTA.SOCKET4677_AZIF0045P001C01CS(CHIPS)':
 'VCCFA_EHV_FIVRA4': CDS_PINID='VCCFA_EHV_FIVRA4';
NODE_NAME     U1 AE11
 '@S9S_MB_2U_LIB.S9S_MB_2U(SCH_1):PAGE69_I1@PURE_QUANTA.SOCKET4677_AZIF0045P001C01CS(CHIPS)':
 'VCCFA_EHV_FIVRA5': CDS_PINID='VCCFA_EHV_FIVRA5';
NODE_NAME     U1 AE15
 '@S9S_MB_2U_LIB.S9S_MB_2U(SCH_1):PAGE69_I1@PURE_QUANTA.SOCKET4677_AZIF0045P001C01CS(CHIPS)':
 'VCCFA_EHV_FIVRA6': CDS_PINID='VCCFA_EHV_FIVRA6';
NODE_NAME     U1 AE7
 '@S9S_MB_2U_LIB.S9S_MB_2U(SCH_1):PAGE69_I1@PURE_QUANTA.SOCKET4677_AZIF0045P001C01CS(CHIPS)':
 'VCCFA_EHV_FIVRA7': CDS_PINID='VCCFA_EHV_FIVRA7';
NODE_NAME     U1 AF77
 '@S9S_MB_2U_LIB.S9S_MB_2U(SCH_1):PAGE69_I1@PURE_QUANTA.SOCKET4677_AZIF0045P001C01CS(CHIPS)':
 'VCCFA_EHV_FIVRA8': CDS_PINID='VCCFA_EHV_FIVRA8';
NODE_NAME     U1 AG78
 '@S9S_MB_2U_LIB.S9S_MB_2U(SCH_1):PAGE69_I1@PURE_QUANTA.SOCKET4677_AZIF0045P001C01CS(CHIPS)':
 'VCCFA_EHV_FIVRA9': CDS_PINID='VCCFA_EHV_FIVRA9';
NODE_NAME     U1 AH85
 '@S9S_MB_2U_LIB.S9S_MB_2U(SCH_1):PAGE69_I1@PURE_QUANTA.SOCKET4677_AZIF0045P001C01CS(CHIPS)':
 'VCCFA_EHV_FIVRA10': CDS_PINID='VCCFA_EHV_FIVRA10';
NODE_NAME     U1 AH89
 '@S9S_MB_2U_LIB.S9S_MB_2U(SCH_1):PAGE69_I1@PURE_QUANTA.SOCKET4677_AZIF0045P001C01CS(CHIPS)':
 'VCCFA_EHV_FIVRA11': CDS_PINID='VCCFA_EHV_FIVRA11';
NODE_NAME     U1 AJ11
 '@S9S_MB_2U_LIB.S9S_MB_2U(SCH_1):PAGE69_I1@PURE_QUANTA.SOCKET4677_AZIF0045P001C01CS(CHIPS)':
 'VCCFA_EHV_FIVRA12': CDS_PINID='VCCFA_EHV_FIVRA12';
NODE_NAME     U1 AJ15
 '@S9S_MB_2U_LIB.S9S_MB_2U(SCH_1):PAGE69_I1@PURE_QUANTA.SOCKET4677_AZIF0045P001C01CS(CHIPS)':
 'VCCFA_EHV_FIVRA13': CDS_PINID='VCCFA_EHV_FIVRA13';
NODE_NAME     U1 AJ7
 '@S9S_MB_2U_LIB.S9S_MB_2U(SCH_1):PAGE69_I1@PURE_QUANTA.SOCKET4677_AZIF0045P001C01CS(CHIPS)':
 'VCCFA_EHV_FIVRA14': CDS_PINID='VCCFA_EHV_FIVRA14';
NODE_NAME     U1 AM79
 '@S9S_MB_2U_LIB.S9S_MB_2U(SCH_1):PAGE69_I1@PURE_QUANTA.SOCKET4677_AZIF0045P001C01CS(CHIPS)':
 'VCCFA_EHV_FIVRA15': CDS_PINID='VCCFA_EHV_FIVRA15';
NODE_NAME     U1 AM85
 '@S9S_MB_2U_LIB.S9S_MB_2U(SCH_1):PAGE69_I1@PURE_QUANTA.SOCKET4677_AZIF0045P001C01CS(CHIPS)':
 'VCCFA_EHV_FIVRA16': CDS_PINID='VCCFA_EHV_FIVRA16';
NODE_NAME     U1 AM89
 '@S9S_MB_2U_LIB.S9S_MB_2U(SCH_1):PAGE69_I1@PURE_QUANTA.SOCKET4677_AZIF0045P001C01CS(CHIPS)':
 'VCCFA_EHV_FIVRA17': CDS_PINID='VCCFA_EHV_FIVRA17';
NODE_NAME     U1 AN11
 '@S9S_MB_2U_LIB.S9S_MB_2U(SCH_1):PAGE69_I1@PURE_QUANTA.SOCKET4677_AZIF0045P001C01CS(CHIPS)':
 'VCCFA_EHV_FIVRA18': CDS_PINID='VCCFA_EHV_FIVRA18';
NODE_NAME     U1 AN15
 '@S9S_MB_2U_LIB.S9S_MB_2U(SCH_1):PAGE69_I1@PURE_QUANTA.SOCKET4677_AZIF0045P001C01CS(CHIPS)':
 'VCCFA_EHV_FIVRA19': CDS_PINID='VCCFA_EHV_FIVRA19';
NODE_NAME     U1 AN7
 '@S9S_MB_2U_LIB.S9S_MB_2U(SCH_1):PAGE69_I1@PURE_QUANTA.SOCKET4677_AZIF0045P001C01CS(CHIPS)':
 'VCCFA_EHV_FIVRA20': CDS_PINID='VCCFA_EHV_FIVRA20';
NODE_NAME     U1 AN80
 '@S9S_MB_2U_LIB.S9S_MB_2U(SCH_1):PAGE69_I1@PURE_QUANTA.SOCKET4677_AZIF0045P001C01CS(CHIPS)':
 'VCCFA_EHV_FIVRA21': CDS_PINID='VCCFA_EHV_FIVRA21';
NODE_NAME     U1 AT73
 '@S9S_MB_2U_LIB.S9S_MB_2U(SCH_1):PAGE69_I1@PURE_QUANTA.SOCKET4677_AZIF0045P001C01CS(CHIPS)':
 'VCCFA_EHV_FIVRA22': CDS_PINID='VCCFA_EHV_FIVRA22';
NODE_NAME     U1 AT89
 '@S9S_MB_2U_LIB.S9S_MB_2U(SCH_1):PAGE69_I1@PURE_QUANTA.SOCKET4677_AZIF0045P001C01CS(CHIPS)':
 'VCCFA_EHV_FIVRA23': CDS_PINID='VCCFA_EHV_FIVRA23';
NODE_NAME     U1 AU15
 '@S9S_MB_2U_LIB.S9S_MB_2U(SCH_1):PAGE69_I1@PURE_QUANTA.SOCKET4677_AZIF0045P001C01CS(CHIPS)':
 'VCCFA_EHV_FIVRA24': CDS_PINID='VCCFA_EHV_FIVRA24';
NODE_NAME     U1 AW76
 '@S9S_MB_2U_LIB.S9S_MB_2U(SCH_1):PAGE69_I1@PURE_QUANTA.SOCKET4677_AZIF0045P001C01CS(CHIPS)':
 'VCCFA_EHV_FIVRA25': CDS_PINID='VCCFA_EHV_FIVRA25';
NODE_NAME     U1 AY89
 '@S9S_MB_2U_LIB.S9S_MB_2U(SCH_1):PAGE69_I1@PURE_QUANTA.SOCKET4677_AZIF0045P001C01CS(CHIPS)':
 'VCCFA_EHV_FIVRA26': CDS_PINID='VCCFA_EHV_FIVRA26';
NODE_NAME     U1 BE72
 '@S9S_MB_2U_LIB.S9S_MB_2U(SCH_1):PAGE69_I1@PURE_QUANTA.SOCKET4677_AZIF0045P001C01CS(CHIPS)':
 'VCCFA_EHV_FIVRA27': CDS_PINID='VCCFA_EHV_FIVRA27';
NODE_NAME     U1 BF77
 '@S9S_MB_2U_LIB.S9S_MB_2U(SCH_1):PAGE69_I1@PURE_QUANTA.SOCKET4677_AZIF0045P001C01CS(CHIPS)':
 'VCCFA_EHV_FIVRA28': CDS_PINID='VCCFA_EHV_FIVRA28';
NODE_NAME     U1 BH79
 '@S9S_MB_2U_LIB.S9S_MB_2U(SCH_1):PAGE69_I1@PURE_QUANTA.SOCKET4677_AZIF0045P001C01CS(CHIPS)':
 'VCCFA_EHV_FIVRA29': CDS_PINID='VCCFA_EHV_FIVRA29';
NODE_NAME     U1 BJ72
 '@S9S_MB_2U_LIB.S9S_MB_2U(SCH_1):PAGE69_I1@PURE_QUANTA.SOCKET4677_AZIF0045P001C01CS(CHIPS)':
 'VCCFA_EHV_FIVRA30': CDS_PINID='VCCFA_EHV_FIVRA30';
NODE_NAME     U1 BJ78
 '@S9S_MB_2U_LIB.S9S_MB_2U(SCH_1):PAGE69_I1@PURE_QUANTA.SOCKET4677_AZIF0045P001C01CS(CHIPS)':
 'VCCFA_EHV_FIVRA31': CDS_PINID='VCCFA_EHV_FIVRA31';
NODE_NAME     U1 C84
 '@S9S_MB_2U_LIB.S9S_MB_2U(SCH_1):PAGE69_I1@PURE_QUANTA.SOCKET4677_AZIF0045P001C01CS(CHIPS)':
 'VCCFA_EHV_FIVRA32': CDS_PINID='VCCFA_EHV_FIVRA32';
NODE_NAME     U1 C88
 '@S9S_MB_2U_LIB.S9S_MB_2U(SCH_1):PAGE69_I1@PURE_QUANTA.SOCKET4677_AZIF0045P001C01CS(CHIPS)':
 'VCCFA_EHV_FIVRA33': CDS_PINID='VCCFA_EHV_FIVRA33';
NODE_NAME     U1 CE74
 '@S9S_MB_2U_LIB.S9S_MB_2U(SCH_1):PAGE69_I1@PURE_QUANTA.SOCKET4677_AZIF0045P001C01CS(CHIPS)':
 'VCCFA_EHV_FIVRA34': CDS_PINID='VCCFA_EHV_FIVRA34';
NODE_NAME     U1 CK73
 '@S9S_MB_2U_LIB.S9S_MB_2U(SCH_1):PAGE69_I1@PURE_QUANTA.SOCKET4677_AZIF0045P001C01CS(CHIPS)':
 'VCCFA_EHV_FIVRA35': CDS_PINID='VCCFA_EHV_FIVRA35';
NODE_NAME     U1 CK79
 '@S9S_MB_2U_LIB.S9S_MB_2U(SCH_1):PAGE69_I1@PURE_QUANTA.SOCKET4677_AZIF0045P001C01CS(CHIPS)':
 'VCCFA_EHV_FIVRA36': CDS_PINID='VCCFA_EHV_FIVRA36';
NODE_NAME     U1 CM73
 '@S9S_MB_2U_LIB.S9S_MB_2U(SCH_1):PAGE69_I1@PURE_QUANTA.SOCKET4677_AZIF0045P001C01CS(CHIPS)':
 'VCCFA_EHV_FIVRA37': CDS_PINID='VCCFA_EHV_FIVRA37';
NODE_NAME     U1 CN78
 '@S9S_MB_2U_LIB.S9S_MB_2U(SCH_1):PAGE69_I1@PURE_QUANTA.SOCKET4677_AZIF0045P001C01CS(CHIPS)':
 'VCCFA_EHV_FIVRA38': CDS_PINID='VCCFA_EHV_FIVRA38';
NODE_NAME     U1 CP73
 '@S9S_MB_2U_LIB.S9S_MB_2U(SCH_1):PAGE69_I1@PURE_QUANTA.SOCKET4677_AZIF0045P001C01CS(CHIPS)':
 'VCCFA_EHV_FIVRA39': CDS_PINID='VCCFA_EHV_FIVRA39';
NODE_NAME     U1 CT77
 '@S9S_MB_2U_LIB.S9S_MB_2U(SCH_1):PAGE69_I1@PURE_QUANTA.SOCKET4677_AZIF0045P001C01CS(CHIPS)':
 'VCCFA_EHV_FIVRA40': CDS_PINID='VCCFA_EHV_FIVRA40';
NODE_NAME     U1 CT85
 '@S9S_MB_2U_LIB.S9S_MB_2U(SCH_1):PAGE69_I1@PURE_QUANTA.SOCKET4677_AZIF0045P001C01CS(CHIPS)':
 'VCCFA_EHV_FIVRA41': CDS_PINID='VCCFA_EHV_FIVRA41';
NODE_NAME     U1 CY75
 '@S9S_MB_2U_LIB.S9S_MB_2U(SCH_1):PAGE69_I1@PURE_QUANTA.SOCKET4677_AZIF0045P001C01CS(CHIPS)':
 'VCCFA_EHV_FIVRA42': CDS_PINID='VCCFA_EHV_FIVRA42';
NODE_NAME     U1 CY79
 '@S9S_MB_2U_LIB.S9S_MB_2U(SCH_1):PAGE69_I1@PURE_QUANTA.SOCKET4677_AZIF0045P001C01CS(CHIPS)':
 'VCCFA_EHV_FIVRA43': CDS_PINID='VCCFA_EHV_FIVRA43';
NODE_NAME     U1 CY85
 '@S9S_MB_2U_LIB.S9S_MB_2U(SCH_1):PAGE69_I1@PURE_QUANTA.SOCKET4677_AZIF0045P001C01CS(CHIPS)':
 'VCCFA_EHV_FIVRA44': CDS_PINID='VCCFA_EHV_FIVRA44';
NODE_NAME     U1 CY89
 '@S9S_MB_2U_LIB.S9S_MB_2U(SCH_1):PAGE69_I1@PURE_QUANTA.SOCKET4677_AZIF0045P001C01CS(CHIPS)':
 'VCCFA_EHV_FIVRA45': CDS_PINID='VCCFA_EHV_FIVRA45';
NODE_NAME     U1 DD77
 '@S9S_MB_2U_LIB.S9S_MB_2U(SCH_1):PAGE69_I1@PURE_QUANTA.SOCKET4677_AZIF0045P001C01CS(CHIPS)':
 'VCCFA_EHV_FIVRA46': CDS_PINID='VCCFA_EHV_FIVRA46';
NODE_NAME     U1 DD83
 '@S9S_MB_2U_LIB.S9S_MB_2U(SCH_1):PAGE69_I1@PURE_QUANTA.SOCKET4677_AZIF0045P001C01CS(CHIPS)':
 'VCCFA_EHV_FIVRA47': CDS_PINID='VCCFA_EHV_FIVRA47';
NODE_NAME     U1 DD85
 '@S9S_MB_2U_LIB.S9S_MB_2U(SCH_1):PAGE69_I1@PURE_QUANTA.SOCKET4677_AZIF0045P001C01CS(CHIPS)':
 'VCCFA_EHV_FIVRA48': CDS_PINID='VCCFA_EHV_FIVRA48';
NODE_NAME     U1 DD89
 '@S9S_MB_2U_LIB.S9S_MB_2U(SCH_1):PAGE69_I1@PURE_QUANTA.SOCKET4677_AZIF0045P001C01CS(CHIPS)':
 'VCCFA_EHV_FIVRA49': CDS_PINID='VCCFA_EHV_FIVRA49';
NODE_NAME     U1 DH89
 '@S9S_MB_2U_LIB.S9S_MB_2U(SCH_1):PAGE69_I1@PURE_QUANTA.SOCKET4677_AZIF0045P001C01CS(CHIPS)':
 'VCCFA_EHV_FIVRA50': CDS_PINID='VCCFA_EHV_FIVRA50';
NODE_NAME     U1 DM83
 '@S9S_MB_2U_LIB.S9S_MB_2U(SCH_1):PAGE69_I1@PURE_QUANTA.SOCKET4677_AZIF0045P001C01CS(CHIPS)':
 'VCCFA_EHV_FIVRA51': CDS_PINID='VCCFA_EHV_FIVRA51';
NODE_NAME     U1 DM85
 '@S9S_MB_2U_LIB.S9S_MB_2U(SCH_1):PAGE69_I1@PURE_QUANTA.SOCKET4677_AZIF0045P001C01CS(CHIPS)':
 'VCCFA_EHV_FIVRA52': CDS_PINID='VCCFA_EHV_FIVRA52';
NODE_NAME     U1 DM89
 '@S9S_MB_2U_LIB.S9S_MB_2U(SCH_1):PAGE69_I1@PURE_QUANTA.SOCKET4677_AZIF0045P001C01CS(CHIPS)':
 'VCCFA_EHV_FIVRA53': CDS_PINID='VCCFA_EHV_FIVRA53';
NODE_NAME     U1 DN11
 '@S9S_MB_2U_LIB.S9S_MB_2U(SCH_1):PAGE69_I1@PURE_QUANTA.SOCKET4677_AZIF0045P001C01CS(CHIPS)':
 'VCCFA_EHV_FIVRA54': CDS_PINID='VCCFA_EHV_FIVRA54';
NODE_NAME     U1 DN15
 '@S9S_MB_2U_LIB.S9S_MB_2U(SCH_1):PAGE69_I1@PURE_QUANTA.SOCKET4677_AZIF0045P001C01CS(CHIPS)':
 'VCCFA_EHV_FIVRA55': CDS_PINID='VCCFA_EHV_FIVRA55';
NODE_NAME     U1 DN3
 '@S9S_MB_2U_LIB.S9S_MB_2U(SCH_1):PAGE69_I1@PURE_QUANTA.SOCKET4677_AZIF0045P001C01CS(CHIPS)':
 'VCCFA_EHV_FIVRA56': CDS_PINID='VCCFA_EHV_FIVRA56';
NODE_NAME     U1 DN7
 '@S9S_MB_2U_LIB.S9S_MB_2U(SCH_1):PAGE69_I1@PURE_QUANTA.SOCKET4677_AZIF0045P001C01CS(CHIPS)':
 'VCCFA_EHV_FIVRA57': CDS_PINID='VCCFA_EHV_FIVRA57';
NODE_NAME     U1 DT79
 '@S9S_MB_2U_LIB.S9S_MB_2U(SCH_1):PAGE69_I1@PURE_QUANTA.SOCKET4677_AZIF0045P001C01CS(CHIPS)':
 'VCCFA_EHV_FIVRA58': CDS_PINID='VCCFA_EHV_FIVRA58';
NODE_NAME     U1 DT85
 '@S9S_MB_2U_LIB.S9S_MB_2U(SCH_1):PAGE69_I1@PURE_QUANTA.SOCKET4677_AZIF0045P001C01CS(CHIPS)':
 'VCCFA_EHV_FIVRA59': CDS_PINID='VCCFA_EHV_FIVRA59';
NODE_NAME     U1 DT89
 '@S9S_MB_2U_LIB.S9S_MB_2U(SCH_1):PAGE69_I1@PURE_QUANTA.SOCKET4677_AZIF0045P001C01CS(CHIPS)':
 'VCCFA_EHV_FIVRA60': CDS_PINID='VCCFA_EHV_FIVRA60';
NODE_NAME     U1 DU11
 '@S9S_MB_2U_LIB.S9S_MB_2U(SCH_1):PAGE69_I1@PURE_QUANTA.SOCKET4677_AZIF0045P001C01CS(CHIPS)':
 'VCCFA_EHV_FIVRA61': CDS_PINID='VCCFA_EHV_FIVRA61';
NODE_NAME     U1 DU15
 '@S9S_MB_2U_LIB.S9S_MB_2U(SCH_1):PAGE69_I1@PURE_QUANTA.SOCKET4677_AZIF0045P001C01CS(CHIPS)':
 'VCCFA_EHV_FIVRA62': CDS_PINID='VCCFA_EHV_FIVRA62';
NODE_NAME     U1 DU3
 '@S9S_MB_2U_LIB.S9S_MB_2U(SCH_1):PAGE69_I1@PURE_QUANTA.SOCKET4677_AZIF0045P001C01CS(CHIPS)':
 'VCCFA_EHV_FIVRA63': CDS_PINID='VCCFA_EHV_FIVRA63';
NODE_NAME     U1 DU7
 '@S9S_MB_2U_LIB.S9S_MB_2U(SCH_1):PAGE69_I1@PURE_QUANTA.SOCKET4677_AZIF0045P001C01CS(CHIPS)':
 'VCCFA_EHV_FIVRA64': CDS_PINID='VCCFA_EHV_FIVRA64';
NODE_NAME     U1 DY85
 '@S9S_MB_2U_LIB.S9S_MB_2U(SCH_1):PAGE69_I1@PURE_QUANTA.SOCKET4677_AZIF0045P001C01CS(CHIPS)':
 'VCCFA_EHV_FIVRA65': CDS_PINID='VCCFA_EHV_FIVRA65';
NODE_NAME     U1 DY89
 '@S9S_MB_2U_LIB.S9S_MB_2U(SCH_1):PAGE69_I1@PURE_QUANTA.SOCKET4677_AZIF0045P001C01CS(CHIPS)':
 'VCCFA_EHV_FIVRA66': CDS_PINID='VCCFA_EHV_FIVRA66';
NODE_NAME     U1 EA11
 '@S9S_MB_2U_LIB.S9S_MB_2U(SCH_1):PAGE69_I1@PURE_QUANTA.SOCKET4677_AZIF0045P001C01CS(CHIPS)':
 'VCCFA_EHV_FIVRA67': CDS_PINID='VCCFA_EHV_FIVRA67';
NODE_NAME     U1 EA15
 '@S9S_MB_2U_LIB.S9S_MB_2U(SCH_1):PAGE69_I1@PURE_QUANTA.SOCKET4677_AZIF0045P001C01CS(CHIPS)':
 'VCCFA_EHV_FIVRA68': CDS_PINID='VCCFA_EHV_FIVRA68';
NODE_NAME     U1 EA3
 '@S9S_MB_2U_LIB.S9S_MB_2U(SCH_1):PAGE69_I1@PURE_QUANTA.SOCKET4677_AZIF0045P001C01CS(CHIPS)':
 'VCCFA_EHV_FIVRA69': CDS_PINID='VCCFA_EHV_FIVRA69';
NODE_NAME     U1 EA7
 '@S9S_MB_2U_LIB.S9S_MB_2U(SCH_1):PAGE69_I1@PURE_QUANTA.SOCKET4677_AZIF0045P001C01CS(CHIPS)':
 'VCCFA_EHV_FIVRA70': CDS_PINID='VCCFA_EHV_FIVRA70';
NODE_NAME     U1 EC78
 '@S9S_MB_2U_LIB.S9S_MB_2U(SCH_1):PAGE69_I1@PURE_QUANTA.SOCKET4677_AZIF0045P001C01CS(CHIPS)':
 'VCCFA_EHV_FIVRA71': CDS_PINID='VCCFA_EHV_FIVRA71';
NODE_NAME     U1 ED79
 '@S9S_MB_2U_LIB.S9S_MB_2U(SCH_1):PAGE69_I1@PURE_QUANTA.SOCKET4677_AZIF0045P001C01CS(CHIPS)':
 'VCCFA_EHV_FIVRA72': CDS_PINID='VCCFA_EHV_FIVRA72';
NODE_NAME     U1 ED85
 '@S9S_MB_2U_LIB.S9S_MB_2U(SCH_1):PAGE69_I1@PURE_QUANTA.SOCKET4677_AZIF0045P001C01CS(CHIPS)':
 'VCCFA_EHV_FIVRA73': CDS_PINID='VCCFA_EHV_FIVRA73';
NODE_NAME     U1 ED89
 '@S9S_MB_2U_LIB.S9S_MB_2U(SCH_1):PAGE69_I1@PURE_QUANTA.SOCKET4677_AZIF0045P001C01CS(CHIPS)':
 'VCCFA_EHV_FIVRA74': CDS_PINID='VCCFA_EHV_FIVRA74';
NODE_NAME     U1 EE11
 '@S9S_MB_2U_LIB.S9S_MB_2U(SCH_1):PAGE69_I1@PURE_QUANTA.SOCKET4677_AZIF0045P001C01CS(CHIPS)':
 'VCCFA_EHV_FIVRA75': CDS_PINID='VCCFA_EHV_FIVRA75';
NODE_NAME     U1 EE15
 '@S9S_MB_2U_LIB.S9S_MB_2U(SCH_1):PAGE69_I1@PURE_QUANTA.SOCKET4677_AZIF0045P001C01CS(CHIPS)':
 'VCCFA_EHV_FIVRA76': CDS_PINID='VCCFA_EHV_FIVRA76';
NODE_NAME     U1 EE7
 '@S9S_MB_2U_LIB.S9S_MB_2U(SCH_1):PAGE69_I1@PURE_QUANTA.SOCKET4677_AZIF0045P001C01CS(CHIPS)':
 'VCCFA_EHV_FIVRA77': CDS_PINID='VCCFA_EHV_FIVRA77';
NODE_NAME     U1 EE84
 '@S9S_MB_2U_LIB.S9S_MB_2U(SCH_1):PAGE69_I1@PURE_QUANTA.SOCKET4677_AZIF0045P001C01CS(CHIPS)':
 'VCCFA_EHV_FIVRA78': CDS_PINID='VCCFA_EHV_FIVRA78';
NODE_NAME     U1 EF79
 '@S9S_MB_2U_LIB.S9S_MB_2U(SCH_1):PAGE69_I1@PURE_QUANTA.SOCKET4677_AZIF0045P001C01CS(CHIPS)':
 'VCCFA_EHV_FIVRA79': CDS_PINID='VCCFA_EHV_FIVRA79';
NODE_NAME     U1 EG80
 '@S9S_MB_2U_LIB.S9S_MB_2U(SCH_1):PAGE69_I1@PURE_QUANTA.SOCKET4677_AZIF0045P001C01CS(CHIPS)':
 'VCCFA_EHV_FIVRA80': CDS_PINID='VCCFA_EHV_FIVRA80';
NODE_NAME     U1 EJ15
 '@S9S_MB_2U_LIB.S9S_MB_2U(SCH_1):PAGE69_I1@PURE_QUANTA.SOCKET4677_AZIF0045P001C01CS(CHIPS)':
 'VCCFA_EHV_FIVRA81': CDS_PINID='VCCFA_EHV_FIVRA81';
NODE_NAME     U1 EJ84
 '@S9S_MB_2U_LIB.S9S_MB_2U(SCH_1):PAGE69_I1@PURE_QUANTA.SOCKET4677_AZIF0045P001C01CS(CHIPS)':
 'VCCFA_EHV_FIVRA82': CDS_PINID='VCCFA_EHV_FIVRA82';
NODE_NAME     U1 EN84
 '@S9S_MB_2U_LIB.S9S_MB_2U(SCH_1):PAGE69_I1@PURE_QUANTA.SOCKET4677_AZIF0045P001C01CS(CHIPS)':
 'VCCFA_EHV_FIVRA83': CDS_PINID='VCCFA_EHV_FIVRA83';
NODE_NAME     U1 H89
 '@S9S_MB_2U_LIB.S9S_MB_2U(SCH_1):PAGE69_I1@PURE_QUANTA.SOCKET4677_AZIF0045P001C01CS(CHIPS)':
 'VCCFA_EHV_FIVRA84': CDS_PINID='VCCFA_EHV_FIVRA84';
NODE_NAME     U1 J11
 '@S9S_MB_2U_LIB.S9S_MB_2U(SCH_1):PAGE69_I1@PURE_QUANTA.SOCKET4677_AZIF0045P001C01CS(CHIPS)':
 'VCCFA_EHV_FIVRA85': CDS_PINID='VCCFA_EHV_FIVRA85';
NODE_NAME     U1 J7
 '@S9S_MB_2U_LIB.S9S_MB_2U(SCH_1):PAGE69_I1@PURE_QUANTA.SOCKET4677_AZIF0045P001C01CS(CHIPS)':
 'VCCFA_EHV_FIVRA86': CDS_PINID='VCCFA_EHV_FIVRA86';
NODE_NAME     U1 J80
 '@S9S_MB_2U_LIB.S9S_MB_2U(SCH_1):PAGE69_I1@PURE_QUANTA.SOCKET4677_AZIF0045P001C01CS(CHIPS)':
 'VCCFA_EHV_FIVRA87': CDS_PINID='VCCFA_EHV_FIVRA87';
NODE_NAME     U1 K87
 '@S9S_MB_2U_LIB.S9S_MB_2U(SCH_1):PAGE69_I1@PURE_QUANTA.SOCKET4677_AZIF0045P001C01CS(CHIPS)':
 'VCCFA_EHV_FIVRA88': CDS_PINID='VCCFA_EHV_FIVRA88';
NODE_NAME     U1 L84
 '@S9S_MB_2U_LIB.S9S_MB_2U(SCH_1):PAGE69_I1@PURE_QUANTA.SOCKET4677_AZIF0045P001C01CS(CHIPS)':
 'VCCFA_EHV_FIVRA89': CDS_PINID='VCCFA_EHV_FIVRA89';
NODE_NAME     U1 M85
 '@S9S_MB_2U_LIB.S9S_MB_2U(SCH_1):PAGE69_I1@PURE_QUANTA.SOCKET4677_AZIF0045P001C01CS(CHIPS)':
 'VCCFA_EHV_FIVRA90': CDS_PINID='VCCFA_EHV_FIVRA90';
NODE_NAME     U1 M89
 '@S9S_MB_2U_LIB.S9S_MB_2U(SCH_1):PAGE69_I1@PURE_QUANTA.SOCKET4677_AZIF0045P001C01CS(CHIPS)':
 'VCCFA_EHV_FIVRA91': CDS_PINID='VCCFA_EHV_FIVRA91';
NODE_NAME     U1 N11
 '@S9S_MB_2U_LIB.S9S_MB_2U(SCH_1):PAGE69_I1@PURE_QUANTA.SOCKET4677_AZIF0045P001C01CS(CHIPS)':
 'VCCFA_EHV_FIVRA92': CDS_PINID='VCCFA_EHV_FIVRA92';
NODE_NAME     U1 N7
 '@S9S_MB_2U_LIB.S9S_MB_2U(SCH_1):PAGE69_I1@PURE_QUANTA.SOCKET4677_AZIF0045P001C01CS(CHIPS)':
 'VCCFA_EHV_FIVRA93': CDS_PINID='VCCFA_EHV_FIVRA93';
NODE_NAME     U1 P79
 '@S9S_MB_2U_LIB.S9S_MB_2U(SCH_1):PAGE69_I1@PURE_QUANTA.SOCKET4677_AZIF0045P001C01CS(CHIPS)':
 'VCCFA_EHV_FIVRA94': CDS_PINID='VCCFA_EHV_FIVRA94';
NODE_NAME     U1 R80
 '@S9S_MB_2U_LIB.S9S_MB_2U(SCH_1):PAGE69_I1@PURE_QUANTA.SOCKET4677_AZIF0045P001C01CS(CHIPS)':
 'VCCFA_EHV_FIVRA95': CDS_PINID='VCCFA_EHV_FIVRA95';
NODE_NAME     U1 T85
 '@S9S_MB_2U_LIB.S9S_MB_2U(SCH_1):PAGE69_I1@PURE_QUANTA.SOCKET4677_AZIF0045P001C01CS(CHIPS)':
 'VCCFA_EHV_FIVRA96': CDS_PINID='VCCFA_EHV_FIVRA96';
NODE_NAME     U1 T89
 '@S9S_MB_2U_LIB.S9S_MB_2U(SCH_1):PAGE69_I1@PURE_QUANTA.SOCKET4677_AZIF0045P001C01CS(CHIPS)':
 'VCCFA_EHV_FIVRA97': CDS_PINID='VCCFA_EHV_FIVRA97';
NODE_NAME     U1 U11
 '@S9S_MB_2U_LIB.S9S_MB_2U(SCH_1):PAGE69_I1@PURE_QUANTA.SOCKET4677_AZIF0045P001C01CS(CHIPS)':
 'VCCFA_EHV_FIVRA98': CDS_PINID='VCCFA_EHV_FIVRA98';
NODE_NAME     U1 U15
 '@S9S_MB_2U_LIB.S9S_MB_2U(SCH_1):PAGE69_I1@PURE_QUANTA.SOCKET4677_AZIF0045P001C01CS(CHIPS)':
 'VCCFA_EHV_FIVRA99': CDS_PINID='VCCFA_EHV_FIVRA99';
NODE_NAME     U1 U7
 '@S9S_MB_2U_LIB.S9S_MB_2U(SCH_1):PAGE69_I1@PURE_QUANTA.SOCKET4677_AZIF0045P001C01CS(CHIPS)':
 'VCCFA_EHV_FIVRA100': CDS_PINID='VCCFA_EHV_FIVRA100';
NODE_NAME     U1 W80
 '@S9S_MB_2U_LIB.S9S_MB_2U(SCH_1):PAGE69_I1@PURE_QUANTA.SOCKET4677_AZIF0045P001C01CS(CHIPS)':
 'VCCFA_EHV_FIVRA101': CDS_PINID='VCCFA_EHV_FIVRA101';
NODE_NAME     U1 Y79
 '@S9S_MB_2U_LIB.S9S_MB_2U(SCH_1):PAGE69_I1@PURE_QUANTA.SOCKET4677_AZIF0045P001C01CS(CHIPS)':
 'VCCFA_EHV_FIVRA102': CDS_PINID='VCCFA_EHV_FIVRA102';
NODE_NAME     U1 Y85
 '@S9S_MB_2U_LIB.S9S_MB_2U(SCH_1):PAGE69_I1@PURE_QUANTA.SOCKET4677_AZIF0045P001C01CS(CHIPS)':
 'VCCFA_EHV_FIVRA103': CDS_PINID='VCCFA_EHV_FIVRA103';
NODE_NAME     U1 Y89
 '@S9S_MB_2U_LIB.S9S_MB_2U(SCH_1):PAGE69_I1@PURE_QUANTA.SOCKET4677_AZIF0045P001C01CS(CHIPS)':
 'VCCFA_EHV_FIVRA104': CDS_PINID='VCCFA_EHV_FIVRA104';
NODE_NAME     C424 1
 '@S9S_MB_2U_LIB.S9S_MB_2U(SCH_1):PAGE77_I1@PURE_QUANTA.Q_CAP(CHIPS)':
 'A': CDS_PINID='A';
NODE_NAME     C428 1
 '@S9S_MB_2U_LIB.S9S_MB_2U(SCH_1):PAGE77_I4@PURE_QUANTA.Q_CAP(CHIPS)':
 'A': CDS_PINID='A';
NODE_NAME     C430 1
 '@S9S_MB_2U_LIB.S9S_MB_2U(SCH_1):PAGE77_I5@PURE_QUANTA.Q_CAP(CHIPS)':
 'A': CDS_PINID='A';
NODE_NAME     C431 1
 '@S9S_MB_2U_LIB.S9S_MB_2U(SCH_1):PAGE77_I37@PURE_QUANTA.Q_CAP(CHIPS)':
 'A': CDS_PINID='A';
NODE_NAME     C433 1
 '@S9S_MB_2U_LIB.S9S_MB_2U(SCH_1):PAGE77_I38@PURE_QUANTA.Q_CAP(CHIPS)':
 'A': CDS_PINID='A';
NODE_NAME     C435 1
 '@S9S_MB_2U_LIB.S9S_MB_2U(SCH_1):PAGE77_I39@PURE_QUANTA.Q_CAP(CHIPS)':
 'A': CDS_PINID='A';
NODE_NAME     C439 1
 '@S9S_MB_2U_LIB.S9S_MB_2U(SCH_1):PAGE77_I53@PURE_QUANTA.Q_CAP(CHIPS)':
 'A': CDS_PINID='A';
NODE_NAME     C441 1
 '@S9S_MB_2U_LIB.S9S_MB_2U(SCH_1):PAGE77_I55@PURE_QUANTA.Q_CAP(CHIPS)':
 'A': CDS_PINID='A';
NODE_NAME     C442 1
 '@S9S_MB_2U_LIB.S9S_MB_2U(SCH_1):PAGE77_I57@PURE_QUANTA.Q_CAP(CHIPS)':
 'A': CDS_PINID='A';
NODE_NAME     C453 1
 '@S9S_MB_2U_LIB.S9S_MB_2U(SCH_1):PAGE78_I3@PURE_QUANTA.Q_CAP(CHIPS)':
 'A': CDS_PINID='A';
NODE_NAME     C461 1
 '@S9S_MB_2U_LIB.S9S_MB_2U(SCH_1):PAGE78_I5@PURE_QUANTA.Q_CAP(CHIPS)':
 'A': CDS_PINID='A';
NODE_NAME     C465 1
 '@S9S_MB_2U_LIB.S9S_MB_2U(SCH_1):PAGE78_I7@PURE_QUANTA.Q_CAP(CHIPS)':
 'A': CDS_PINID='A';
NODE_NAME     C450 1
 '@S9S_MB_2U_LIB.S9S_MB_2U(SCH_1):PAGE79_I1@PURE_QUANTA.Q_CAP(CHIPS)':
 'A': CDS_PINID='A';
NODE_NAME     C454 1
 '@S9S_MB_2U_LIB.S9S_MB_2U(SCH_1):PAGE79_I3@PURE_QUANTA.Q_CAP(CHIPS)':
 'A': CDS_PINID='A';
NODE_NAME     C458 1
 '@S9S_MB_2U_LIB.S9S_MB_2U(SCH_1):PAGE79_I4@PURE_QUANTA.Q_CAP(CHIPS)':
 'A': CDS_PINID='A';
NODE_NAME     C462 1
 '@S9S_MB_2U_LIB.S9S_MB_2U(SCH_1):PAGE79_I5@PURE_QUANTA.Q_CAP(CHIPS)':
 'A': CDS_PINID='A';
NODE_NAME     C466 1
 '@S9S_MB_2U_LIB.S9S_MB_2U(SCH_1):PAGE79_I7@PURE_QUANTA.Q_CAP(CHIPS)':
 'A': CDS_PINID='A';
NODE_NAME     C470 1
 '@S9S_MB_2U_LIB.S9S_MB_2U(SCH_1):PAGE79_I8@PURE_QUANTA.Q_CAP(CHIPS)':
 'A': CDS_PINID='A';
NODE_NAME     C473 1
 '@S9S_MB_2U_LIB.S9S_MB_2U(SCH_1):PAGE79_I9@PURE_QUANTA.Q_CAP(CHIPS)':
 'A': CDS_PINID='A';
NODE_NAME     PL113 2
 '@S9S_MB_2U_LIB.S9S_MB_2U(SCH_1):PAGE276_I44@PURE_QUANTA.Q_INDUCTOR(CHIPS)':
 '2': CDS_PINID='\2\';
NODE_NAME     PC1201 1
 '@S9S_MB_2U_LIB.S9S_MB_2U(SCH_1):PAGE276_I55@PURE_QUANTA.Q_CAPP(CHIPS)':
 'A': CDS_PINID='A';
NODE_NAME     PC1204_P1_3 1
 '@S9S_MB_2U_LIB.S9S_MB_2U(SCH_1):PAGE276_I56@PURE_QUANTA.Q_CAP(CHIPS)':
 'A': CDS_PINID='A';
NODE_NAME     PC1203 1
 '@S9S_MB_2U_LIB.S9S_MB_2U(SCH_1):PAGE276_I67@PURE_QUANTA.Q_CAPP(CHIPS)':
 'A': CDS_PINID='A';
NODE_NAME     PC1208_P1_3 1
 '@S9S_MB_2U_LIB.S9S_MB_2U(SCH_1):PAGE276_I68@PURE_QUANTA.Q_CAP(CHIPS)':
 'A': CDS_PINID='A';
NODE_NAME     PL19 2
 '@S9S_MB_2U_LIB.S9S_MB_2U(SCH_1):PAGE275_I44@PURE_QUANTA.Q_INDUCTOR(CHIPS)':
 '2': CDS_PINID='\2\';
NODE_NAME     PR1331 2
 '@S9S_MB_2U_LIB.S9S_MB_2U(SCH_1):PAGE275_I53@PURE_QUANTA.Q_RES(CHIPS)':
 'B': CDS_PINID='B';
NODE_NAME     PL18 2
 '@S9S_MB_2U_LIB.S9S_MB_2U(SCH_1):PAGE275_I55@PURE_QUANTA.Q_INDUCTOR(CHIPS)':
 '2': CDS_PINID='\2\';
NODE_NAME     PC621_P1_1 1
 '@S9S_MB_2U_LIB.S9S_MB_2U(SCH_1):PAGE275_I60@PURE_QUANTA.Q_CAP(CHIPS)':
 'A': CDS_PINID='A';
NODE_NAME     PC413_P1_2 1
 '@S9S_MB_2U_LIB.S9S_MB_2U(SCH_1):PAGE275_I63@PURE_QUANTA.Q_CAP(CHIPS)':
 'A': CDS_PINID='A';
NODE_NAME     PC416 1
 '@S9S_MB_2U_LIB.S9S_MB_2U(SCH_1):PAGE275_I68@PURE_QUANTA.Q_CAPP(CHIPS)':
 'A': CDS_PINID='A';
NODE_NAME     PL12 2
 '@S9S_MB_2U_LIB.S9S_MB_2U(SCH_1):PAGE276_I57@PURE_QUANTA.Q_INDUCTOR(CHIPS)':
 '2': CDS_PINID='\2\';
NODE_NAME     C426 1
 '@S9S_MB_2U_LIB.S9S_MB_2U(SCH_1):PAGE77_I2@PURE_QUANTA.Q_CAP(CHIPS)':
 'A': CDS_PINID='A';
NODE_NAME     C437 1
 '@S9S_MB_2U_LIB.S9S_MB_2U(SCH_1):PAGE77_I40@PURE_QUANTA.Q_CAP(CHIPS)':
 'A': CDS_PINID='A';
NODE_NAME     C449 1
 '@S9S_MB_2U_LIB.S9S_MB_2U(SCH_1):PAGE78_I1@PURE_QUANTA.Q_CAP(CHIPS)':
 'A': CDS_PINID='A';
NODE_NAME     C457 1
 '@S9S_MB_2U_LIB.S9S_MB_2U(SCH_1):PAGE78_I4@PURE_QUANTA.Q_CAP(CHIPS)':
 'A': CDS_PINID='A';
NODE_NAME     C476 1
 '@S9S_MB_2U_LIB.S9S_MB_2U(SCH_1):PAGE79_I37@PURE_QUANTA.Q_CAP(CHIPS)':
 'A': CDS_PINID='A';
NODE_NAME     C477 1
 '@S9S_MB_2U_LIB.S9S_MB_2U(SCH_1):PAGE79_I38@PURE_QUANTA.Q_CAP(CHIPS)':
 'A': CDS_PINID='A';
NODE_NAME     C479 1
 '@S9S_MB_2U_LIB.S9S_MB_2U(SCH_1):PAGE79_I39@PURE_QUANTA.Q_CAP(CHIPS)':
 'A': CDS_PINID='A';
NODE_NAME     C482 1
 '@S9S_MB_2U_LIB.S9S_MB_2U(SCH_1):PAGE79_I41@PURE_QUANTA.Q_CAP(CHIPS)':
 'A': CDS_PINID='A';
NODE_NAME     C485 1
 '@S9S_MB_2U_LIB.S9S_MB_2U(SCH_1):PAGE79_I42@PURE_QUANTA.Q_CAP(CHIPS)':
 'A': CDS_PINID='A';
NODE_NAME     PR1332 2
 '@S9S_MB_2U_LIB.S9S_MB_2U(SCH_1):PAGE275_I41@PURE_QUANTA.Q_RES(CHIPS)':
 'B': CDS_PINID='B';
NODE_NAME     PC411_P1_2 1
 '@S9S_MB_2U_LIB.S9S_MB_2U(SCH_1):PAGE275_I62@PURE_QUANTA.Q_CAP(CHIPS)':
 'A': CDS_PINID='A';
NODE_NAME     PC1206_P1_3 1
 '@S9S_MB_2U_LIB.S9S_MB_2U(SCH_1):PAGE276_I66@PURE_QUANTA.Q_CAP(CHIPS)':
 'A': CDS_PINID='A';
NODE_NAME     PC408_P1_2 1
 '@S9S_MB_2U_LIB.S9S_MB_2U(SCH_1):PAGE275_I61@PURE_QUANTA.Q_CAP(CHIPS)':
 'A': CDS_PINID='A';
NODE_NAME     PR4241 1
 '@S9S_MB_2U_LIB.S9S_MB_2U(SCH_1):PAGE275_I64@PURE_QUANTA.Q_RES(CHIPS)':
 'A': CDS_PINID='A';
NODE_NAME     PC418 1
 '@S9S_MB_2U_LIB.S9S_MB_2U(SCH_1):PAGE275_I70@PURE_QUANTA.Q_CAPP(CHIPS)':
 'A': CDS_PINID='A';
NODE_NAME     PC2172 1
 '@S9S_MB_2U_LIB.S9S_MB_2U(SCH_1):PAGE275_I72@PURE_QUANTA.Q_CAPP(CHIPS)':
 'A': CDS_PINID='A';
NODE_NAME     PC1209_P1_4 1
 '@S9S_MB_2U_LIB.S9S_MB_2U(SCH_1):PAGE276_I50@PURE_QUANTA.Q_CAP(CHIPS)':
 'A': CDS_PINID='A';
NODE_NAME     PR1333 2
 '@S9S_MB_2U_LIB.S9S_MB_2U(SCH_1):PAGE276_I54@PURE_QUANTA.Q_RES(CHIPS)':
 'B': CDS_PINID='B';
NODE_NAME     PC1204 1
 '@S9S_MB_2U_LIB.S9S_MB_2U(SCH_1):PAGE276_I70@PURE_QUANTA.Q_CAPP(CHIPS)':
 'A': CDS_PINID='A';
NODE_NAME     PC1205 1
 '@S9S_MB_2U_LIB.S9S_MB_2U(SCH_1):PAGE276_I72@PURE_QUANTA.Q_CAPP(CHIPS)':
 'A': CDS_PINID='A';
NODE_NAME     PC414 1
 '@S9S_MB_2U_LIB.S9S_MB_2U(SCH_1):PAGE275_I66@PURE_QUANTA.Q_CAPP(CHIPS)':
 'A': CDS_PINID='A';
NODE_NAME     PC415 1
 '@S9S_MB_2U_LIB.S9S_MB_2U(SCH_1):PAGE275_I67@PURE_QUANTA.Q_CAPP(CHIPS)':
 'A': CDS_PINID='A';
NODE_NAME     PC410_P1_1 1
 '@S9S_MB_2U_LIB.S9S_MB_2U(SCH_1):PAGE275_I74@PURE_QUANTA.Q_CAP(CHIPS)':
 'A': CDS_PINID='A';
NODE_NAME     PC412_P1_1 1
 '@S9S_MB_2U_LIB.S9S_MB_2U(SCH_1):PAGE275_I75@PURE_QUANTA.Q_CAP(CHIPS)':
 'A': CDS_PINID='A';
NODE_NAME     PR1334 2
 '@S9S_MB_2U_LIB.S9S_MB_2U(SCH_1):PAGE276_I43@PURE_QUANTA.Q_RES(CHIPS)':
 'B': CDS_PINID='B';
NODE_NAME     PC1203_P1_4 1
 '@S9S_MB_2U_LIB.S9S_MB_2U(SCH_1):PAGE276_I47@PURE_QUANTA.Q_CAP(CHIPS)':
 'A': CDS_PINID='A';
NODE_NAME     PC1207_P1_4 1
 '@S9S_MB_2U_LIB.S9S_MB_2U(SCH_1):PAGE276_I48@PURE_QUANTA.Q_CAP(CHIPS)':
 'A': CDS_PINID='A';
NODE_NAME     PC2171 1
 '@S9S_MB_2U_LIB.S9S_MB_2U(SCH_1):PAGE276_I73@PURE_QUANTA.Q_CAPP(CHIPS)':
 'A': CDS_PINID='A';
NODE_NAME     PR561 2
 '@S9S_MB_2U_LIB.S9S_MB_2U(SCH_1):PAGE270_I23@PURE_QUANTA.Q_RES(CHIPS)':
 'B': CDS_PINID='B';
NET_NAME
'PVCCFA_EHV_FIVRA_CPU1_BTSEN'
 '@S9S_MB_2U_LIB.S9S_MB_2U(SCH_1):PVCCFA_EHV_FIVRA_CPU1_BTSEN':
 C_SIGNAL='@s9s_mb_2u_lib.s9s_mb_2u(sch_1):pvccfa_ehv_fivra_cpu1_btsen';
NODE_NAME     PU76_P1_2 36
 '@S9S_MB_2U_LIB.S9S_MB_2U(SCH_1):PAGE275_I9@PURE_QUANTA.ISL99390FRZTR5935(CHIPS)':
 'TOUT_FLT': CDS_PINID='TOUT_FLT';
NODE_NAME     PU78_P1_4 36
 '@S9S_MB_2U_LIB.S9S_MB_2U(SCH_1):PAGE276_I15@PURE_QUANTA.ISL99390FRZTR5935(CHIPS)':
 'TOUT_FLT': CDS_PINID='TOUT_FLT';
NODE_NAME     PU77_P1_3 36
 '@S9S_MB_2U_LIB.S9S_MB_2U(SCH_1):PAGE276_I24@PURE_QUANTA.ISL99390FRZTR5935(CHIPS)':
 'TOUT_FLT': CDS_PINID='TOUT_FLT';
NODE_NAME     PU75_P1_1 36
 '@S9S_MB_2U_LIB.S9S_MB_2U(SCH_1):PAGE275_I89@PURE_QUANTA.ISL99390FRZTR5935(CHIPS)':
 'TOUT_FLT': CDS_PINID='TOUT_FLT';
NODE_NAME     PU29 44
 '@S9S_MB_2U_LIB.S9S_MB_2U(SCH_1):PAGE270_I33@PURE_QUANTA.RAA229126GNPHA0(CHIPS)':
 'TEMP1||ISYS': CDS_PINID='\temp1||isys\';
NODE_NAME     PC101 1
 '@S9S_MB_2U_LIB.S9S_MB_2U(SCH_1):PAGE270_I92@PURE_QUANTA.Q_CAP(CHIPS)':
 'A': CDS_PINID='A';
NODE_NAME     PR453 1
 '@S9S_MB_2U_LIB.S9S_MB_2U(SCH_1):PAGE270_I94@PURE_QUANTA.Q_RES(CHIPS)':
 'A': CDS_PINID='A';
NET_NAME
'PVCCFA_EHV_FIVRA_CPU1_EN_R'
 '@S9S_MB_2U_LIB.S9S_MB_2U(SCH_1):PVCCFA_EHV_FIVRA_CPU1_EN_R':
 C_SIGNAL='@s9s_mb_2u_lib.s9s_mb_2u(sch_1):pvccfa_ehv_fivra_cpu1_en_r';
NODE_NAME     R2550 2
 '@S9S_MB_2U_LIB.S9S_MB_2U(SCH_1):PAGE270_I19@PURE_QUANTA.Q_RES(CHIPS)':
 'B': CDS_PINID='B';
NODE_NAME     C2446 1
 '@S9S_MB_2U_LIB.S9S_MB_2U(SCH_1):PAGE270_I34@PURE_QUANTA.Q_CAP(CHIPS)':
 'A': CDS_PINID='A';
NODE_NAME     PU29 24
 '@S9S_MB_2U_LIB.S9S_MB_2U(SCH_1):PAGE270_I33@PURE_QUANTA.RAA229126GNPHA0(CHIPS)':
 'EN1': CDS_PINID='EN1';
NET_NAME
'PVCCFA_EHV_FIVRA_CPU1_IMON1'
 '@S9S_MB_2U_LIB.S9S_MB_2U(SCH_1):PVCCFA_EHV_FIVRA_CPU1_IMON1':
 C_SIGNAL='@s9s_mb_2u_lib.s9s_mb_2u(sch_1):pvccfa_ehv_fivra_cpu1_imon1';
NODE_NAME     PU75_P1_1 38
 '@S9S_MB_2U_LIB.S9S_MB_2U(SCH_1):PAGE275_I89@PURE_QUANTA.ISL99390FRZTR5935(CHIPS)':
 'IOUT': CDS_PINID='IOUT';
NODE_NAME     PU29 38
 '@S9S_MB_2U_LIB.S9S_MB_2U(SCH_1):PAGE270_I33@PURE_QUANTA.RAA229126GNPHA0(CHIPS)':
 'CS0': CDS_PINID='CS0';
NET_NAME
'PVCCFA_EHV_FIVRA_CPU1_IMON2'
 '@S9S_MB_2U_LIB.S9S_MB_2U(SCH_1):PVCCFA_EHV_FIVRA_CPU1_IMON2':
 C_SIGNAL='@s9s_mb_2u_lib.s9s_mb_2u(sch_1):pvccfa_ehv_fivra_cpu1_imon2';
NODE_NAME     PU76_P1_2 38
 '@S9S_MB_2U_LIB.S9S_MB_2U(SCH_1):PAGE275_I9@PURE_QUANTA.ISL99390FRZTR5935(CHIPS)':
 'IOUT': CDS_PINID='IOUT';
NODE_NAME     PU29 37
 '@S9S_MB_2U_LIB.S9S_MB_2U(SCH_1):PAGE270_I33@PURE_QUANTA.RAA229126GNPHA0(CHIPS)':
 'CS1': CDS_PINID='CS1';
NET_NAME
'PVCCFA_EHV_FIVRA_CPU1_IMON3'
 '@S9S_MB_2U_LIB.S9S_MB_2U(SCH_1):PVCCFA_EHV_FIVRA_CPU1_IMON3':
 C_SIGNAL='@s9s_mb_2u_lib.s9s_mb_2u(sch_1):pvccfa_ehv_fivra_cpu1_imon3';
NODE_NAME     PU77_P1_3 38
 '@S9S_MB_2U_LIB.S9S_MB_2U(SCH_1):PAGE276_I24@PURE_QUANTA.ISL99390FRZTR5935(CHIPS)':
 'IOUT': CDS_PINID='IOUT';
NODE_NAME     PU29 36
 '@S9S_MB_2U_LIB.S9S_MB_2U(SCH_1):PAGE270_I33@PURE_QUANTA.RAA229126GNPHA0(CHIPS)':
 'CS2': CDS_PINID='CS2';
NODE_NAME     PR4239 1
 '@S9S_MB_2U_LIB.S9S_MB_2U(SCH_1):PAGE270_I80@PURE_QUANTA.Q_RES(CHIPS)':
 'A': CDS_PINID='A';
NET_NAME
'PVCCFA_EHV_FIVRA_CPU1_IMON4'
 '@S9S_MB_2U_LIB.S9S_MB_2U(SCH_1):PVCCFA_EHV_FIVRA_CPU1_IMON4':
 C_SIGNAL='@s9s_mb_2u_lib.s9s_mb_2u(sch_1):pvccfa_ehv_fivra_cpu1_imon4';
NODE_NAME     PU78_P1_4 38
 '@S9S_MB_2U_LIB.S9S_MB_2U(SCH_1):PAGE276_I15@PURE_QUANTA.ISL99390FRZTR5935(CHIPS)':
 'IOUT': CDS_PINID='IOUT';
NODE_NAME     PR4238 1
 '@S9S_MB_2U_LIB.S9S_MB_2U(SCH_1):PAGE270_I81@PURE_QUANTA.Q_RES(CHIPS)':
 'A': CDS_PINID='A';
NODE_NAME     PU29 35
 '@S9S_MB_2U_LIB.S9S_MB_2U(SCH_1):PAGE270_I33@PURE_QUANTA.RAA229126GNPHA0(CHIPS)':
 'CS3': CDS_PINID='CS3';
NET_NAME
'PVCCFA_EHV_FIVRA_CPU1_LSET1'
 '@S9S_MB_2U_LIB.S9S_MB_2U(SCH_1):PVCCFA_EHV_FIVRA_CPU1_LSET1':
 C_SIGNAL='@s9s_mb_2u_lib.s9s_mb_2u(sch_1):pvccfa_ehv_fivra_cpu1_lset1';
NODE_NAME     PR225 1
 '@S9S_MB_2U_LIB.S9S_MB_2U(SCH_1):PAGE275_I20@PURE_QUANTA.Q_RES(CHIPS)':
 'A': CDS_PINID='A';
NODE_NAME     PU75_P1_1 37
 '@S9S_MB_2U_LIB.S9S_MB_2U(SCH_1):PAGE275_I89@PURE_QUANTA.ISL99390FRZTR5935(CHIPS)':
 'LSET': CDS_PINID='LSET';
NET_NAME
'PVCCFA_EHV_FIVRA_CPU1_LSET2'
 '@S9S_MB_2U_LIB.S9S_MB_2U(SCH_1):PVCCFA_EHV_FIVRA_CPU1_LSET2':
 C_SIGNAL='@s9s_mb_2u_lib.s9s_mb_2u(sch_1):pvccfa_ehv_fivra_cpu1_lset2';
NODE_NAME     PR224 1
 '@S9S_MB_2U_LIB.S9S_MB_2U(SCH_1):PAGE275_I2@PURE_QUANTA.Q_RES(CHIPS)':
 'A': CDS_PINID='A';
NODE_NAME     PU76_P1_2 37
 '@S9S_MB_2U_LIB.S9S_MB_2U(SCH_1):PAGE275_I9@PURE_QUANTA.ISL99390FRZTR5935(CHIPS)':
 'LSET': CDS_PINID='LSET';
NET_NAME
'PVCCFA_EHV_FIVRA_CPU1_LSET3'
 '@S9S_MB_2U_LIB.S9S_MB_2U(SCH_1):PVCCFA_EHV_FIVRA_CPU1_LSET3':
 C_SIGNAL='@s9s_mb_2u_lib.s9s_mb_2u(sch_1):pvccfa_ehv_fivra_cpu1_lset3';
NODE_NAME     PU77_P1_3 37
 '@S9S_MB_2U_LIB.S9S_MB_2U(SCH_1):PAGE276_I24@PURE_QUANTA.ISL99390FRZTR5935(CHIPS)':
 'LSET': CDS_PINID='LSET';
NODE_NAME     PR1305 1
 '@S9S_MB_2U_LIB.S9S_MB_2U(SCH_1):PAGE276_I5@PURE_QUANTA.Q_RES(CHIPS)':
 'A': CDS_PINID='A';
NET_NAME
'PVCCFA_EHV_FIVRA_CPU1_LSET4'
 '@S9S_MB_2U_LIB.S9S_MB_2U(SCH_1):PVCCFA_EHV_FIVRA_CPU1_LSET4':
 C_SIGNAL='@s9s_mb_2u_lib.s9s_mb_2u(sch_1):pvccfa_ehv_fivra_cpu1_lset4';
NODE_NAME     PR1304 1
 '@S9S_MB_2U_LIB.S9S_MB_2U(SCH_1):PAGE276_I2@PURE_QUANTA.Q_RES(CHIPS)':
 'A': CDS_PINID='A';
NODE_NAME     PU78_P1_4 37
 '@S9S_MB_2U_LIB.S9S_MB_2U(SCH_1):PAGE276_I15@PURE_QUANTA.ISL99390FRZTR5935(CHIPS)':
 'LSET': CDS_PINID='LSET';
NET_NAME
'PVCCFA_EHV_FIVRA_CPU1_PVCC1'
 '@S9S_MB_2U_LIB.S9S_MB_2U(SCH_1):PVCCFA_EHV_FIVRA_CPU1_PVCC1':
 C_SIGNAL='@s9s_mb_2u_lib.s9s_mb_2u(sch_1):pvccfa_ehv_fivra_cpu1_pvcc1',
 CDS_GLOBAL_NET='TRUE';
NODE_NAME     PR701 2
 '@S9S_MB_2U_LIB.S9S_MB_2U(SCH_1):PAGE275_I32@PURE_QUANTA.Q_RES(CHIPS)':
 'B': CDS_PINID='B';
NODE_NAME     PR703 2
 '@S9S_MB_2U_LIB.S9S_MB_2U(SCH_1):PAGE275_I34@PURE_QUANTA.Q_RES(CHIPS)':
 'B': CDS_PINID='B';
NODE_NAME     PU77_P1_3 4
 '@S9S_MB_2U_LIB.S9S_MB_2U(SCH_1):PAGE276_I24@PURE_QUANTA.ISL99390FRZTR5935(CHIPS)':
 'PVCC': CDS_PINID='PVCC';
NODE_NAME     PC1244_P1_3 1
 '@S9S_MB_2U_LIB.S9S_MB_2U(SCH_1):PAGE276_I31@PURE_QUANTA.Q_CAP(CHIPS)':
 'A': CDS_PINID='A';
NODE_NAME     PR226 1
 '@S9S_MB_2U_LIB.S9S_MB_2U(SCH_1):PAGE275_I28@PURE_QUANTA.Q_RES(CHIPS)':
 'A': CDS_PINID='A';
NODE_NAME     PC1242_P1_1 1
 '@S9S_MB_2U_LIB.S9S_MB_2U(SCH_1):PAGE275_I31@PURE_QUANTA.Q_CAP(CHIPS)':
 'A': CDS_PINID='A';
NODE_NAME     PU75_P1_1 4
 '@S9S_MB_2U_LIB.S9S_MB_2U(SCH_1):PAGE275_I89@PURE_QUANTA.ISL99390FRZTR5935(CHIPS)':
 'PVCC': CDS_PINID='PVCC';
NODE_NAME     PR1306 1
 '@S9S_MB_2U_LIB.S9S_MB_2U(SCH_1):PAGE276_I29@PURE_QUANTA.Q_RES(CHIPS)':
 'A': CDS_PINID='A';
NET_NAME
'PVCCFA_EHV_FIVRA_CPU1_PVCC2'
 '@S9S_MB_2U_LIB.S9S_MB_2U(SCH_1):PVCCFA_EHV_FIVRA_CPU1_PVCC2':
 C_SIGNAL='@s9s_mb_2u_lib.s9s_mb_2u(sch_1):pvccfa_ehv_fivra_cpu1_pvcc2',
 CDS_GLOBAL_NET='TRUE';
NODE_NAME     PU76_P1_2 4
 '@S9S_MB_2U_LIB.S9S_MB_2U(SCH_1):PAGE275_I9@PURE_QUANTA.ISL99390FRZTR5935(CHIPS)':
 'PVCC': CDS_PINID='PVCC';
NODE_NAME     PU78_P1_4 4
 '@S9S_MB_2U_LIB.S9S_MB_2U(SCH_1):PAGE276_I15@PURE_QUANTA.ISL99390FRZTR5935(CHIPS)':
 'PVCC': CDS_PINID='PVCC';
NODE_NAME     PR1307 1
 '@S9S_MB_2U_LIB.S9S_MB_2U(SCH_1):PAGE276_I18@PURE_QUANTA.Q_RES(CHIPS)':
 'A': CDS_PINID='A';
NODE_NAME     PR227 1
 '@S9S_MB_2U_LIB.S9S_MB_2U(SCH_1):PAGE275_I12@PURE_QUANTA.Q_RES(CHIPS)':
 'A': CDS_PINID='A';
NODE_NAME     PR702 2
 '@S9S_MB_2U_LIB.S9S_MB_2U(SCH_1):PAGE275_I13@PURE_QUANTA.Q_RES(CHIPS)':
 'B': CDS_PINID='B';
NODE_NAME     PC1243_P1_2 1
 '@S9S_MB_2U_LIB.S9S_MB_2U(SCH_1):PAGE275_I16@PURE_QUANTA.Q_CAP(CHIPS)':
 'A': CDS_PINID='A';
NODE_NAME     PR704 2
 '@S9S_MB_2U_LIB.S9S_MB_2U(SCH_1):PAGE275_I17@PURE_QUANTA.Q_RES(CHIPS)':
 'B': CDS_PINID='B';
NODE_NAME     PC1245_P1_4 1
 '@S9S_MB_2U_LIB.S9S_MB_2U(SCH_1):PAGE276_I20@PURE_QUANTA.Q_CAP(CHIPS)':
 'A': CDS_PINID='A';
NET_NAME
'PVCCFA_EHV_FIVRA_CPU1_PWM1'
 '@S9S_MB_2U_LIB.S9S_MB_2U(SCH_1):PVCCFA_EHV_FIVRA_CPU1_PWM1':
 C_SIGNAL='@s9s_mb_2u_lib.s9s_mb_2u(sch_1):pvccfa_ehv_fivra_cpu1_pwm1';
NODE_NAME     PU75_P1_1 34
 '@S9S_MB_2U_LIB.S9S_MB_2U(SCH_1):PAGE275_I89@PURE_QUANTA.ISL99390FRZTR5935(CHIPS)':
 'PWM': CDS_PINID='PWM';
NODE_NAME     PU29 1
 '@S9S_MB_2U_LIB.S9S_MB_2U(SCH_1):PAGE270_I33@PURE_QUANTA.RAA229126GNPHA0(CHIPS)':
 'PWM0': CDS_PINID='PWM0';
NET_NAME
'PVCCFA_EHV_FIVRA_CPU1_PWM2'
 '@S9S_MB_2U_LIB.S9S_MB_2U(SCH_1):PVCCFA_EHV_FIVRA_CPU1_PWM2':
 C_SIGNAL='@s9s_mb_2u_lib.s9s_mb_2u(sch_1):pvccfa_ehv_fivra_cpu1_pwm2';
NODE_NAME     PU76_P1_2 34
 '@S9S_MB_2U_LIB.S9S_MB_2U(SCH_1):PAGE275_I9@PURE_QUANTA.ISL99390FRZTR5935(CHIPS)':
 'PWM': CDS_PINID='PWM';
NODE_NAME     PU29 2
 '@S9S_MB_2U_LIB.S9S_MB_2U(SCH_1):PAGE270_I33@PURE_QUANTA.RAA229126GNPHA0(CHIPS)':
 'PWM1': CDS_PINID='PWM1';
NET_NAME
'PVCCFA_EHV_FIVRA_CPU1_PWM3'
 '@S9S_MB_2U_LIB.S9S_MB_2U(SCH_1):PVCCFA_EHV_FIVRA_CPU1_PWM3':
 C_SIGNAL='@s9s_mb_2u_lib.s9s_mb_2u(sch_1):pvccfa_ehv_fivra_cpu1_pwm3';
NODE_NAME     PU77_P1_3 34
 '@S9S_MB_2U_LIB.S9S_MB_2U(SCH_1):PAGE276_I24@PURE_QUANTA.ISL99390FRZTR5935(CHIPS)':
 'PWM': CDS_PINID='PWM';
NODE_NAME     PU29 3
 '@S9S_MB_2U_LIB.S9S_MB_2U(SCH_1):PAGE270_I33@PURE_QUANTA.RAA229126GNPHA0(CHIPS)':
 'PWM2': CDS_PINID='PWM2';
NET_NAME
'PVCCFA_EHV_FIVRA_CPU1_PWM4'
 '@S9S_MB_2U_LIB.S9S_MB_2U(SCH_1):PVCCFA_EHV_FIVRA_CPU1_PWM4':
 C_SIGNAL='@s9s_mb_2u_lib.s9s_mb_2u(sch_1):pvccfa_ehv_fivra_cpu1_pwm4';
NODE_NAME     PU78_P1_4 34
 '@S9S_MB_2U_LIB.S9S_MB_2U(SCH_1):PAGE276_I15@PURE_QUANTA.ISL99390FRZTR5935(CHIPS)':
 'PWM': CDS_PINID='PWM';
NODE_NAME     PU29 4
 '@S9S_MB_2U_LIB.S9S_MB_2U(SCH_1):PAGE270_I33@PURE_QUANTA.RAA229126GNPHA0(CHIPS)':
 'PWM3': CDS_PINID='PWM3';
NET_NAME
'PVCCFA_EHV_FIVRA_CPU1_VDD1'
 '@S9S_MB_2U_LIB.S9S_MB_2U(SCH_1):PVCCFA_EHV_FIVRA_CPU1_VDD1':
 C_SIGNAL='@s9s_mb_2u_lib.s9s_mb_2u(sch_1):pvccfa_ehv_fivra_cpu1_vdd1';
NODE_NAME     PC395 1
 '@S9S_MB_2U_LIB.S9S_MB_2U(SCH_1):PAGE275_I27@PURE_QUANTA.Q_CAP(CHIPS)':
 'A': CDS_PINID='A';
NODE_NAME     PR226 2
 '@S9S_MB_2U_LIB.S9S_MB_2U(SCH_1):PAGE275_I28@PURE_QUANTA.Q_RES(CHIPS)':
 'B': CDS_PINID='B';
NODE_NAME     PU75_P1_1 35
 '@S9S_MB_2U_LIB.S9S_MB_2U(SCH_1):PAGE275_I89@PURE_QUANTA.ISL99390FRZTR5935(CHIPS)':
 'EN': CDS_PINID='EN';
NODE_NAME     PU75_P1_1 3
 '@S9S_MB_2U_LIB.S9S_MB_2U(SCH_1):PAGE275_I89@PURE_QUANTA.ISL99390FRZTR5935(CHIPS)':
 'VCC': CDS_PINID='VCC';
NET_NAME
'PVCCFA_EHV_FIVRA_CPU1_VDD2'
 '@S9S_MB_2U_LIB.S9S_MB_2U(SCH_1):PVCCFA_EHV_FIVRA_CPU1_VDD2':
 C_SIGNAL='@s9s_mb_2u_lib.s9s_mb_2u(sch_1):pvccfa_ehv_fivra_cpu1_vdd2';
NODE_NAME     PU76_P1_2 35
 '@S9S_MB_2U_LIB.S9S_MB_2U(SCH_1):PAGE275_I9@PURE_QUANTA.ISL99390FRZTR5935(CHIPS)':
 'EN': CDS_PINID='EN';
NODE_NAME     PU76_P1_2 3
 '@S9S_MB_2U_LIB.S9S_MB_2U(SCH_1):PAGE275_I9@PURE_QUANTA.ISL99390FRZTR5935(CHIPS)':
 'VCC': CDS_PINID='VCC';
NODE_NAME     PC396 1
 '@S9S_MB_2U_LIB.S9S_MB_2U(SCH_1):PAGE275_I11@PURE_QUANTA.Q_CAP(CHIPS)':
 'A': CDS_PINID='A';
NODE_NAME     PR227 2
 '@S9S_MB_2U_LIB.S9S_MB_2U(SCH_1):PAGE275_I12@PURE_QUANTA.Q_RES(CHIPS)':
 'B': CDS_PINID='B';
NET_NAME
'PVCCFA_EHV_FIVRA_CPU1_VDD3'
 '@S9S_MB_2U_LIB.S9S_MB_2U(SCH_1):PVCCFA_EHV_FIVRA_CPU1_VDD3':
 C_SIGNAL='@s9s_mb_2u_lib.s9s_mb_2u(sch_1):pvccfa_ehv_fivra_cpu1_vdd3';
NODE_NAME     PC1191 1
 '@S9S_MB_2U_LIB.S9S_MB_2U(SCH_1):PAGE276_I27@PURE_QUANTA.Q_CAP(CHIPS)':
 'A': CDS_PINID='A';
NODE_NAME     PU77_P1_3 35
 '@S9S_MB_2U_LIB.S9S_MB_2U(SCH_1):PAGE276_I24@PURE_QUANTA.ISL99390FRZTR5935(CHIPS)':
 'EN': CDS_PINID='EN';
NODE_NAME     PU77_P1_3 3
 '@S9S_MB_2U_LIB.S9S_MB_2U(SCH_1):PAGE276_I24@PURE_QUANTA.ISL99390FRZTR5935(CHIPS)':
 'VCC': CDS_PINID='VCC';
NODE_NAME     PR1306 2
 '@S9S_MB_2U_LIB.S9S_MB_2U(SCH_1):PAGE276_I29@PURE_QUANTA.Q_RES(CHIPS)':
 'B': CDS_PINID='B';
NET_NAME
'PVCCFA_EHV_FIVRA_CPU1_VDD4'
 '@S9S_MB_2U_LIB.S9S_MB_2U(SCH_1):PVCCFA_EHV_FIVRA_CPU1_VDD4':
 C_SIGNAL='@s9s_mb_2u_lib.s9s_mb_2u(sch_1):pvccfa_ehv_fivra_cpu1_vdd4';
NODE_NAME     PU78_P1_4 35
 '@S9S_MB_2U_LIB.S9S_MB_2U(SCH_1):PAGE276_I15@PURE_QUANTA.ISL99390FRZTR5935(CHIPS)':
 'EN': CDS_PINID='EN';
NODE_NAME     PU78_P1_4 3
 '@S9S_MB_2U_LIB.S9S_MB_2U(SCH_1):PAGE276_I15@PURE_QUANTA.ISL99390FRZTR5935(CHIPS)':
 'VCC': CDS_PINID='VCC';
NODE_NAME     PR1307 2
 '@S9S_MB_2U_LIB.S9S_MB_2U(SCH_1):PAGE276_I18@PURE_QUANTA.Q_RES(CHIPS)':
 'B': CDS_PINID='B';
NODE_NAME     PC1192 1
 '@S9S_MB_2U_LIB.S9S_MB_2U(SCH_1):PAGE276_I12@PURE_QUANTA.Q_CAP(CHIPS)':
 'A': CDS_PINID='A';
NET_NAME
'PVCCFA_EHV_FIVRA_CPU1_VOS1'
 '@S9S_MB_2U_LIB.S9S_MB_2U(SCH_1):PVCCFA_EHV_FIVRA_CPU1_VOS1':
 C_SIGNAL='@s9s_mb_2u_lib.s9s_mb_2u(sch_1):pvccfa_ehv_fivra_cpu1_vos1';
NODE_NAME     PR1331 1
 '@S9S_MB_2U_LIB.S9S_MB_2U(SCH_1):PAGE275_I53@PURE_QUANTA.Q_RES(CHIPS)':
 'A': CDS_PINID='A';
NODE_NAME     PU75_P1_1 1
 '@S9S_MB_2U_LIB.S9S_MB_2U(SCH_1):PAGE275_I89@PURE_QUANTA.ISL99390FRZTR5935(CHIPS)':
 'VOS': CDS_PINID='VOS';
NET_NAME
'PVCCFA_EHV_FIVRA_CPU1_VOS2'
 '@S9S_MB_2U_LIB.S9S_MB_2U(SCH_1):PVCCFA_EHV_FIVRA_CPU1_VOS2':
 C_SIGNAL='@s9s_mb_2u_lib.s9s_mb_2u(sch_1):pvccfa_ehv_fivra_cpu1_vos2';
NODE_NAME     PU76_P1_2 1
 '@S9S_MB_2U_LIB.S9S_MB_2U(SCH_1):PAGE275_I9@PURE_QUANTA.ISL99390FRZTR5935(CHIPS)':
 'VOS': CDS_PINID='VOS';
NODE_NAME     PR1332 1
 '@S9S_MB_2U_LIB.S9S_MB_2U(SCH_1):PAGE275_I41@PURE_QUANTA.Q_RES(CHIPS)':
 'A': CDS_PINID='A';
NET_NAME
'PVCCFA_EHV_FIVRA_CPU1_VOS3'
 '@S9S_MB_2U_LIB.S9S_MB_2U(SCH_1):PVCCFA_EHV_FIVRA_CPU1_VOS3':
 C_SIGNAL='@s9s_mb_2u_lib.s9s_mb_2u(sch_1):pvccfa_ehv_fivra_cpu1_vos3';
NODE_NAME     PU77_P1_3 1
 '@S9S_MB_2U_LIB.S9S_MB_2U(SCH_1):PAGE276_I24@PURE_QUANTA.ISL99390FRZTR5935(CHIPS)':
 'VOS': CDS_PINID='VOS';
NODE_NAME     PR1333 1
 '@S9S_MB_2U_LIB.S9S_MB_2U(SCH_1):PAGE276_I54@PURE_QUANTA.Q_RES(CHIPS)':
 'A': CDS_PINID='A';
NET_NAME
'PVCCFA_EHV_FIVRA_CPU1_VOS4'
 '@S9S_MB_2U_LIB.S9S_MB_2U(SCH_1):PVCCFA_EHV_FIVRA_CPU1_VOS4':
 C_SIGNAL='@s9s_mb_2u_lib.s9s_mb_2u(sch_1):pvccfa_ehv_fivra_cpu1_vos4';
NODE_NAME     PU78_P1_4 1
 '@S9S_MB_2U_LIB.S9S_MB_2U(SCH_1):PAGE276_I15@PURE_QUANTA.ISL99390FRZTR5935(CHIPS)':
 'VOS': CDS_PINID='VOS';
NODE_NAME     PR1334 1
 '@S9S_MB_2U_LIB.S9S_MB_2U(SCH_1):PAGE276_I43@PURE_QUANTA.Q_RES(CHIPS)':
 'A': CDS_PINID='A';
NET_NAME
'PVCCINFAON_CPU0'
 '@S9S_MB_2U_LIB.S9S_MB_2U(SCH_1):PVCCINFAON_CPU0':
 C_SIGNAL='@s9s_mb_2u_lib.s9s_mb_2u(sch_1):pvccinfaon_cpu0',
 CDS_GLOBAL_NET='TRUE';
NODE_NAME     U2 AY18
 '@S9S_MB_2U_LIB.S9S_MB_2U(SCH_1):PAGE37_I7@PURE_QUANTA.SOCKET4677_AZIF0045P001C01CS(CHIPS)':
 'VCCINFAON33': CDS_PINID='VCCINFAON33';
NODE_NAME     U2 BA15
 '@S9S_MB_2U_LIB.S9S_MB_2U(SCH_1):PAGE37_I7@PURE_QUANTA.SOCKET4677_AZIF0045P001C01CS(CHIPS)':
 'VCCINFAON34': CDS_PINID='VCCINFAON34';
NODE_NAME     U2 BC60
 '@S9S_MB_2U_LIB.S9S_MB_2U(SCH_1):PAGE37_I7@PURE_QUANTA.SOCKET4677_AZIF0045P001C01CS(CHIPS)':
 'VCCINFAON35': CDS_PINID='VCCINFAON35';
NODE_NAME     U2 BE15
 '@S9S_MB_2U_LIB.S9S_MB_2U(SCH_1):PAGE37_I7@PURE_QUANTA.SOCKET4677_AZIF0045P001C01CS(CHIPS)':
 'VCCINFAON36': CDS_PINID='VCCINFAON36';
NODE_NAME     U2 BE60
 '@S9S_MB_2U_LIB.S9S_MB_2U(SCH_1):PAGE37_I7@PURE_QUANTA.SOCKET4677_AZIF0045P001C01CS(CHIPS)':
 'VCCINFAON37': CDS_PINID='VCCINFAON37';
NODE_NAME     U2 BG60
 '@S9S_MB_2U_LIB.S9S_MB_2U(SCH_1):PAGE37_I7@PURE_QUANTA.SOCKET4677_AZIF0045P001C01CS(CHIPS)':
 'VCCINFAON38': CDS_PINID='VCCINFAON38';
NODE_NAME     U2 BJ15
 '@S9S_MB_2U_LIB.S9S_MB_2U(SCH_1):PAGE37_I7@PURE_QUANTA.SOCKET4677_AZIF0045P001C01CS(CHIPS)':
 'VCCINFAON39': CDS_PINID='VCCINFAON39';
NODE_NAME     U2 BJ60
 '@S9S_MB_2U_LIB.S9S_MB_2U(SCH_1):PAGE37_I7@PURE_QUANTA.SOCKET4677_AZIF0045P001C01CS(CHIPS)':
 'VCCINFAON40': CDS_PINID='VCCINFAON40';
NODE_NAME     U2 BK61
 '@S9S_MB_2U_LIB.S9S_MB_2U(SCH_1):PAGE37_I7@PURE_QUANTA.SOCKET4677_AZIF0045P001C01CS(CHIPS)':
 'VCCINFAON41': CDS_PINID='VCCINFAON41';
NODE_NAME     U2 BN15
 '@S9S_MB_2U_LIB.S9S_MB_2U(SCH_1):PAGE37_I7@PURE_QUANTA.SOCKET4677_AZIF0045P001C01CS(CHIPS)':
 'VCCINFAON42': CDS_PINID='VCCINFAON42';
NODE_NAME     U2 CA15
 '@S9S_MB_2U_LIB.S9S_MB_2U(SCH_1):PAGE37_I7@PURE_QUANTA.SOCKET4677_AZIF0045P001C01CS(CHIPS)':
 'VCCINFAON43': CDS_PINID='VCCINFAON43';
NODE_NAME     U2 CE19
 '@S9S_MB_2U_LIB.S9S_MB_2U(SCH_1):PAGE37_I7@PURE_QUANTA.SOCKET4677_AZIF0045P001C01CS(CHIPS)':
 'VCCINFAON44': CDS_PINID='VCCINFAON44';
NODE_NAME     U2 CJ11
 '@S9S_MB_2U_LIB.S9S_MB_2U(SCH_1):PAGE37_I7@PURE_QUANTA.SOCKET4677_AZIF0045P001C01CS(CHIPS)':
 'VCCINFAON45': CDS_PINID='VCCINFAON45';
NODE_NAME     U2 CJ19
 '@S9S_MB_2U_LIB.S9S_MB_2U(SCH_1):PAGE37_I7@PURE_QUANTA.SOCKET4677_AZIF0045P001C01CS(CHIPS)':
 'VCCINFAON46': CDS_PINID='VCCINFAON46';
NODE_NAME     U2 CN19
 '@S9S_MB_2U_LIB.S9S_MB_2U(SCH_1):PAGE37_I7@PURE_QUANTA.SOCKET4677_AZIF0045P001C01CS(CHIPS)':
 'VCCINFAON47': CDS_PINID='VCCINFAON47';
NODE_NAME     U2 CP63
 '@S9S_MB_2U_LIB.S9S_MB_2U(SCH_1):PAGE37_I7@PURE_QUANTA.SOCKET4677_AZIF0045P001C01CS(CHIPS)':
 'VCCINFAON48': CDS_PINID='VCCINFAON48';
NODE_NAME     U2 CT63
 '@S9S_MB_2U_LIB.S9S_MB_2U(SCH_1):PAGE37_I7@PURE_QUANTA.SOCKET4677_AZIF0045P001C01CS(CHIPS)':
 'VCCINFAON49': CDS_PINID='VCCINFAON49';
NODE_NAME     U2 CV61
 '@S9S_MB_2U_LIB.S9S_MB_2U(SCH_1):PAGE37_I7@PURE_QUANTA.SOCKET4677_AZIF0045P001C01CS(CHIPS)':
 'VCCINFAON50': CDS_PINID='VCCINFAON50';
NODE_NAME     U2 CV63
 '@S9S_MB_2U_LIB.S9S_MB_2U(SCH_1):PAGE37_I7@PURE_QUANTA.SOCKET4677_AZIF0045P001C01CS(CHIPS)':
 'VCCINFAON51': CDS_PINID='VCCINFAON51';
NODE_NAME     U2 CW62
 '@S9S_MB_2U_LIB.S9S_MB_2U(SCH_1):PAGE37_I7@PURE_QUANTA.SOCKET4677_AZIF0045P001C01CS(CHIPS)':
 'VCCINFAON52': CDS_PINID='VCCINFAON52';
NODE_NAME     U2 DA21
 '@S9S_MB_2U_LIB.S9S_MB_2U(SCH_1):PAGE37_I7@PURE_QUANTA.SOCKET4677_AZIF0045P001C01CS(CHIPS)':
 'VCCINFAON53': CDS_PINID='VCCINFAON53';
NODE_NAME     U2 CE15
 '@S9S_MB_2U_LIB.S9S_MB_2U(SCH_1):PAGE37_I8@PURE_QUANTA.SOCKET4677_AZIF0045P001C01CS(CHIPS)':
 'VCCINFAON0': CDS_PINID='VCCINFAON0';
NODE_NAME     U2 CJ15
 '@S9S_MB_2U_LIB.S9S_MB_2U(SCH_1):PAGE37_I8@PURE_QUANTA.SOCKET4677_AZIF0045P001C01CS(CHIPS)':
 'VCCINFAON1': CDS_PINID='VCCINFAON1';
NODE_NAME     U2 CJ3
 '@S9S_MB_2U_LIB.S9S_MB_2U(SCH_1):PAGE37_I8@PURE_QUANTA.SOCKET4677_AZIF0045P001C01CS(CHIPS)':
 'VCCINFAON2': CDS_PINID='VCCINFAON2';
NODE_NAME     U2 CJ7
 '@S9S_MB_2U_LIB.S9S_MB_2U(SCH_1):PAGE37_I8@PURE_QUANTA.SOCKET4677_AZIF0045P001C01CS(CHIPS)':
 'VCCINFAON3': CDS_PINID='VCCINFAON3';
NODE_NAME     U2 CN11
 '@S9S_MB_2U_LIB.S9S_MB_2U(SCH_1):PAGE37_I8@PURE_QUANTA.SOCKET4677_AZIF0045P001C01CS(CHIPS)':
 'VCCINFAON4': CDS_PINID='VCCINFAON4';
NODE_NAME     U2 CN15
 '@S9S_MB_2U_LIB.S9S_MB_2U(SCH_1):PAGE37_I8@PURE_QUANTA.SOCKET4677_AZIF0045P001C01CS(CHIPS)':
 'VCCINFAON5': CDS_PINID='VCCINFAON5';
NODE_NAME     U2 CN3
 '@S9S_MB_2U_LIB.S9S_MB_2U(SCH_1):PAGE37_I8@PURE_QUANTA.SOCKET4677_AZIF0045P001C01CS(CHIPS)':
 'VCCINFAON6': CDS_PINID='VCCINFAON6';
NODE_NAME     U2 CN64
 '@S9S_MB_2U_LIB.S9S_MB_2U(SCH_1):PAGE37_I8@PURE_QUANTA.SOCKET4677_AZIF0045P001C01CS(CHIPS)':
 'VCCINFAON7': CDS_PINID='VCCINFAON7';
NODE_NAME     U2 CN66
 '@S9S_MB_2U_LIB.S9S_MB_2U(SCH_1):PAGE37_I8@PURE_QUANTA.SOCKET4677_AZIF0045P001C01CS(CHIPS)':
 'VCCINFAON8': CDS_PINID='VCCINFAON8';
NODE_NAME     U2 CN7
 '@S9S_MB_2U_LIB.S9S_MB_2U(SCH_1):PAGE37_I8@PURE_QUANTA.SOCKET4677_AZIF0045P001C01CS(CHIPS)':
 'VCCINFAON9': CDS_PINID='VCCINFAON9';
NODE_NAME     U2 CP65
 '@S9S_MB_2U_LIB.S9S_MB_2U(SCH_1):PAGE37_I8@PURE_QUANTA.SOCKET4677_AZIF0045P001C01CS(CHIPS)':
 'VCCINFAON10': CDS_PINID='VCCINFAON10';
NODE_NAME     U2 CP67
 '@S9S_MB_2U_LIB.S9S_MB_2U(SCH_1):PAGE37_I8@PURE_QUANTA.SOCKET4677_AZIF0045P001C01CS(CHIPS)':
 'VCCINFAON11': CDS_PINID='VCCINFAON11';
NODE_NAME     U2 CT65
 '@S9S_MB_2U_LIB.S9S_MB_2U(SCH_1):PAGE37_I8@PURE_QUANTA.SOCKET4677_AZIF0045P001C01CS(CHIPS)':
 'VCCINFAON12': CDS_PINID='VCCINFAON12';
NODE_NAME     U2 CT67
 '@S9S_MB_2U_LIB.S9S_MB_2U(SCH_1):PAGE37_I8@PURE_QUANTA.SOCKET4677_AZIF0045P001C01CS(CHIPS)':
 'VCCINFAON13': CDS_PINID='VCCINFAON13';
NODE_NAME     U2 CU11
 '@S9S_MB_2U_LIB.S9S_MB_2U(SCH_1):PAGE37_I8@PURE_QUANTA.SOCKET4677_AZIF0045P001C01CS(CHIPS)':
 'VCCINFAON14': CDS_PINID='VCCINFAON14';
NODE_NAME     U2 CU15
 '@S9S_MB_2U_LIB.S9S_MB_2U(SCH_1):PAGE37_I8@PURE_QUANTA.SOCKET4677_AZIF0045P001C01CS(CHIPS)':
 'VCCINFAON15': CDS_PINID='VCCINFAON15';
NODE_NAME     U2 CU3
 '@S9S_MB_2U_LIB.S9S_MB_2U(SCH_1):PAGE37_I8@PURE_QUANTA.SOCKET4677_AZIF0045P001C01CS(CHIPS)':
 'VCCINFAON16': CDS_PINID='VCCINFAON16';
NODE_NAME     U2 CU64
 '@S9S_MB_2U_LIB.S9S_MB_2U(SCH_1):PAGE37_I8@PURE_QUANTA.SOCKET4677_AZIF0045P001C01CS(CHIPS)':
 'VCCINFAON17': CDS_PINID='VCCINFAON17';
NODE_NAME     U2 CU7
 '@S9S_MB_2U_LIB.S9S_MB_2U(SCH_1):PAGE37_I8@PURE_QUANTA.SOCKET4677_AZIF0045P001C01CS(CHIPS)':
 'VCCINFAON18': CDS_PINID='VCCINFAON18';
NODE_NAME     U2 CV65
 '@S9S_MB_2U_LIB.S9S_MB_2U(SCH_1):PAGE37_I8@PURE_QUANTA.SOCKET4677_AZIF0045P001C01CS(CHIPS)':
 'VCCINFAON19': CDS_PINID='VCCINFAON19';
NODE_NAME     U2 CV67
 '@S9S_MB_2U_LIB.S9S_MB_2U(SCH_1):PAGE37_I8@PURE_QUANTA.SOCKET4677_AZIF0045P001C01CS(CHIPS)':
 'VCCINFAON20': CDS_PINID='VCCINFAON20';
NODE_NAME     U2 CW66
 '@S9S_MB_2U_LIB.S9S_MB_2U(SCH_1):PAGE37_I8@PURE_QUANTA.SOCKET4677_AZIF0045P001C01CS(CHIPS)':
 'VCCINFAON21': CDS_PINID='VCCINFAON21';
NODE_NAME     U2 CY65
 '@S9S_MB_2U_LIB.S9S_MB_2U(SCH_1):PAGE37_I8@PURE_QUANTA.SOCKET4677_AZIF0045P001C01CS(CHIPS)':
 'VCCINFAON22': CDS_PINID='VCCINFAON22';
NODE_NAME     U2 CY67
 '@S9S_MB_2U_LIB.S9S_MB_2U(SCH_1):PAGE37_I8@PURE_QUANTA.SOCKET4677_AZIF0045P001C01CS(CHIPS)':
 'VCCINFAON23': CDS_PINID='VCCINFAON23';
NODE_NAME     U2 DA11
 '@S9S_MB_2U_LIB.S9S_MB_2U(SCH_1):PAGE37_I8@PURE_QUANTA.SOCKET4677_AZIF0045P001C01CS(CHIPS)':
 'VCCINFAON24': CDS_PINID='VCCINFAON24';
NODE_NAME     U2 DA15
 '@S9S_MB_2U_LIB.S9S_MB_2U(SCH_1):PAGE37_I8@PURE_QUANTA.SOCKET4677_AZIF0045P001C01CS(CHIPS)':
 'VCCINFAON25': CDS_PINID='VCCINFAON25';
NODE_NAME     U2 DA64
 '@S9S_MB_2U_LIB.S9S_MB_2U(SCH_1):PAGE37_I8@PURE_QUANTA.SOCKET4677_AZIF0045P001C01CS(CHIPS)':
 'VCCINFAON26': CDS_PINID='VCCINFAON26';
NODE_NAME     U2 DE11
 '@S9S_MB_2U_LIB.S9S_MB_2U(SCH_1):PAGE37_I8@PURE_QUANTA.SOCKET4677_AZIF0045P001C01CS(CHIPS)':
 'VCCINFAON27': CDS_PINID='VCCINFAON27';
NODE_NAME     U2 DE15
 '@S9S_MB_2U_LIB.S9S_MB_2U(SCH_1):PAGE37_I8@PURE_QUANTA.SOCKET4677_AZIF0045P001C01CS(CHIPS)':
 'VCCINFAON28': CDS_PINID='VCCINFAON28';
NODE_NAME     U2 DE3
 '@S9S_MB_2U_LIB.S9S_MB_2U(SCH_1):PAGE37_I8@PURE_QUANTA.SOCKET4677_AZIF0045P001C01CS(CHIPS)':
 'VCCINFAON29': CDS_PINID='VCCINFAON29';
NODE_NAME     U2 DJ15
 '@S9S_MB_2U_LIB.S9S_MB_2U(SCH_1):PAGE37_I8@PURE_QUANTA.SOCKET4677_AZIF0045P001C01CS(CHIPS)':
 'VCCINFAON30': CDS_PINID='VCCINFAON30';
NODE_NAME     U2 DJ3
 '@S9S_MB_2U_LIB.S9S_MB_2U(SCH_1):PAGE37_I8@PURE_QUANTA.SOCKET4677_AZIF0045P001C01CS(CHIPS)':
 'VCCINFAON31': CDS_PINID='VCCINFAON31';
NODE_NAME     U2 DJ7
 '@S9S_MB_2U_LIB.S9S_MB_2U(SCH_1):PAGE37_I8@PURE_QUANTA.SOCKET4677_AZIF0045P001C01CS(CHIPS)':
 'VCCINFAON32': CDS_PINID='VCCINFAON32';
NODE_NAME     U2 CR66
 '@S9S_MB_2U_LIB.S9S_MB_2U(SCH_1):PAGE37_I8@PURE_QUANTA.SOCKET4677_AZIF0045P001C01CS(CHIPS)':
 'VCCINFAON54': CDS_PINID='VCCINFAON54';
NODE_NAME     U2 CW64
 '@S9S_MB_2U_LIB.S9S_MB_2U(SCH_1):PAGE37_I8@PURE_QUANTA.SOCKET4677_AZIF0045P001C01CS(CHIPS)':
 'VCCINFAON55': CDS_PINID='VCCINFAON55';
NODE_NAME     U2 DA3
 '@S9S_MB_2U_LIB.S9S_MB_2U(SCH_1):PAGE37_I8@PURE_QUANTA.SOCKET4677_AZIF0045P001C01CS(CHIPS)':
 'VCCINFAON56': CDS_PINID='VCCINFAON56';
NODE_NAME     U2 DA7
 '@S9S_MB_2U_LIB.S9S_MB_2U(SCH_1):PAGE37_I8@PURE_QUANTA.SOCKET4677_AZIF0045P001C01CS(CHIPS)':
 'VCCINFAON57': CDS_PINID='VCCINFAON57';
NODE_NAME     U2 DE7
 '@S9S_MB_2U_LIB.S9S_MB_2U(SCH_1):PAGE37_I8@PURE_QUANTA.SOCKET4677_AZIF0045P001C01CS(CHIPS)':
 'VCCINFAON58': CDS_PINID='VCCINFAON58';
NODE_NAME     U2 DJ11
 '@S9S_MB_2U_LIB.S9S_MB_2U(SCH_1):PAGE37_I8@PURE_QUANTA.SOCKET4677_AZIF0045P001C01CS(CHIPS)':
 'VCCINFAON59': CDS_PINID='VCCINFAON59';
NODE_NAME     C410 1
 '@S9S_MB_2U_LIB.S9S_MB_2U(SCH_1):PAGE74_I41@PURE_QUANTA.Q_CAP(CHIPS)':
 'A': CDS_PINID='A';
NODE_NAME     C412 1
 '@S9S_MB_2U_LIB.S9S_MB_2U(SCH_1):PAGE74_I42@PURE_QUANTA.Q_CAP(CHIPS)':
 'A': CDS_PINID='A';
NODE_NAME     C414 1
 '@S9S_MB_2U_LIB.S9S_MB_2U(SCH_1):PAGE74_I70@PURE_QUANTA.Q_CAP(CHIPS)':
 'A': CDS_PINID='A';
NODE_NAME     C416 1
 '@S9S_MB_2U_LIB.S9S_MB_2U(SCH_1):PAGE74_I72@PURE_QUANTA.Q_CAP(CHIPS)':
 'A': CDS_PINID='A';
NODE_NAME     C408 1
 '@S9S_MB_2U_LIB.S9S_MB_2U(SCH_1):PAGE74_I142@PURE_QUANTA.Q_CAP(CHIPS)':
 'A': CDS_PINID='A';
NODE_NAME     C532 1
 '@S9S_MB_2U_LIB.S9S_MB_2U(SCH_1):PAGE75_I14@PURE_QUANTA.Q_CAP(CHIPS)':
 'A': CDS_PINID='A';
NODE_NAME     C528 1
 '@S9S_MB_2U_LIB.S9S_MB_2U(SCH_1):PAGE76_I6@PURE_QUANTA.Q_CAP(CHIPS)':
 'A': CDS_PINID='A';
NODE_NAME     C530 1
 '@S9S_MB_2U_LIB.S9S_MB_2U(SCH_1):PAGE76_I7@PURE_QUANTA.Q_CAP(CHIPS)':
 'A': CDS_PINID='A';
NODE_NAME     C531 1
 '@S9S_MB_2U_LIB.S9S_MB_2U(SCH_1):PAGE76_I31@PURE_QUANTA.Q_CAP(CHIPS)':
 'A': CDS_PINID='A';
NODE_NAME     C522 1
 '@S9S_MB_2U_LIB.S9S_MB_2U(SCH_1):PAGE75_I9@PURE_QUANTA.Q_CAP(CHIPS)':
 'A': CDS_PINID='A';
NODE_NAME     C533 1
 '@S9S_MB_2U_LIB.S9S_MB_2U(SCH_1):PAGE75_I17@PURE_QUANTA.Q_CAP(CHIPS)':
 'A': CDS_PINID='A';
NODE_NAME     C534 1
 '@S9S_MB_2U_LIB.S9S_MB_2U(SCH_1):PAGE75_I29@PURE_QUANTA.Q_CAP(CHIPS)':
 'A': CDS_PINID='A';
NODE_NAME     C525 1
 '@S9S_MB_2U_LIB.S9S_MB_2U(SCH_1):PAGE76_I5@PURE_QUANTA.Q_CAP(CHIPS)':
 'A': CDS_PINID='A';
NODE_NAME     R323 1
 '@S9S_MB_2U_LIB.S9S_MB_2U(SCH_1):PAGE80_I13@PURE_QUANTA.Q_RES(CHIPS)':
 'A': CDS_PINID='A';
NODE_NAME     PR521 2
 '@S9S_MB_2U_LIB.S9S_MB_2U(SCH_1):PAGE260_I44@PURE_QUANTA.Q_RES(CHIPS)':
 'B': CDS_PINID='B';
NODE_NAME     PR1777 2
 '@S9S_MB_2U_LIB.S9S_MB_2U(SCH_1):PAGE261_I31@PURE_QUANTA.Q_RES(CHIPS)':
 'B': CDS_PINID='B';
NODE_NAME     PL5 2
 '@S9S_MB_2U_LIB.S9S_MB_2U(SCH_1):PAGE261_I39@PURE_QUANTA.Q_INDUCTOR(CHIPS)':
 '2': CDS_PINID='\2\';
NODE_NAME     PC203_P0_2 1
 '@S9S_MB_2U_LIB.S9S_MB_2U(SCH_1):PAGE261_I40@PURE_QUANTA.Q_CAP(CHIPS)':
 'A': CDS_PINID='A';
NODE_NAME     PR1776 2
 '@S9S_MB_2U_LIB.S9S_MB_2U(SCH_1):PAGE261_I46@PURE_QUANTA.Q_RES(CHIPS)':
 'B': CDS_PINID='B';
NODE_NAME     PL4 2
 '@S9S_MB_2U_LIB.S9S_MB_2U(SCH_1):PAGE261_I52@PURE_QUANTA.Q_INDUCTOR(CHIPS)':
 '2': CDS_PINID='\2\';
NODE_NAME     PC202_P0_1 1
 '@S9S_MB_2U_LIB.S9S_MB_2U(SCH_1):PAGE261_I56@PURE_QUANTA.Q_CAP(CHIPS)':
 'A': CDS_PINID='A';
NODE_NAME     PC1574 1
 '@S9S_MB_2U_LIB.S9S_MB_2U(SCH_1):PAGE261_I66@PURE_QUANTA.Q_CAPP(CHIPS)':
 'A': CDS_PINID='A';
NODE_NAME     PC1576 1
 '@S9S_MB_2U_LIB.S9S_MB_2U(SCH_1):PAGE261_I67@PURE_QUANTA.Q_CAPP(CHIPS)':
 'A': CDS_PINID='A';
NODE_NAME     PC1573 1
 '@S9S_MB_2U_LIB.S9S_MB_2U(SCH_1):PAGE261_I68@PURE_QUANTA.Q_CAPP(CHIPS)':
 'A': CDS_PINID='A';
NODE_NAME     PC205_P0_2 1
 '@S9S_MB_2U_LIB.S9S_MB_2U(SCH_1):PAGE261_I41@PURE_QUANTA.Q_CAP(CHIPS)':
 'A': CDS_PINID='A';
NODE_NAME     PC1575 1
 '@S9S_MB_2U_LIB.S9S_MB_2U(SCH_1):PAGE261_I69@PURE_QUANTA.Q_CAPP(CHIPS)':
 'A': CDS_PINID='A';
NODE_NAME     PC199_P0_1 1
 '@S9S_MB_2U_LIB.S9S_MB_2U(SCH_1):PAGE261_I54@PURE_QUANTA.Q_CAP(CHIPS)':
 'A': CDS_PINID='A';
NODE_NAME     PC204_P0_1 1
 '@S9S_MB_2U_LIB.S9S_MB_2U(SCH_1):PAGE261_I57@PURE_QUANTA.Q_CAP(CHIPS)':
 'A': CDS_PINID='A';
NODE_NAME     PR4226 1
 '@S9S_MB_2U_LIB.S9S_MB_2U(SCH_1):PAGE261_I63@PURE_QUANTA.Q_RES(CHIPS)':
 'A': CDS_PINID='A';
NODE_NAME     PC1579 1
 '@S9S_MB_2U_LIB.S9S_MB_2U(SCH_1):PAGE261_I70@PURE_QUANTA.Q_CAPP(CHIPS)':
 'A': CDS_PINID='A';
NET_NAME
'PVCCINFAON_CPU0_ACSP1'
 '@S9S_MB_2U_LIB.S9S_MB_2U(SCH_1):PVCCINFAON_CPU0_ACSP1':
 C_SIGNAL='@s9s_mb_2u_lib.s9s_mb_2u(sch_1):pvccinfaon_cpu0_acsp1';
NODE_NAME     PU5 23
 '@S9S_MB_2U_LIB.S9S_MB_2U(SCH_1):PAGE260_I65@PURE_QUANTA.ISL69260IRAZT(CHIPS)':
 'CS7': CDS_PINID='CS7';
NODE_NAME     PU43_P0_1 38
 '@S9S_MB_2U_LIB.S9S_MB_2U(SCH_1):PAGE261_I79@PURE_QUANTA.ISL99390FRZTR5935(CHIPS)':
 'IOUT': CDS_PINID='IOUT';
NET_NAME
'PVCCINFAON_CPU0_ACSP2'
 '@S9S_MB_2U_LIB.S9S_MB_2U(SCH_1):PVCCINFAON_CPU0_ACSP2':
 C_SIGNAL='@s9s_mb_2u_lib.s9s_mb_2u(sch_1):pvccinfaon_cpu0_acsp2';
NODE_NAME     PU5 24
 '@S9S_MB_2U_LIB.S9S_MB_2U(SCH_1):PAGE260_I65@PURE_QUANTA.ISL69260IRAZT(CHIPS)':
 'CS6': CDS_PINID='CS6';
NODE_NAME     PU44_P0_2 38
 '@S9S_MB_2U_LIB.S9S_MB_2U(SCH_1):PAGE261_I12@PURE_QUANTA.ISL99390FRZTR5935(CHIPS)':
 'IOUT': CDS_PINID='IOUT';
NET_NAME
'PVCCINFAON_CPU0_ADDR'
 '@S9S_MB_2U_LIB.S9S_MB_2U(SCH_1):PVCCINFAON_CPU0_ADDR':
 C_SIGNAL='@s9s_mb_2u_lib.s9s_mb_2u(sch_1):pvccinfaon_cpu0_addr';
NODE_NAME     PU5 34
 '@S9S_MB_2U_LIB.S9S_MB_2U(SCH_1):PAGE260_I65@PURE_QUANTA.ISL69260IRAZT(CHIPS)':
 'ADDR_CFG': CDS_PINID='ADDR_CFG';
NODE_NAME     PR105 2
 '@S9S_MB_2U_LIB.S9S_MB_2U(SCH_1):PAGE260_I7@PURE_QUANTA.Q_RES(CHIPS)':
 'B': CDS_PINID='B';
NODE_NAME     PR106 1
 '@S9S_MB_2U_LIB.S9S_MB_2U(SCH_1):PAGE260_I109@PURE_QUANTA.Q_RES(CHIPS)':
 'A': CDS_PINID='A';
NET_NAME
'PVCCINFAON_CPU0_APWM1'
 '@S9S_MB_2U_LIB.S9S_MB_2U(SCH_1):PVCCINFAON_CPU0_APWM1':
 C_SIGNAL='@s9s_mb_2u_lib.s9s_mb_2u(sch_1):pvccinfaon_cpu0_apwm1';
NODE_NAME     PU5 8
 '@S9S_MB_2U_LIB.S9S_MB_2U(SCH_1):PAGE260_I65@PURE_QUANTA.ISL69260IRAZT(CHIPS)':
 'PWM7': CDS_PINID='PWM7';
NODE_NAME     PU43_P0_1 34
 '@S9S_MB_2U_LIB.S9S_MB_2U(SCH_1):PAGE261_I79@PURE_QUANTA.ISL99390FRZTR5935(CHIPS)':
 'PWM': CDS_PINID='PWM';
NET_NAME
'PVCCINFAON_CPU0_APWM2'
 '@S9S_MB_2U_LIB.S9S_MB_2U(SCH_1):PVCCINFAON_CPU0_APWM2':
 C_SIGNAL='@s9s_mb_2u_lib.s9s_mb_2u(sch_1):pvccinfaon_cpu0_apwm2';
NODE_NAME     PU5 7
 '@S9S_MB_2U_LIB.S9S_MB_2U(SCH_1):PAGE260_I65@PURE_QUANTA.ISL69260IRAZT(CHIPS)':
 'PWM6': CDS_PINID='PWM6';
NODE_NAME     PU44_P0_2 34
 '@S9S_MB_2U_LIB.S9S_MB_2U(SCH_1):PAGE261_I12@PURE_QUANTA.ISL99390FRZTR5935(CHIPS)':
 'PWM': CDS_PINID='PWM';
NET_NAME
'PVCCINFAON_CPU0_ATSEN'
 '@S9S_MB_2U_LIB.S9S_MB_2U(SCH_1):PVCCINFAON_CPU0_ATSEN':
 C_SIGNAL='@s9s_mb_2u_lib.s9s_mb_2u(sch_1):pvccinfaon_cpu0_atsen';
NODE_NAME     PU5 35
 '@S9S_MB_2U_LIB.S9S_MB_2U(SCH_1):PAGE260_I65@PURE_QUANTA.ISL69260IRAZT(CHIPS)':
 'TEMP0': CDS_PINID='TEMP0';
NODE_NAME     PU44_P0_2 36
 '@S9S_MB_2U_LIB.S9S_MB_2U(SCH_1):PAGE261_I12@PURE_QUANTA.ISL99390FRZTR5935(CHIPS)':
 'TOUT_FLT': CDS_PINID='TOUT_FLT';
NODE_NAME     PU43_P0_1 36
 '@S9S_MB_2U_LIB.S9S_MB_2U(SCH_1):PAGE261_I79@PURE_QUANTA.ISL99390FRZTR5935(CHIPS)':
 'TOUT_FLT': CDS_PINID='TOUT_FLT';
NODE_NAME     PC222 1
 '@S9S_MB_2U_LIB.S9S_MB_2U(SCH_1):PAGE260_I69@PURE_QUANTA.Q_CAP(CHIPS)':
 'A': CDS_PINID='A';
NODE_NAME     PR435 1
 '@S9S_MB_2U_LIB.S9S_MB_2U(SCH_1):PAGE260_I71@PURE_QUANTA.Q_RES(CHIPS)':
 'A': CDS_PINID='A';
NET_NAME
'PVCCINFAON_CPU0_CSPIN'
 '@S9S_MB_2U_LIB.S9S_MB_2U(SCH_1):PVCCINFAON_CPU0_CSPIN':
 C_SIGNAL='@s9s_mb_2u_lib.s9s_mb_2u(sch_1):pvccinfaon_cpu0_cspin';
NODE_NAME     PU5 37
 '@S9S_MB_2U_LIB.S9S_MB_2U(SCH_1):PAGE260_I65@PURE_QUANTA.ISL69260IRAZT(CHIPS)':
 'VMON||IINSEN||VSYS||ISYS': CDS_PINID='\vmon||iinsen||vsys||isys\';
NODE_NAME     PR107 2
 '@S9S_MB_2U_LIB.S9S_MB_2U(SCH_1):PAGE260_I10@PURE_QUANTA.Q_RES(CHIPS)':
 'B': CDS_PINID='B';
NODE_NAME     PR4220 1
 '@S9S_MB_2U_LIB.S9S_MB_2U(SCH_1):PAGE260_I19@PURE_QUANTA.Q_RES(CHIPS)':
 'A': CDS_PINID='A';
NODE_NAME     PC214 1
 '@S9S_MB_2U_LIB.S9S_MB_2U(SCH_1):PAGE260_I20@PURE_QUANTA.Q_CAP(CHIPS)':
 'A': CDS_PINID='A';
NET_NAME
'PVCCINFAON_CPU0_EN_R'
 '@S9S_MB_2U_LIB.S9S_MB_2U(SCH_1):PVCCINFAON_CPU0_EN_R':
 C_SIGNAL='@s9s_mb_2u_lib.s9s_mb_2u(sch_1):pvccinfaon_cpu0_en_r';
NODE_NAME     C3274 1
 '@S9S_MB_2U_LIB.S9S_MB_2U(SCH_1):PAGE260_I60@PURE_QUANTA.Q_CAP(CHIPS)':
 'A': CDS_PINID='A';
NODE_NAME     PU5 13
 '@S9S_MB_2U_LIB.S9S_MB_2U(SCH_1):PAGE260_I65@PURE_QUANTA.ISL69260IRAZT(CHIPS)':
 'EN0': CDS_PINID='EN0';
NODE_NAME     R2594 2
 '@S9S_MB_2U_LIB.S9S_MB_2U(SCH_1):PAGE260_I55@PURE_QUANTA.Q_RES(CHIPS)':
 'B': CDS_PINID='B';
NET_NAME
'PVCCINFAON_CPU0_LSET1'
 '@S9S_MB_2U_LIB.S9S_MB_2U(SCH_1):PVCCINFAON_CPU0_LSET1':
 C_SIGNAL='@s9s_mb_2u_lib.s9s_mb_2u(sch_1):pvccinfaon_cpu0_lset1';
NODE_NAME     PU43_P0_1 37
 '@S9S_MB_2U_LIB.S9S_MB_2U(SCH_1):PAGE261_I79@PURE_QUANTA.ISL99390FRZTR5935(CHIPS)':
 'LSET': CDS_PINID='LSET';
NODE_NAME     PR1708 1
 '@S9S_MB_2U_LIB.S9S_MB_2U(SCH_1):PAGE261_I5@PURE_QUANTA.Q_RES(CHIPS)':
 'A': CDS_PINID='A';
NET_NAME
'PVCCINFAON_CPU0_LSET2'
 '@S9S_MB_2U_LIB.S9S_MB_2U(SCH_1):PVCCINFAON_CPU0_LSET2':
 C_SIGNAL='@s9s_mb_2u_lib.s9s_mb_2u(sch_1):pvccinfaon_cpu0_lset2';
NODE_NAME     PU44_P0_2 37
 '@S9S_MB_2U_LIB.S9S_MB_2U(SCH_1):PAGE261_I12@PURE_QUANTA.ISL99390FRZTR5935(CHIPS)':
 'LSET': CDS_PINID='LSET';
NODE_NAME     PR1707 1
 '@S9S_MB_2U_LIB.S9S_MB_2U(SCH_1):PAGE261_I2@PURE_QUANTA.Q_RES(CHIPS)':
 'A': CDS_PINID='A';
NET_NAME
'PVCCINFAON_CPU0_PIN_ALERT'
 '@S9S_MB_2U_LIB.S9S_MB_2U(SCH_1):PVCCINFAON_CPU0_PIN_ALERT':
 C_SIGNAL='@s9s_mb_2u_lib.s9s_mb_2u(sch_1):pvccinfaon_cpu0_pin_alert';
NODE_NAME     PU5 15
 '@S9S_MB_2U_LIB.S9S_MB_2U(SCH_1):PAGE260_I65@PURE_QUANTA.ISL69260IRAZT(CHIPS)':
 'NPINALERT#||NPSYSCRIT#': CDS_PINID='\npinalert#||npsyscrit#\';
NODE_NAME     R2393 2
 '@S9S_MB_2U_LIB.S9S_MB_2U(SCH_1):PAGE260_I17@PURE_QUANTA.Q_RES(CHIPS)':
 'B': CDS_PINID='B';
NET_NAME
'PVCCINFAON_CPU0_VCC'
 '@S9S_MB_2U_LIB.S9S_MB_2U(SCH_1):PVCCINFAON_CPU0_VCC':
 C_SIGNAL='@s9s_mb_2u_lib.s9s_mb_2u(sch_1):pvccinfaon_cpu0_vcc';
NODE_NAME     PU5 39
 '@S9S_MB_2U_LIB.S9S_MB_2U(SCH_1):PAGE260_I65@PURE_QUANTA.ISL69260IRAZT(CHIPS)':
 'VCC': CDS_PINID='VCC';
NODE_NAME     PC223 1
 '@S9S_MB_2U_LIB.S9S_MB_2U(SCH_1):PAGE260_I98@PURE_QUANTA.Q_CAP(CHIPS)':
 'A': CDS_PINID='A';
NODE_NAME     PC225 1
 '@S9S_MB_2U_LIB.S9S_MB_2U(SCH_1):PAGE260_I99@PURE_QUANTA.Q_CAP(CHIPS)':
 'A': CDS_PINID='A';
NODE_NAME     PR130 1
 '@S9S_MB_2U_LIB.S9S_MB_2U(SCH_1):PAGE260_I100@PURE_QUANTA.Q_RES(CHIPS)':
 'A': CDS_PINID='A';
NODE_NAME     PC2362 1
 '@S9S_MB_2U_LIB.S9S_MB_2U(SCH_1):PAGE260_I110@PURE_QUANTA.Q_CAP(CHIPS)':
 'A': CDS_PINID='A';
NET_NAME
'PVCCINFAON_CPU0_VDD1'
 '@S9S_MB_2U_LIB.S9S_MB_2U(SCH_1):PVCCINFAON_CPU0_VDD1':
 C_SIGNAL='@s9s_mb_2u_lib.s9s_mb_2u(sch_1):pvccinfaon_cpu0_vdd1';
NODE_NAME     PR101 2
 '@S9S_MB_2U_LIB.S9S_MB_2U(SCH_1):PAGE261_I26@PURE_QUANTA.Q_RES(CHIPS)':
 'B': CDS_PINID='B';
NODE_NAME     PU43_P0_1 35
 '@S9S_MB_2U_LIB.S9S_MB_2U(SCH_1):PAGE261_I79@PURE_QUANTA.ISL99390FRZTR5935(CHIPS)':
 'EN': CDS_PINID='EN';
NODE_NAME     PU43_P0_1 3
 '@S9S_MB_2U_LIB.S9S_MB_2U(SCH_1):PAGE261_I79@PURE_QUANTA.ISL99390FRZTR5935(CHIPS)':
 'VCC': CDS_PINID='VCC';
NODE_NAME     PC187 1
 '@S9S_MB_2U_LIB.S9S_MB_2U(SCH_1):PAGE261_I24@PURE_QUANTA.Q_CAP(CHIPS)':
 'A': CDS_PINID='A';
NET_NAME
'PVCCINFAON_CPU0_VDD2'
 '@S9S_MB_2U_LIB.S9S_MB_2U(SCH_1):PVCCINFAON_CPU0_VDD2':
 C_SIGNAL='@s9s_mb_2u_lib.s9s_mb_2u(sch_1):pvccinfaon_cpu0_vdd2';
NODE_NAME     PU44_P0_2 35
 '@S9S_MB_2U_LIB.S9S_MB_2U(SCH_1):PAGE261_I12@PURE_QUANTA.ISL99390FRZTR5935(CHIPS)':
 'EN': CDS_PINID='EN';
NODE_NAME     PU44_P0_2 3
 '@S9S_MB_2U_LIB.S9S_MB_2U(SCH_1):PAGE261_I12@PURE_QUANTA.ISL99390FRZTR5935(CHIPS)':
 'VCC': CDS_PINID='VCC';
NODE_NAME     PR102 2
 '@S9S_MB_2U_LIB.S9S_MB_2U(SCH_1):PAGE261_I14@PURE_QUANTA.Q_RES(CHIPS)':
 'B': CDS_PINID='B';
NODE_NAME     PC188 1
 '@S9S_MB_2U_LIB.S9S_MB_2U(SCH_1):PAGE261_I13@PURE_QUANTA.Q_CAP(CHIPS)':
 'A': CDS_PINID='A';
NET_NAME
'PVCCINFAON_CPU0_VIN_CSNIN'
 '@S9S_MB_2U_LIB.S9S_MB_2U(SCH_1):PVCCINFAON_CPU0_VIN_CSNIN':
 C_SIGNAL='@s9s_mb_2u_lib.s9s_mb_2u(sch_1):pvccinfaon_cpu0_vin_csnin';
NODE_NAME     PU5 38
 '@S9S_MB_2U_LIB.S9S_MB_2U(SCH_1):PAGE260_I65@PURE_QUANTA.ISL69260IRAZT(CHIPS)':
 'VINSEN||VSYS': CDS_PINID='\vinsen||vsys\';
NODE_NAME     PC221 1
 '@S9S_MB_2U_LIB.S9S_MB_2U(SCH_1):PAGE260_I63@PURE_QUANTA.Q_CAP(CHIPS)':
 'A': CDS_PINID='A';
NODE_NAME     PR108 2
 '@S9S_MB_2U_LIB.S9S_MB_2U(SCH_1):PAGE260_I9@PURE_QUANTA.Q_RES(CHIPS)':
 'B': CDS_PINID='B';
NODE_NAME     PR123 1
 '@S9S_MB_2U_LIB.S9S_MB_2U(SCH_1):PAGE260_I21@PURE_QUANTA.Q_RES(CHIPS)':
 'A': CDS_PINID='A';
NET_NAME
'PVCCINFAON_CPU0_VOS1'
 '@S9S_MB_2U_LIB.S9S_MB_2U(SCH_1):PVCCINFAON_CPU0_VOS1':
 C_SIGNAL='@s9s_mb_2u_lib.s9s_mb_2u(sch_1):pvccinfaon_cpu0_vos1';
NODE_NAME     PR1776 1
 '@S9S_MB_2U_LIB.S9S_MB_2U(SCH_1):PAGE261_I46@PURE_QUANTA.Q_RES(CHIPS)':
 'A': CDS_PINID='A';
NODE_NAME     PU43_P0_1 1
 '@S9S_MB_2U_LIB.S9S_MB_2U(SCH_1):PAGE261_I79@PURE_QUANTA.ISL99390FRZTR5935(CHIPS)':
 'VOS': CDS_PINID='VOS';
NET_NAME
'PVCCINFAON_CPU0_VOS2'
 '@S9S_MB_2U_LIB.S9S_MB_2U(SCH_1):PVCCINFAON_CPU0_VOS2':
 C_SIGNAL='@s9s_mb_2u_lib.s9s_mb_2u(sch_1):pvccinfaon_cpu0_vos2';
NODE_NAME     PU44_P0_2 1
 '@S9S_MB_2U_LIB.S9S_MB_2U(SCH_1):PAGE261_I12@PURE_QUANTA.ISL99390FRZTR5935(CHIPS)':
 'VOS': CDS_PINID='VOS';
NODE_NAME     PR1777 1
 '@S9S_MB_2U_LIB.S9S_MB_2U(SCH_1):PAGE261_I31@PURE_QUANTA.Q_RES(CHIPS)':
 'A': CDS_PINID='A';
NET_NAME
'PVCCINFAON_CPU0_VREF'
 '@S9S_MB_2U_LIB.S9S_MB_2U(SCH_1):PVCCINFAON_CPU0_VREF':
 C_SIGNAL='@s9s_mb_2u_lib.s9s_mb_2u(sch_1):pvccinfaon_cpu0_vref';
NODE_NAME     PU5 40
 '@S9S_MB_2U_LIB.S9S_MB_2U(SCH_1):PAGE260_I65@PURE_QUANTA.ISL69260IRAZT(CHIPS)':
 'VCCS': CDS_PINID='VCCS';
NODE_NAME     PU44_P0_2 39
 '@S9S_MB_2U_LIB.S9S_MB_2U(SCH_1):PAGE261_I12@PURE_QUANTA.ISL99390FRZTR5935(CHIPS)':
 'REFIN': CDS_PINID='REFIN';
NODE_NAME     PC1347 2
 '@S9S_MB_2U_LIB.S9S_MB_2U(SCH_1):PAGE261_I25@PURE_QUANTA.Q_CAP(CHIPS)':
 'B': CDS_PINID='B';
NODE_NAME     PU43_P0_1 39
 '@S9S_MB_2U_LIB.S9S_MB_2U(SCH_1):PAGE261_I79@PURE_QUANTA.ISL99390FRZTR5935(CHIPS)':
 'REFIN': CDS_PINID='REFIN';
NODE_NAME     PC224 1
 '@S9S_MB_2U_LIB.S9S_MB_2U(SCH_1):PAGE260_I92@PURE_QUANTA.Q_CAP(CHIPS)':
 'A': CDS_PINID='A';
NODE_NAME     PC1348 2
 '@S9S_MB_2U_LIB.S9S_MB_2U(SCH_1):PAGE262_I10@PURE_QUANTA.Q_CAP(CHIPS)':
 'B': CDS_PINID='B';
NODE_NAME     PU42 24
 '@S9S_MB_2U_LIB.S9S_MB_2U(SCH_1):PAGE262_I14@PURE_QUANTA.RAA2213404GNPHB0(CHIPS)':
 'REFIN': CDS_PINID='REFIN';
NODE_NAME     PC1346 2
 '@S9S_MB_2U_LIB.S9S_MB_2U(SCH_1):PAGE261_I11@PURE_QUANTA.Q_CAP(CHIPS)':
 'B': CDS_PINID='B';
NODE_NAME     PR105 1
 '@S9S_MB_2U_LIB.S9S_MB_2U(SCH_1):PAGE260_I7@PURE_QUANTA.Q_RES(CHIPS)':
 'A': CDS_PINID='A';
NODE_NAME     PC1372 1
 '@S9S_MB_2U_LIB.S9S_MB_2U(SCH_1):PAGE260_I95@PURE_QUANTA.Q_CAP(CHIPS)':
 'A': CDS_PINID='A';
NET_NAME
'PVCCINFAON_CPU0_VR_FAULT'
 '@S9S_MB_2U_LIB.S9S_MB_2U(SCH_1):PVCCINFAON_CPU0_VR_FAULT':
 C_SIGNAL='@s9s_mb_2u_lib.s9s_mb_2u(sch_1):pvccinfaon_cpu0_vr_fault';
NODE_NAME     PU5 33
 '@S9S_MB_2U_LIB.S9S_MB_2U(SCH_1):PAGE260_I65@PURE_QUANTA.ISL69260IRAZT(CHIPS)':
 'CFP': CDS_PINID='CFP';
NODE_NAME     R2392 2
 '@S9S_MB_2U_LIB.S9S_MB_2U(SCH_1):PAGE260_I18@PURE_QUANTA.Q_RES(CHIPS)':
 'B': CDS_PINID='B';
NET_NAME
'PVCCINFAON_CPU1'
 '@S9S_MB_2U_LIB.S9S_MB_2U(SCH_1):PVCCINFAON_CPU1':
 C_SIGNAL='@s9s_mb_2u_lib.s9s_mb_2u(sch_1):pvccinfaon_cpu1',
 CDS_GLOBAL_NET='TRUE';
NODE_NAME     U1 AY18
 '@S9S_MB_2U_LIB.S9S_MB_2U(SCH_1):PAGE68_I1@PURE_QUANTA.SOCKET4677_AZIF0045P001C01CS(CHIPS)':
 'VCCINFAON33': CDS_PINID='VCCINFAON33';
NODE_NAME     U1 BA15
 '@S9S_MB_2U_LIB.S9S_MB_2U(SCH_1):PAGE68_I1@PURE_QUANTA.SOCKET4677_AZIF0045P001C01CS(CHIPS)':
 'VCCINFAON34': CDS_PINID='VCCINFAON34';
NODE_NAME     U1 BC60
 '@S9S_MB_2U_LIB.S9S_MB_2U(SCH_1):PAGE68_I1@PURE_QUANTA.SOCKET4677_AZIF0045P001C01CS(CHIPS)':
 'VCCINFAON35': CDS_PINID='VCCINFAON35';
NODE_NAME     U1 BE15
 '@S9S_MB_2U_LIB.S9S_MB_2U(SCH_1):PAGE68_I1@PURE_QUANTA.SOCKET4677_AZIF0045P001C01CS(CHIPS)':
 'VCCINFAON36': CDS_PINID='VCCINFAON36';
NODE_NAME     U1 BE60
 '@S9S_MB_2U_LIB.S9S_MB_2U(SCH_1):PAGE68_I1@PURE_QUANTA.SOCKET4677_AZIF0045P001C01CS(CHIPS)':
 'VCCINFAON37': CDS_PINID='VCCINFAON37';
NODE_NAME     U1 BG60
 '@S9S_MB_2U_LIB.S9S_MB_2U(SCH_1):PAGE68_I1@PURE_QUANTA.SOCKET4677_AZIF0045P001C01CS(CHIPS)':
 'VCCINFAON38': CDS_PINID='VCCINFAON38';
NODE_NAME     U1 BJ15
 '@S9S_MB_2U_LIB.S9S_MB_2U(SCH_1):PAGE68_I1@PURE_QUANTA.SOCKET4677_AZIF0045P001C01CS(CHIPS)':
 'VCCINFAON39': CDS_PINID='VCCINFAON39';
NODE_NAME     U1 BJ60
 '@S9S_MB_2U_LIB.S9S_MB_2U(SCH_1):PAGE68_I1@PURE_QUANTA.SOCKET4677_AZIF0045P001C01CS(CHIPS)':
 'VCCINFAON40': CDS_PINID='VCCINFAON40';
NODE_NAME     U1 BK61
 '@S9S_MB_2U_LIB.S9S_MB_2U(SCH_1):PAGE68_I1@PURE_QUANTA.SOCKET4677_AZIF0045P001C01CS(CHIPS)':
 'VCCINFAON41': CDS_PINID='VCCINFAON41';
NODE_NAME     U1 BN15
 '@S9S_MB_2U_LIB.S9S_MB_2U(SCH_1):PAGE68_I1@PURE_QUANTA.SOCKET4677_AZIF0045P001C01CS(CHIPS)':
 'VCCINFAON42': CDS_PINID='VCCINFAON42';
NODE_NAME     U1 CA15
 '@S9S_MB_2U_LIB.S9S_MB_2U(SCH_1):PAGE68_I1@PURE_QUANTA.SOCKET4677_AZIF0045P001C01CS(CHIPS)':
 'VCCINFAON43': CDS_PINID='VCCINFAON43';
NODE_NAME     U1 CE19
 '@S9S_MB_2U_LIB.S9S_MB_2U(SCH_1):PAGE68_I1@PURE_QUANTA.SOCKET4677_AZIF0045P001C01CS(CHIPS)':
 'VCCINFAON44': CDS_PINID='VCCINFAON44';
NODE_NAME     U1 CJ11
 '@S9S_MB_2U_LIB.S9S_MB_2U(SCH_1):PAGE68_I1@PURE_QUANTA.SOCKET4677_AZIF0045P001C01CS(CHIPS)':
 'VCCINFAON45': CDS_PINID='VCCINFAON45';
NODE_NAME     U1 CJ19
 '@S9S_MB_2U_LIB.S9S_MB_2U(SCH_1):PAGE68_I1@PURE_QUANTA.SOCKET4677_AZIF0045P001C01CS(CHIPS)':
 'VCCINFAON46': CDS_PINID='VCCINFAON46';
NODE_NAME     U1 CN19
 '@S9S_MB_2U_LIB.S9S_MB_2U(SCH_1):PAGE68_I1@PURE_QUANTA.SOCKET4677_AZIF0045P001C01CS(CHIPS)':
 'VCCINFAON47': CDS_PINID='VCCINFAON47';
NODE_NAME     U1 CP63
 '@S9S_MB_2U_LIB.S9S_MB_2U(SCH_1):PAGE68_I1@PURE_QUANTA.SOCKET4677_AZIF0045P001C01CS(CHIPS)':
 'VCCINFAON48': CDS_PINID='VCCINFAON48';
NODE_NAME     U1 CT63
 '@S9S_MB_2U_LIB.S9S_MB_2U(SCH_1):PAGE68_I1@PURE_QUANTA.SOCKET4677_AZIF0045P001C01CS(CHIPS)':
 'VCCINFAON49': CDS_PINID='VCCINFAON49';
NODE_NAME     U1 CV61
 '@S9S_MB_2U_LIB.S9S_MB_2U(SCH_1):PAGE68_I1@PURE_QUANTA.SOCKET4677_AZIF0045P001C01CS(CHIPS)':
 'VCCINFAON50': CDS_PINID='VCCINFAON50';
NODE_NAME     U1 CV63
 '@S9S_MB_2U_LIB.S9S_MB_2U(SCH_1):PAGE68_I1@PURE_QUANTA.SOCKET4677_AZIF0045P001C01CS(CHIPS)':
 'VCCINFAON51': CDS_PINID='VCCINFAON51';
NODE_NAME     U1 CW62
 '@S9S_MB_2U_LIB.S9S_MB_2U(SCH_1):PAGE68_I1@PURE_QUANTA.SOCKET4677_AZIF0045P001C01CS(CHIPS)':
 'VCCINFAON52': CDS_PINID='VCCINFAON52';
NODE_NAME     U1 DA21
 '@S9S_MB_2U_LIB.S9S_MB_2U(SCH_1):PAGE68_I1@PURE_QUANTA.SOCKET4677_AZIF0045P001C01CS(CHIPS)':
 'VCCINFAON53': CDS_PINID='VCCINFAON53';
NODE_NAME     U1 CE15
 '@S9S_MB_2U_LIB.S9S_MB_2U(SCH_1):PAGE68_I8@PURE_QUANTA.SOCKET4677_AZIF0045P001C01CS(CHIPS)':
 'VCCINFAON0': CDS_PINID='VCCINFAON0';
NODE_NAME     U1 CJ15
 '@S9S_MB_2U_LIB.S9S_MB_2U(SCH_1):PAGE68_I8@PURE_QUANTA.SOCKET4677_AZIF0045P001C01CS(CHIPS)':
 'VCCINFAON1': CDS_PINID='VCCINFAON1';
NODE_NAME     U1 CJ3
 '@S9S_MB_2U_LIB.S9S_MB_2U(SCH_1):PAGE68_I8@PURE_QUANTA.SOCKET4677_AZIF0045P001C01CS(CHIPS)':
 'VCCINFAON2': CDS_PINID='VCCINFAON2';
NODE_NAME     U1 CJ7
 '@S9S_MB_2U_LIB.S9S_MB_2U(SCH_1):PAGE68_I8@PURE_QUANTA.SOCKET4677_AZIF0045P001C01CS(CHIPS)':
 'VCCINFAON3': CDS_PINID='VCCINFAON3';
NODE_NAME     U1 CN11
 '@S9S_MB_2U_LIB.S9S_MB_2U(SCH_1):PAGE68_I8@PURE_QUANTA.SOCKET4677_AZIF0045P001C01CS(CHIPS)':
 'VCCINFAON4': CDS_PINID='VCCINFAON4';
NODE_NAME     U1 CN15
 '@S9S_MB_2U_LIB.S9S_MB_2U(SCH_1):PAGE68_I8@PURE_QUANTA.SOCKET4677_AZIF0045P001C01CS(CHIPS)':
 'VCCINFAON5': CDS_PINID='VCCINFAON5';
NODE_NAME     U1 CN3
 '@S9S_MB_2U_LIB.S9S_MB_2U(SCH_1):PAGE68_I8@PURE_QUANTA.SOCKET4677_AZIF0045P001C01CS(CHIPS)':
 'VCCINFAON6': CDS_PINID='VCCINFAON6';
NODE_NAME     U1 CN64
 '@S9S_MB_2U_LIB.S9S_MB_2U(SCH_1):PAGE68_I8@PURE_QUANTA.SOCKET4677_AZIF0045P001C01CS(CHIPS)':
 'VCCINFAON7': CDS_PINID='VCCINFAON7';
NODE_NAME     U1 CN66
 '@S9S_MB_2U_LIB.S9S_MB_2U(SCH_1):PAGE68_I8@PURE_QUANTA.SOCKET4677_AZIF0045P001C01CS(CHIPS)':
 'VCCINFAON8': CDS_PINID='VCCINFAON8';
NODE_NAME     U1 CN7
 '@S9S_MB_2U_LIB.S9S_MB_2U(SCH_1):PAGE68_I8@PURE_QUANTA.SOCKET4677_AZIF0045P001C01CS(CHIPS)':
 'VCCINFAON9': CDS_PINID='VCCINFAON9';
NODE_NAME     U1 CP65
 '@S9S_MB_2U_LIB.S9S_MB_2U(SCH_1):PAGE68_I8@PURE_QUANTA.SOCKET4677_AZIF0045P001C01CS(CHIPS)':
 'VCCINFAON10': CDS_PINID='VCCINFAON10';
NODE_NAME     U1 CP67
 '@S9S_MB_2U_LIB.S9S_MB_2U(SCH_1):PAGE68_I8@PURE_QUANTA.SOCKET4677_AZIF0045P001C01CS(CHIPS)':
 'VCCINFAON11': CDS_PINID='VCCINFAON11';
NODE_NAME     U1 CT65
 '@S9S_MB_2U_LIB.S9S_MB_2U(SCH_1):PAGE68_I8@PURE_QUANTA.SOCKET4677_AZIF0045P001C01CS(CHIPS)':
 'VCCINFAON12': CDS_PINID='VCCINFAON12';
NODE_NAME     U1 CT67
 '@S9S_MB_2U_LIB.S9S_MB_2U(SCH_1):PAGE68_I8@PURE_QUANTA.SOCKET4677_AZIF0045P001C01CS(CHIPS)':
 'VCCINFAON13': CDS_PINID='VCCINFAON13';
NODE_NAME     U1 CU11
 '@S9S_MB_2U_LIB.S9S_MB_2U(SCH_1):PAGE68_I8@PURE_QUANTA.SOCKET4677_AZIF0045P001C01CS(CHIPS)':
 'VCCINFAON14': CDS_PINID='VCCINFAON14';
NODE_NAME     U1 CU15
 '@S9S_MB_2U_LIB.S9S_MB_2U(SCH_1):PAGE68_I8@PURE_QUANTA.SOCKET4677_AZIF0045P001C01CS(CHIPS)':
 'VCCINFAON15': CDS_PINID='VCCINFAON15';
NODE_NAME     U1 CU3
 '@S9S_MB_2U_LIB.S9S_MB_2U(SCH_1):PAGE68_I8@PURE_QUANTA.SOCKET4677_AZIF0045P001C01CS(CHIPS)':
 'VCCINFAON16': CDS_PINID='VCCINFAON16';
NODE_NAME     U1 CU64
 '@S9S_MB_2U_LIB.S9S_MB_2U(SCH_1):PAGE68_I8@PURE_QUANTA.SOCKET4677_AZIF0045P001C01CS(CHIPS)':
 'VCCINFAON17': CDS_PINID='VCCINFAON17';
NODE_NAME     U1 CU7
 '@S9S_MB_2U_LIB.S9S_MB_2U(SCH_1):PAGE68_I8@PURE_QUANTA.SOCKET4677_AZIF0045P001C01CS(CHIPS)':
 'VCCINFAON18': CDS_PINID='VCCINFAON18';
NODE_NAME     U1 CV65
 '@S9S_MB_2U_LIB.S9S_MB_2U(SCH_1):PAGE68_I8@PURE_QUANTA.SOCKET4677_AZIF0045P001C01CS(CHIPS)':
 'VCCINFAON19': CDS_PINID='VCCINFAON19';
NODE_NAME     U1 CV67
 '@S9S_MB_2U_LIB.S9S_MB_2U(SCH_1):PAGE68_I8@PURE_QUANTA.SOCKET4677_AZIF0045P001C01CS(CHIPS)':
 'VCCINFAON20': CDS_PINID='VCCINFAON20';
NODE_NAME     U1 CW66
 '@S9S_MB_2U_LIB.S9S_MB_2U(SCH_1):PAGE68_I8@PURE_QUANTA.SOCKET4677_AZIF0045P001C01CS(CHIPS)':
 'VCCINFAON21': CDS_PINID='VCCINFAON21';
NODE_NAME     U1 CY65
 '@S9S_MB_2U_LIB.S9S_MB_2U(SCH_1):PAGE68_I8@PURE_QUANTA.SOCKET4677_AZIF0045P001C01CS(CHIPS)':
 'VCCINFAON22': CDS_PINID='VCCINFAON22';
NODE_NAME     U1 CY67
 '@S9S_MB_2U_LIB.S9S_MB_2U(SCH_1):PAGE68_I8@PURE_QUANTA.SOCKET4677_AZIF0045P001C01CS(CHIPS)':
 'VCCINFAON23': CDS_PINID='VCCINFAON23';
NODE_NAME     U1 DA11
 '@S9S_MB_2U_LIB.S9S_MB_2U(SCH_1):PAGE68_I8@PURE_QUANTA.SOCKET4677_AZIF0045P001C01CS(CHIPS)':
 'VCCINFAON24': CDS_PINID='VCCINFAON24';
NODE_NAME     U1 DA15
 '@S9S_MB_2U_LIB.S9S_MB_2U(SCH_1):PAGE68_I8@PURE_QUANTA.SOCKET4677_AZIF0045P001C01CS(CHIPS)':
 'VCCINFAON25': CDS_PINID='VCCINFAON25';
NODE_NAME     U1 DA64
 '@S9S_MB_2U_LIB.S9S_MB_2U(SCH_1):PAGE68_I8@PURE_QUANTA.SOCKET4677_AZIF0045P001C01CS(CHIPS)':
 'VCCINFAON26': CDS_PINID='VCCINFAON26';
NODE_NAME     U1 DE11
 '@S9S_MB_2U_LIB.S9S_MB_2U(SCH_1):PAGE68_I8@PURE_QUANTA.SOCKET4677_AZIF0045P001C01CS(CHIPS)':
 'VCCINFAON27': CDS_PINID='VCCINFAON27';
NODE_NAME     U1 DE15
 '@S9S_MB_2U_LIB.S9S_MB_2U(SCH_1):PAGE68_I8@PURE_QUANTA.SOCKET4677_AZIF0045P001C01CS(CHIPS)':
 'VCCINFAON28': CDS_PINID='VCCINFAON28';
NODE_NAME     U1 DE3
 '@S9S_MB_2U_LIB.S9S_MB_2U(SCH_1):PAGE68_I8@PURE_QUANTA.SOCKET4677_AZIF0045P001C01CS(CHIPS)':
 'VCCINFAON29': CDS_PINID='VCCINFAON29';
NODE_NAME     U1 DJ15
 '@S9S_MB_2U_LIB.S9S_MB_2U(SCH_1):PAGE68_I8@PURE_QUANTA.SOCKET4677_AZIF0045P001C01CS(CHIPS)':
 'VCCINFAON30': CDS_PINID='VCCINFAON30';
NODE_NAME     U1 DJ3
 '@S9S_MB_2U_LIB.S9S_MB_2U(SCH_1):PAGE68_I8@PURE_QUANTA.SOCKET4677_AZIF0045P001C01CS(CHIPS)':
 'VCCINFAON31': CDS_PINID='VCCINFAON31';
NODE_NAME     U1 DJ7
 '@S9S_MB_2U_LIB.S9S_MB_2U(SCH_1):PAGE68_I8@PURE_QUANTA.SOCKET4677_AZIF0045P001C01CS(CHIPS)':
 'VCCINFAON32': CDS_PINID='VCCINFAON32';
NODE_NAME     U1 CR66
 '@S9S_MB_2U_LIB.S9S_MB_2U(SCH_1):PAGE68_I8@PURE_QUANTA.SOCKET4677_AZIF0045P001C01CS(CHIPS)':
 'VCCINFAON54': CDS_PINID='VCCINFAON54';
NODE_NAME     U1 CW64
 '@S9S_MB_2U_LIB.S9S_MB_2U(SCH_1):PAGE68_I8@PURE_QUANTA.SOCKET4677_AZIF0045P001C01CS(CHIPS)':
 'VCCINFAON55': CDS_PINID='VCCINFAON55';
NODE_NAME     U1 DA3
 '@S9S_MB_2U_LIB.S9S_MB_2U(SCH_1):PAGE68_I8@PURE_QUANTA.SOCKET4677_AZIF0045P001C01CS(CHIPS)':
 'VCCINFAON56': CDS_PINID='VCCINFAON56';
NODE_NAME     U1 DA7
 '@S9S_MB_2U_LIB.S9S_MB_2U(SCH_1):PAGE68_I8@PURE_QUANTA.SOCKET4677_AZIF0045P001C01CS(CHIPS)':
 'VCCINFAON57': CDS_PINID='VCCINFAON57';
NODE_NAME     U1 DE7
 '@S9S_MB_2U_LIB.S9S_MB_2U(SCH_1):PAGE68_I8@PURE_QUANTA.SOCKET4677_AZIF0045P001C01CS(CHIPS)':
 'VCCINFAON58': CDS_PINID='VCCINFAON58';
NODE_NAME     U1 DJ11
 '@S9S_MB_2U_LIB.S9S_MB_2U(SCH_1):PAGE68_I8@PURE_QUANTA.SOCKET4677_AZIF0045P001C01CS(CHIPS)':
 'VCCINFAON59': CDS_PINID='VCCINFAON59';
NODE_NAME     C432 1
 '@S9S_MB_2U_LIB.S9S_MB_2U(SCH_1):PAGE77_I42@PURE_QUANTA.Q_CAP(CHIPS)':
 'A': CDS_PINID='A';
NODE_NAME     C434 1
 '@S9S_MB_2U_LIB.S9S_MB_2U(SCH_1):PAGE77_I47@PURE_QUANTA.Q_CAP(CHIPS)':
 'A': CDS_PINID='A';
NODE_NAME     C436 1
 '@S9S_MB_2U_LIB.S9S_MB_2U(SCH_1):PAGE77_I49@PURE_QUANTA.Q_CAP(CHIPS)':
 'A': CDS_PINID='A';
NODE_NAME     C438 1
 '@S9S_MB_2U_LIB.S9S_MB_2U(SCH_1):PAGE77_I58@PURE_QUANTA.Q_CAP(CHIPS)':
 'A': CDS_PINID='A';
NODE_NAME     C440 1
 '@S9S_MB_2U_LIB.S9S_MB_2U(SCH_1):PAGE77_I61@PURE_QUANTA.Q_CAP(CHIPS)':
 'A': CDS_PINID='A';
NODE_NAME     C490 1
 '@S9S_MB_2U_LIB.S9S_MB_2U(SCH_1):PAGE78_I23@PURE_QUANTA.Q_CAP(CHIPS)':
 'A': CDS_PINID='A';
NODE_NAME     C487 1
 '@S9S_MB_2U_LIB.S9S_MB_2U(SCH_1):PAGE79_I10@PURE_QUANTA.Q_CAP(CHIPS)':
 'A': CDS_PINID='A';
NODE_NAME     C486 1
 '@S9S_MB_2U_LIB.S9S_MB_2U(SCH_1):PAGE79_I11@PURE_QUANTA.Q_CAP(CHIPS)':
 'A': CDS_PINID='A';
NODE_NAME     PC458_P1_2 1
 '@S9S_MB_2U_LIB.S9S_MB_2U(SCH_1):PAGE279_I33@PURE_QUANTA.Q_CAP(CHIPS)':
 'A': CDS_PINID='A';
NODE_NAME     PR4247 1
 '@S9S_MB_2U_LIB.S9S_MB_2U(SCH_1):PAGE279_I34@PURE_QUANTA.Q_RES(CHIPS)':
 'A': CDS_PINID='A';
NODE_NAME     PC1593 1
 '@S9S_MB_2U_LIB.S9S_MB_2U(SCH_1):PAGE279_I59@PURE_QUANTA.Q_CAPP(CHIPS)':
 'A': CDS_PINID='A';
NODE_NAME     PC1594 1
 '@S9S_MB_2U_LIB.S9S_MB_2U(SCH_1):PAGE279_I62@PURE_QUANTA.Q_CAPP(CHIPS)':
 'A': CDS_PINID='A';
NODE_NAME     C478 1
 '@S9S_MB_2U_LIB.S9S_MB_2U(SCH_1):PAGE78_I8@PURE_QUANTA.Q_CAP(CHIPS)':
 'A': CDS_PINID='A';
NODE_NAME     C488 1
 '@S9S_MB_2U_LIB.S9S_MB_2U(SCH_1):PAGE78_I18@PURE_QUANTA.Q_CAP(CHIPS)':
 'A': CDS_PINID='A';
NODE_NAME     C489 1
 '@S9S_MB_2U_LIB.S9S_MB_2U(SCH_1):PAGE78_I19@PURE_QUANTA.Q_CAP(CHIPS)':
 'A': CDS_PINID='A';
NODE_NAME     C484 1
 '@S9S_MB_2U_LIB.S9S_MB_2U(SCH_1):PAGE79_I12@PURE_QUANTA.Q_CAP(CHIPS)':
 'A': CDS_PINID='A';
NODE_NAME     C481 1
 '@S9S_MB_2U_LIB.S9S_MB_2U(SCH_1):PAGE79_I13@PURE_QUANTA.Q_CAP(CHIPS)':
 'A': CDS_PINID='A';
NODE_NAME     R329 1
 '@S9S_MB_2U_LIB.S9S_MB_2U(SCH_1):PAGE80_I35@PURE_QUANTA.Q_RES(CHIPS)':
 'A': CDS_PINID='A';
NODE_NAME     PR568 2
 '@S9S_MB_2U_LIB.S9S_MB_2U(SCH_1):PAGE278_I55@PURE_QUANTA.Q_RES(CHIPS)':
 'B': CDS_PINID='B';
NODE_NAME     PC456_P1_2 1
 '@S9S_MB_2U_LIB.S9S_MB_2U(SCH_1):PAGE279_I32@PURE_QUANTA.Q_CAP(CHIPS)':
 'A': CDS_PINID='A';
NODE_NAME     PL22 2
 '@S9S_MB_2U_LIB.S9S_MB_2U(SCH_1):PAGE279_I46@PURE_QUANTA.Q_INDUCTOR(CHIPS)':
 '2': CDS_PINID='\2\';
NODE_NAME     PC1595 1
 '@S9S_MB_2U_LIB.S9S_MB_2U(SCH_1):PAGE279_I60@PURE_QUANTA.Q_CAPP(CHIPS)':
 'A': CDS_PINID='A';
NODE_NAME     PC1588 1
 '@S9S_MB_2U_LIB.S9S_MB_2U(SCH_1):PAGE279_I61@PURE_QUANTA.Q_CAPP(CHIPS)':
 'A': CDS_PINID='A';
NODE_NAME     PC455_P1_1 1
 '@S9S_MB_2U_LIB.S9S_MB_2U(SCH_1):PAGE279_I63@PURE_QUANTA.Q_CAP(CHIPS)':
 'A': CDS_PINID='A';
NODE_NAME     PR1797 2
 '@S9S_MB_2U_LIB.S9S_MB_2U(SCH_1):PAGE279_I31@PURE_QUANTA.Q_RES(CHIPS)':
 'B': CDS_PINID='B';
NODE_NAME     PR1796 2
 '@S9S_MB_2U_LIB.S9S_MB_2U(SCH_1):PAGE279_I49@PURE_QUANTA.Q_RES(CHIPS)':
 'B': CDS_PINID='B';
NODE_NAME     PL21 2
 '@S9S_MB_2U_LIB.S9S_MB_2U(SCH_1):PAGE279_I54@PURE_QUANTA.Q_INDUCTOR(CHIPS)':
 '2': CDS_PINID='\2\';
NODE_NAME     PC452_P1_1 1
 '@S9S_MB_2U_LIB.S9S_MB_2U(SCH_1):PAGE279_I55@PURE_QUANTA.Q_CAP(CHIPS)':
 'A': CDS_PINID='A';
NODE_NAME     PC457_P1_1 1
 '@S9S_MB_2U_LIB.S9S_MB_2U(SCH_1):PAGE279_I65@PURE_QUANTA.Q_CAP(CHIPS)':
 'A': CDS_PINID='A';
NODE_NAME     PC1596 1
 '@S9S_MB_2U_LIB.S9S_MB_2U(SCH_1):PAGE279_I71@PURE_QUANTA.Q_CAPP(CHIPS)':
 'A': CDS_PINID='A';
NET_NAME
'PVCCINFAON_CPU1_ACSP1'
 '@S9S_MB_2U_LIB.S9S_MB_2U(SCH_1):PVCCINFAON_CPU1_ACSP1':
 C_SIGNAL='@s9s_mb_2u_lib.s9s_mb_2u(sch_1):pvccinfaon_cpu1_acsp1';
NODE_NAME     PU50_P1_1 38
 '@S9S_MB_2U_LIB.S9S_MB_2U(SCH_1):PAGE279_I38@PURE_QUANTA.ISL99390FRZTR5935(CHIPS)':
 'IOUT': CDS_PINID='IOUT';
NODE_NAME     PU22 23
 '@S9S_MB_2U_LIB.S9S_MB_2U(SCH_1):PAGE278_I38@PURE_QUANTA.ISL69260IRAZT(CHIPS)':
 'CS7': CDS_PINID='CS7';
NET_NAME
'PVCCINFAON_CPU1_ACSP2'
 '@S9S_MB_2U_LIB.S9S_MB_2U(SCH_1):PVCCINFAON_CPU1_ACSP2':
 C_SIGNAL='@s9s_mb_2u_lib.s9s_mb_2u(sch_1):pvccinfaon_cpu1_acsp2';
NODE_NAME     PU51_P1_2 38
 '@S9S_MB_2U_LIB.S9S_MB_2U(SCH_1):PAGE279_I29@PURE_QUANTA.ISL99390FRZTR5935(CHIPS)':
 'IOUT': CDS_PINID='IOUT';
NODE_NAME     PU22 24
 '@S9S_MB_2U_LIB.S9S_MB_2U(SCH_1):PAGE278_I38@PURE_QUANTA.ISL69260IRAZT(CHIPS)':
 'CS6': CDS_PINID='CS6';
NET_NAME
'PVCCINFAON_CPU1_ADDR'
 '@S9S_MB_2U_LIB.S9S_MB_2U(SCH_1):PVCCINFAON_CPU1_ADDR':
 C_SIGNAL='@s9s_mb_2u_lib.s9s_mb_2u(sch_1):pvccinfaon_cpu1_addr';
NODE_NAME     PR258 2
 '@S9S_MB_2U_LIB.S9S_MB_2U(SCH_1):PAGE278_I23@PURE_QUANTA.Q_RES(CHIPS)':
 'B': CDS_PINID='B';
NODE_NAME     PU22 34
 '@S9S_MB_2U_LIB.S9S_MB_2U(SCH_1):PAGE278_I38@PURE_QUANTA.ISL69260IRAZT(CHIPS)':
 'ADDR_CFG': CDS_PINID='ADDR_CFG';
NODE_NAME     PR259 1
 '@S9S_MB_2U_LIB.S9S_MB_2U(SCH_1):PAGE278_I110@PURE_QUANTA.Q_RES(CHIPS)':
 'A': CDS_PINID='A';
NET_NAME
'PVCCINFAON_CPU1_APWM1'
 '@S9S_MB_2U_LIB.S9S_MB_2U(SCH_1):PVCCINFAON_CPU1_APWM1':
 C_SIGNAL='@s9s_mb_2u_lib.s9s_mb_2u(sch_1):pvccinfaon_cpu1_apwm1';
NODE_NAME     PU50_P1_1 34
 '@S9S_MB_2U_LIB.S9S_MB_2U(SCH_1):PAGE279_I38@PURE_QUANTA.ISL99390FRZTR5935(CHIPS)':
 'PWM': CDS_PINID='PWM';
NODE_NAME     PU22 8
 '@S9S_MB_2U_LIB.S9S_MB_2U(SCH_1):PAGE278_I38@PURE_QUANTA.ISL69260IRAZT(CHIPS)':
 'PWM7': CDS_PINID='PWM7';
NET_NAME
'PVCCINFAON_CPU1_APWM2'
 '@S9S_MB_2U_LIB.S9S_MB_2U(SCH_1):PVCCINFAON_CPU1_APWM2':
 C_SIGNAL='@s9s_mb_2u_lib.s9s_mb_2u(sch_1):pvccinfaon_cpu1_apwm2';
NODE_NAME     PU51_P1_2 34
 '@S9S_MB_2U_LIB.S9S_MB_2U(SCH_1):PAGE279_I29@PURE_QUANTA.ISL99390FRZTR5935(CHIPS)':
 'PWM': CDS_PINID='PWM';
NODE_NAME     PU22 7
 '@S9S_MB_2U_LIB.S9S_MB_2U(SCH_1):PAGE278_I38@PURE_QUANTA.ISL69260IRAZT(CHIPS)':
 'PWM6': CDS_PINID='PWM6';
NET_NAME
'PVCCINFAON_CPU1_ATSEN'
 '@S9S_MB_2U_LIB.S9S_MB_2U(SCH_1):PVCCINFAON_CPU1_ATSEN':
 C_SIGNAL='@s9s_mb_2u_lib.s9s_mb_2u(sch_1):pvccinfaon_cpu1_atsen';
NODE_NAME     PU50_P1_1 36
 '@S9S_MB_2U_LIB.S9S_MB_2U(SCH_1):PAGE279_I38@PURE_QUANTA.ISL99390FRZTR5935(CHIPS)':
 'TOUT_FLT': CDS_PINID='TOUT_FLT';
NODE_NAME     PC475 1
 '@S9S_MB_2U_LIB.S9S_MB_2U(SCH_1):PAGE278_I66@PURE_QUANTA.Q_CAP(CHIPS)':
 'A': CDS_PINID='A';
NODE_NAME     PU51_P1_2 36
 '@S9S_MB_2U_LIB.S9S_MB_2U(SCH_1):PAGE279_I29@PURE_QUANTA.ISL99390FRZTR5935(CHIPS)':
 'TOUT_FLT': CDS_PINID='TOUT_FLT';
NODE_NAME     PU22 35
 '@S9S_MB_2U_LIB.S9S_MB_2U(SCH_1):PAGE278_I38@PURE_QUANTA.ISL69260IRAZT(CHIPS)':
 'TEMP0': CDS_PINID='TEMP0';
NODE_NAME     PR665 1
 '@S9S_MB_2U_LIB.S9S_MB_2U(SCH_1):PAGE278_I67@PURE_QUANTA.Q_RES(CHIPS)':
 'A': CDS_PINID='A';
NET_NAME
'PVCCINFAON_CPU1_CSPIN'
 '@S9S_MB_2U_LIB.S9S_MB_2U(SCH_1):PVCCINFAON_CPU1_CSPIN':
 C_SIGNAL='@s9s_mb_2u_lib.s9s_mb_2u(sch_1):pvccinfaon_cpu1_cspin';
NODE_NAME     PR260 2
 '@S9S_MB_2U_LIB.S9S_MB_2U(SCH_1):PAGE278_I22@PURE_QUANTA.Q_RES(CHIPS)':
 'B': CDS_PINID='B';
NODE_NAME     PR275 1
 '@S9S_MB_2U_LIB.S9S_MB_2U(SCH_1):PAGE278_I26@PURE_QUANTA.Q_RES(CHIPS)':
 'A': CDS_PINID='A';
NODE_NAME     PC467 1
 '@S9S_MB_2U_LIB.S9S_MB_2U(SCH_1):PAGE278_I28@PURE_QUANTA.Q_CAP(CHIPS)':
 'A': CDS_PINID='A';
NODE_NAME     PU22 37
 '@S9S_MB_2U_LIB.S9S_MB_2U(SCH_1):PAGE278_I38@PURE_QUANTA.ISL69260IRAZT(CHIPS)':
 'VMON||IINSEN||VSYS||ISYS': CDS_PINID='\vmon||iinsen||vsys||isys\';
NET_NAME
'PVCCINFAON_CPU1_EN_R'
 '@S9S_MB_2U_LIB.S9S_MB_2U(SCH_1):PVCCINFAON_CPU1_EN_R':
 C_SIGNAL='@s9s_mb_2u_lib.s9s_mb_2u(sch_1):pvccinfaon_cpu1_en_r';
NODE_NAME     PU22 13
 '@S9S_MB_2U_LIB.S9S_MB_2U(SCH_1):PAGE278_I38@PURE_QUANTA.ISL69260IRAZT(CHIPS)':
 'EN0': CDS_PINID='EN0';
NODE_NAME     C2451 1
 '@S9S_MB_2U_LIB.S9S_MB_2U(SCH_1):PAGE278_I63@PURE_QUANTA.Q_CAP(CHIPS)':
 'A': CDS_PINID='A';
NODE_NAME     R2558 2
 '@S9S_MB_2U_LIB.S9S_MB_2U(SCH_1):PAGE278_I104@PURE_QUANTA.Q_RES(CHIPS)':
 'B': CDS_PINID='B';
NET_NAME
'PVCCINFAON_CPU1_LSET1'
 '@S9S_MB_2U_LIB.S9S_MB_2U(SCH_1):PVCCINFAON_CPU1_LSET1':
 C_SIGNAL='@s9s_mb_2u_lib.s9s_mb_2u(sch_1):pvccinfaon_cpu1_lset1';
NODE_NAME     PU50_P1_1 37
 '@S9S_MB_2U_LIB.S9S_MB_2U(SCH_1):PAGE279_I38@PURE_QUANTA.ISL99390FRZTR5935(CHIPS)':
 'LSET': CDS_PINID='LSET';
NODE_NAME     PR1726 1
 '@S9S_MB_2U_LIB.S9S_MB_2U(SCH_1):PAGE279_I16@PURE_QUANTA.Q_RES(CHIPS)':
 'A': CDS_PINID='A';
NET_NAME
'PVCCINFAON_CPU1_LSET2'
 '@S9S_MB_2U_LIB.S9S_MB_2U(SCH_1):PVCCINFAON_CPU1_LSET2':
 C_SIGNAL='@s9s_mb_2u_lib.s9s_mb_2u(sch_1):pvccinfaon_cpu1_lset2';
NODE_NAME     PU51_P1_2 37
 '@S9S_MB_2U_LIB.S9S_MB_2U(SCH_1):PAGE279_I29@PURE_QUANTA.ISL99390FRZTR5935(CHIPS)':
 'LSET': CDS_PINID='LSET';
NODE_NAME     PR1727 1
 '@S9S_MB_2U_LIB.S9S_MB_2U(SCH_1):PAGE279_I3@PURE_QUANTA.Q_RES(CHIPS)':
 'A': CDS_PINID='A';
NET_NAME
'PVCCINFAON_CPU1_PIN_ALERT'
 '@S9S_MB_2U_LIB.S9S_MB_2U(SCH_1):PVCCINFAON_CPU1_PIN_ALERT':
 C_SIGNAL='@s9s_mb_2u_lib.s9s_mb_2u(sch_1):pvccinfaon_cpu1_pin_alert';
NODE_NAME     PU22 15
 '@S9S_MB_2U_LIB.S9S_MB_2U(SCH_1):PAGE278_I38@PURE_QUANTA.ISL69260IRAZT(CHIPS)':
 'NPINALERT#||NPSYSCRIT#': CDS_PINID='\npinalert#||npsyscrit#\';
NODE_NAME     R2569 2
 '@S9S_MB_2U_LIB.S9S_MB_2U(SCH_1):PAGE278_I49@PURE_QUANTA.Q_RES(CHIPS)':
 'B': CDS_PINID='B';
NET_NAME
'PVCCINFAON_CPU1_VCC'
 '@S9S_MB_2U_LIB.S9S_MB_2U(SCH_1):PVCCINFAON_CPU1_VCC':
 C_SIGNAL='@s9s_mb_2u_lib.s9s_mb_2u(sch_1):pvccinfaon_cpu1_vcc';
NODE_NAME     PC476 1
 '@S9S_MB_2U_LIB.S9S_MB_2U(SCH_1):PAGE278_I93@PURE_QUANTA.Q_CAP(CHIPS)':
 'A': CDS_PINID='A';
NODE_NAME     PC478 1
 '@S9S_MB_2U_LIB.S9S_MB_2U(SCH_1):PAGE278_I97@PURE_QUANTA.Q_CAP(CHIPS)':
 'A': CDS_PINID='A';
NODE_NAME     PU22 39
 '@S9S_MB_2U_LIB.S9S_MB_2U(SCH_1):PAGE278_I38@PURE_QUANTA.ISL69260IRAZT(CHIPS)':
 'VCC': CDS_PINID='VCC';
NODE_NAME     PR283 1
 '@S9S_MB_2U_LIB.S9S_MB_2U(SCH_1):PAGE278_I108@PURE_QUANTA.Q_RES(CHIPS)':
 'A': CDS_PINID='A';
NODE_NAME     PC2367 1
 '@S9S_MB_2U_LIB.S9S_MB_2U(SCH_1):PAGE278_I111@PURE_QUANTA.Q_CAP(CHIPS)':
 'A': CDS_PINID='A';
NET_NAME
'PVCCINFAON_CPU1_VDD1'
 '@S9S_MB_2U_LIB.S9S_MB_2U(SCH_1):PVCCINFAON_CPU1_VDD1':
 C_SIGNAL='@s9s_mb_2u_lib.s9s_mb_2u(sch_1):pvccinfaon_cpu1_vdd1';
NODE_NAME     PU50_P1_1 35
 '@S9S_MB_2U_LIB.S9S_MB_2U(SCH_1):PAGE279_I38@PURE_QUANTA.ISL99390FRZTR5935(CHIPS)':
 'EN': CDS_PINID='EN';
NODE_NAME     PU50_P1_1 3
 '@S9S_MB_2U_LIB.S9S_MB_2U(SCH_1):PAGE279_I38@PURE_QUANTA.ISL99390FRZTR5935(CHIPS)':
 'VCC': CDS_PINID='VCC';
NODE_NAME     PR254 2
 '@S9S_MB_2U_LIB.S9S_MB_2U(SCH_1):PAGE279_I25@PURE_QUANTA.Q_RES(CHIPS)':
 'B': CDS_PINID='B';
NODE_NAME     PC440 1
 '@S9S_MB_2U_LIB.S9S_MB_2U(SCH_1):PAGE279_I24@PURE_QUANTA.Q_CAP(CHIPS)':
 'A': CDS_PINID='A';
NET_NAME
'PVCCINFAON_CPU1_VDD2'
 '@S9S_MB_2U_LIB.S9S_MB_2U(SCH_1):PVCCINFAON_CPU1_VDD2':
 C_SIGNAL='@s9s_mb_2u_lib.s9s_mb_2u(sch_1):pvccinfaon_cpu1_vdd2';
NODE_NAME     PR255 2
 '@S9S_MB_2U_LIB.S9S_MB_2U(SCH_1):PAGE279_I11@PURE_QUANTA.Q_RES(CHIPS)':
 'B': CDS_PINID='B';
NODE_NAME     PU51_P1_2 35
 '@S9S_MB_2U_LIB.S9S_MB_2U(SCH_1):PAGE279_I29@PURE_QUANTA.ISL99390FRZTR5935(CHIPS)':
 'EN': CDS_PINID='EN';
NODE_NAME     PU51_P1_2 3
 '@S9S_MB_2U_LIB.S9S_MB_2U(SCH_1):PAGE279_I29@PURE_QUANTA.ISL99390FRZTR5935(CHIPS)':
 'VCC': CDS_PINID='VCC';
NODE_NAME     PC441 1
 '@S9S_MB_2U_LIB.S9S_MB_2U(SCH_1):PAGE279_I10@PURE_QUANTA.Q_CAP(CHIPS)':
 'A': CDS_PINID='A';
NET_NAME
'PVCCINFAON_CPU1_VIN_CSNIN'
 '@S9S_MB_2U_LIB.S9S_MB_2U(SCH_1):PVCCINFAON_CPU1_VIN_CSNIN':
 C_SIGNAL='@s9s_mb_2u_lib.s9s_mb_2u(sch_1):pvccinfaon_cpu1_vin_csnin';
NODE_NAME     PR261 2
 '@S9S_MB_2U_LIB.S9S_MB_2U(SCH_1):PAGE278_I21@PURE_QUANTA.Q_RES(CHIPS)':
 'B': CDS_PINID='B';
NODE_NAME     PR276 1
 '@S9S_MB_2U_LIB.S9S_MB_2U(SCH_1):PAGE278_I35@PURE_QUANTA.Q_RES(CHIPS)':
 'A': CDS_PINID='A';
NODE_NAME     PC474 1
 '@S9S_MB_2U_LIB.S9S_MB_2U(SCH_1):PAGE278_I36@PURE_QUANTA.Q_CAP(CHIPS)':
 'A': CDS_PINID='A';
NODE_NAME     PU22 38
 '@S9S_MB_2U_LIB.S9S_MB_2U(SCH_1):PAGE278_I38@PURE_QUANTA.ISL69260IRAZT(CHIPS)':
 'VINSEN||VSYS': CDS_PINID='\vinsen||vsys\';
NET_NAME
'PVCCINFAON_CPU1_VOS1'
 '@S9S_MB_2U_LIB.S9S_MB_2U(SCH_1):PVCCINFAON_CPU1_VOS1':
 C_SIGNAL='@s9s_mb_2u_lib.s9s_mb_2u(sch_1):pvccinfaon_cpu1_vos1';
NODE_NAME     PU50_P1_1 1
 '@S9S_MB_2U_LIB.S9S_MB_2U(SCH_1):PAGE279_I38@PURE_QUANTA.ISL99390FRZTR5935(CHIPS)':
 'VOS': CDS_PINID='VOS';
NODE_NAME     PR1796 1
 '@S9S_MB_2U_LIB.S9S_MB_2U(SCH_1):PAGE279_I49@PURE_QUANTA.Q_RES(CHIPS)':
 'A': CDS_PINID='A';
NET_NAME
'PVCCINFAON_CPU1_VOS2'
 '@S9S_MB_2U_LIB.S9S_MB_2U(SCH_1):PVCCINFAON_CPU1_VOS2':
 C_SIGNAL='@s9s_mb_2u_lib.s9s_mb_2u(sch_1):pvccinfaon_cpu1_vos2';
NODE_NAME     PU51_P1_2 1
 '@S9S_MB_2U_LIB.S9S_MB_2U(SCH_1):PAGE279_I29@PURE_QUANTA.ISL99390FRZTR5935(CHIPS)':
 'VOS': CDS_PINID='VOS';
NODE_NAME     PR1797 1
 '@S9S_MB_2U_LIB.S9S_MB_2U(SCH_1):PAGE279_I31@PURE_QUANTA.Q_RES(CHIPS)':
 'A': CDS_PINID='A';
NET_NAME
'PVCCINFAON_CPU1_VREF'
 '@S9S_MB_2U_LIB.S9S_MB_2U(SCH_1):PVCCINFAON_CPU1_VREF':
 C_SIGNAL='@s9s_mb_2u_lib.s9s_mb_2u(sch_1):pvccinfaon_cpu1_vref';
NODE_NAME     PU50_P1_1 39
 '@S9S_MB_2U_LIB.S9S_MB_2U(SCH_1):PAGE279_I38@PURE_QUANTA.ISL99390FRZTR5935(CHIPS)':
 'REFIN': CDS_PINID='REFIN';
NODE_NAME     PU49 24
 '@S9S_MB_2U_LIB.S9S_MB_2U(SCH_1):PAGE280_I14@PURE_QUANTA.RAA2213404GNPHB0(CHIPS)':
 'REFIN': CDS_PINID='REFIN';
NODE_NAME     PU51_P1_2 39
 '@S9S_MB_2U_LIB.S9S_MB_2U(SCH_1):PAGE279_I29@PURE_QUANTA.ISL99390FRZTR5935(CHIPS)':
 'REFIN': CDS_PINID='REFIN';
NODE_NAME     PC1366 2
 '@S9S_MB_2U_LIB.S9S_MB_2U(SCH_1):PAGE280_I9@PURE_QUANTA.Q_CAP(CHIPS)':
 'B': CDS_PINID='B';
NODE_NAME     PR258 1
 '@S9S_MB_2U_LIB.S9S_MB_2U(SCH_1):PAGE278_I23@PURE_QUANTA.Q_RES(CHIPS)':
 'A': CDS_PINID='A';
NODE_NAME     PU22 40
 '@S9S_MB_2U_LIB.S9S_MB_2U(SCH_1):PAGE278_I38@PURE_QUANTA.ISL69260IRAZT(CHIPS)':
 'VCCS': CDS_PINID='VCCS';
NODE_NAME     PC477 1
 '@S9S_MB_2U_LIB.S9S_MB_2U(SCH_1):PAGE278_I92@PURE_QUANTA.Q_CAP(CHIPS)':
 'A': CDS_PINID='A';
NODE_NAME     PC1193 1
 '@S9S_MB_2U_LIB.S9S_MB_2U(SCH_1):PAGE278_I96@PURE_QUANTA.Q_CAP(CHIPS)':
 'A': CDS_PINID='A';
NODE_NAME     PC1365 2
 '@S9S_MB_2U_LIB.S9S_MB_2U(SCH_1):PAGE279_I6@PURE_QUANTA.Q_CAP(CHIPS)':
 'B': CDS_PINID='B';
NODE_NAME     PC1364 2
 '@S9S_MB_2U_LIB.S9S_MB_2U(SCH_1):PAGE279_I20@PURE_QUANTA.Q_CAP(CHIPS)':
 'B': CDS_PINID='B';
NET_NAME
'PVCCINFAON_CPU1_VR_FAULT'
 '@S9S_MB_2U_LIB.S9S_MB_2U(SCH_1):PVCCINFAON_CPU1_VR_FAULT':
 C_SIGNAL='@s9s_mb_2u_lib.s9s_mb_2u(sch_1):pvccinfaon_cpu1_vr_fault';
NODE_NAME     PU22 33
 '@S9S_MB_2U_LIB.S9S_MB_2U(SCH_1):PAGE278_I38@PURE_QUANTA.ISL69260IRAZT(CHIPS)':
 'CFP': CDS_PINID='CFP';
NODE_NAME     R2568 2
 '@S9S_MB_2U_LIB.S9S_MB_2U(SCH_1):PAGE278_I50@PURE_QUANTA.Q_RES(CHIPS)':
 'B': CDS_PINID='B';
NET_NAME
'PVCCIN_CPU0'
 '@S9S_MB_2U_LIB.S9S_MB_2U(SCH_1):PVCCIN_CPU0':
 C_SIGNAL='@s9s_mb_2u_lib.s9s_mb_2u(sch_1):pvccin_cpu0',
 CDS_GLOBAL_NET='TRUE';
NODE_NAME     U2 BW80
 '@S9S_MB_2U_LIB.S9S_MB_2U(SCH_1):PAGE36_I1@PURE_QUANTA.SOCKET4677_AZIF0045P001C01CS(CHIPS)':
 'VCCIN190': CDS_PINID='VCCIN190';
NODE_NAME     U2 BW82
 '@S9S_MB_2U_LIB.S9S_MB_2U(SCH_1):PAGE36_I1@PURE_QUANTA.SOCKET4677_AZIF0045P001C01CS(CHIPS)':
 'VCCIN191': CDS_PINID='VCCIN191';
NODE_NAME     U2 BW84
 '@S9S_MB_2U_LIB.S9S_MB_2U(SCH_1):PAGE36_I1@PURE_QUANTA.SOCKET4677_AZIF0045P001C01CS(CHIPS)':
 'VCCIN192': CDS_PINID='VCCIN192';
NODE_NAME     U2 BW86
 '@S9S_MB_2U_LIB.S9S_MB_2U(SCH_1):PAGE36_I1@PURE_QUANTA.SOCKET4677_AZIF0045P001C01CS(CHIPS)':
 'VCCIN193': CDS_PINID='VCCIN193';
NODE_NAME     U2 BW88
 '@S9S_MB_2U_LIB.S9S_MB_2U(SCH_1):PAGE36_I1@PURE_QUANTA.SOCKET4677_AZIF0045P001C01CS(CHIPS)':
 'VCCIN194': CDS_PINID='VCCIN194';
NODE_NAME     U2 BW90
 '@S9S_MB_2U_LIB.S9S_MB_2U(SCH_1):PAGE36_I1@PURE_QUANTA.SOCKET4677_AZIF0045P001C01CS(CHIPS)':
 'VCCIN195': CDS_PINID='VCCIN195';
NODE_NAME     U2 BY32
 '@S9S_MB_2U_LIB.S9S_MB_2U(SCH_1):PAGE36_I1@PURE_QUANTA.SOCKET4677_AZIF0045P001C01CS(CHIPS)':
 'VCCIN196': CDS_PINID='VCCIN196';
NODE_NAME     U2 BY34
 '@S9S_MB_2U_LIB.S9S_MB_2U(SCH_1):PAGE36_I1@PURE_QUANTA.SOCKET4677_AZIF0045P001C01CS(CHIPS)':
 'VCCIN197': CDS_PINID='VCCIN197';
NODE_NAME     U2 BY36
 '@S9S_MB_2U_LIB.S9S_MB_2U(SCH_1):PAGE36_I1@PURE_QUANTA.SOCKET4677_AZIF0045P001C01CS(CHIPS)':
 'VCCIN198': CDS_PINID='VCCIN198';
NODE_NAME     U2 BY38
 '@S9S_MB_2U_LIB.S9S_MB_2U(SCH_1):PAGE36_I1@PURE_QUANTA.SOCKET4677_AZIF0045P001C01CS(CHIPS)':
 'VCCIN199': CDS_PINID='VCCIN199';
NODE_NAME     U2 BY40
 '@S9S_MB_2U_LIB.S9S_MB_2U(SCH_1):PAGE36_I1@PURE_QUANTA.SOCKET4677_AZIF0045P001C01CS(CHIPS)':
 'VCCIN200': CDS_PINID='VCCIN200';
NODE_NAME     U2 BY42
 '@S9S_MB_2U_LIB.S9S_MB_2U(SCH_1):PAGE36_I1@PURE_QUANTA.SOCKET4677_AZIF0045P001C01CS(CHIPS)':
 'VCCIN201': CDS_PINID='VCCIN201';
NODE_NAME     U2 BY44
 '@S9S_MB_2U_LIB.S9S_MB_2U(SCH_1):PAGE36_I1@PURE_QUANTA.SOCKET4677_AZIF0045P001C01CS(CHIPS)':
 'VCCIN202': CDS_PINID='VCCIN202';
NODE_NAME     U2 BY47
 '@S9S_MB_2U_LIB.S9S_MB_2U(SCH_1):PAGE36_I1@PURE_QUANTA.SOCKET4677_AZIF0045P001C01CS(CHIPS)':
 'VCCIN203': CDS_PINID='VCCIN203';
NODE_NAME     U2 BY49
 '@S9S_MB_2U_LIB.S9S_MB_2U(SCH_1):PAGE36_I1@PURE_QUANTA.SOCKET4677_AZIF0045P001C01CS(CHIPS)':
 'VCCIN204': CDS_PINID='VCCIN204';
NODE_NAME     U2 BY51
 '@S9S_MB_2U_LIB.S9S_MB_2U(SCH_1):PAGE36_I1@PURE_QUANTA.SOCKET4677_AZIF0045P001C01CS(CHIPS)':
 'VCCIN205': CDS_PINID='VCCIN205';
NODE_NAME     U2 BY53
 '@S9S_MB_2U_LIB.S9S_MB_2U(SCH_1):PAGE36_I1@PURE_QUANTA.SOCKET4677_AZIF0045P001C01CS(CHIPS)':
 'VCCIN206': CDS_PINID='VCCIN206';
NODE_NAME     U2 BY55
 '@S9S_MB_2U_LIB.S9S_MB_2U(SCH_1):PAGE36_I1@PURE_QUANTA.SOCKET4677_AZIF0045P001C01CS(CHIPS)':
 'VCCIN207': CDS_PINID='VCCIN207';
NODE_NAME     U2 BY57
 '@S9S_MB_2U_LIB.S9S_MB_2U(SCH_1):PAGE36_I1@PURE_QUANTA.SOCKET4677_AZIF0045P001C01CS(CHIPS)':
 'VCCIN208': CDS_PINID='VCCIN208';
NODE_NAME     U2 BY59
 '@S9S_MB_2U_LIB.S9S_MB_2U(SCH_1):PAGE36_I1@PURE_QUANTA.SOCKET4677_AZIF0045P001C01CS(CHIPS)':
 'VCCIN209': CDS_PINID='VCCIN209';
NODE_NAME     U2 BY61
 '@S9S_MB_2U_LIB.S9S_MB_2U(SCH_1):PAGE36_I1@PURE_QUANTA.SOCKET4677_AZIF0045P001C01CS(CHIPS)':
 'VCCIN210': CDS_PINID='VCCIN210';
NODE_NAME     U2 BY63
 '@S9S_MB_2U_LIB.S9S_MB_2U(SCH_1):PAGE36_I1@PURE_QUANTA.SOCKET4677_AZIF0045P001C01CS(CHIPS)':
 'VCCIN211': CDS_PINID='VCCIN211';
NODE_NAME     U2 BY65
 '@S9S_MB_2U_LIB.S9S_MB_2U(SCH_1):PAGE36_I1@PURE_QUANTA.SOCKET4677_AZIF0045P001C01CS(CHIPS)':
 'VCCIN212': CDS_PINID='VCCIN212';
NODE_NAME     U2 BY67
 '@S9S_MB_2U_LIB.S9S_MB_2U(SCH_1):PAGE36_I1@PURE_QUANTA.SOCKET4677_AZIF0045P001C01CS(CHIPS)':
 'VCCIN213': CDS_PINID='VCCIN213';
NODE_NAME     U2 BY69
 '@S9S_MB_2U_LIB.S9S_MB_2U(SCH_1):PAGE36_I1@PURE_QUANTA.SOCKET4677_AZIF0045P001C01CS(CHIPS)':
 'VCCIN214': CDS_PINID='VCCIN214';
NODE_NAME     U2 BY71
 '@S9S_MB_2U_LIB.S9S_MB_2U(SCH_1):PAGE36_I1@PURE_QUANTA.SOCKET4677_AZIF0045P001C01CS(CHIPS)':
 'VCCIN215': CDS_PINID='VCCIN215';
NODE_NAME     U2 BY73
 '@S9S_MB_2U_LIB.S9S_MB_2U(SCH_1):PAGE36_I1@PURE_QUANTA.SOCKET4677_AZIF0045P001C01CS(CHIPS)':
 'VCCIN216': CDS_PINID='VCCIN216';
NODE_NAME     U2 BY75
 '@S9S_MB_2U_LIB.S9S_MB_2U(SCH_1):PAGE36_I1@PURE_QUANTA.SOCKET4677_AZIF0045P001C01CS(CHIPS)':
 'VCCIN217': CDS_PINID='VCCIN217';
NODE_NAME     U2 BY77
 '@S9S_MB_2U_LIB.S9S_MB_2U(SCH_1):PAGE36_I1@PURE_QUANTA.SOCKET4677_AZIF0045P001C01CS(CHIPS)':
 'VCCIN218': CDS_PINID='VCCIN218';
NODE_NAME     U2 BY79
 '@S9S_MB_2U_LIB.S9S_MB_2U(SCH_1):PAGE36_I1@PURE_QUANTA.SOCKET4677_AZIF0045P001C01CS(CHIPS)':
 'VCCIN219': CDS_PINID='VCCIN219';
NODE_NAME     U2 BY81
 '@S9S_MB_2U_LIB.S9S_MB_2U(SCH_1):PAGE36_I1@PURE_QUANTA.SOCKET4677_AZIF0045P001C01CS(CHIPS)':
 'VCCIN220': CDS_PINID='VCCIN220';
NODE_NAME     U2 BY83
 '@S9S_MB_2U_LIB.S9S_MB_2U(SCH_1):PAGE36_I1@PURE_QUANTA.SOCKET4677_AZIF0045P001C01CS(CHIPS)':
 'VCCIN221': CDS_PINID='VCCIN221';
NODE_NAME     U2 BY85
 '@S9S_MB_2U_LIB.S9S_MB_2U(SCH_1):PAGE36_I1@PURE_QUANTA.SOCKET4677_AZIF0045P001C01CS(CHIPS)':
 'VCCIN222': CDS_PINID='VCCIN222';
NODE_NAME     U2 BY87
 '@S9S_MB_2U_LIB.S9S_MB_2U(SCH_1):PAGE36_I1@PURE_QUANTA.SOCKET4677_AZIF0045P001C01CS(CHIPS)':
 'VCCIN223': CDS_PINID='VCCIN223';
NODE_NAME     U2 BY89
 '@S9S_MB_2U_LIB.S9S_MB_2U(SCH_1):PAGE36_I1@PURE_QUANTA.SOCKET4677_AZIF0045P001C01CS(CHIPS)':
 'VCCIN224': CDS_PINID='VCCIN224';
NODE_NAME     U2 CA33
 '@S9S_MB_2U_LIB.S9S_MB_2U(SCH_1):PAGE36_I1@PURE_QUANTA.SOCKET4677_AZIF0045P001C01CS(CHIPS)':
 'VCCIN225': CDS_PINID='VCCIN225';
NODE_NAME     U2 CA35
 '@S9S_MB_2U_LIB.S9S_MB_2U(SCH_1):PAGE36_I1@PURE_QUANTA.SOCKET4677_AZIF0045P001C01CS(CHIPS)':
 'VCCIN226': CDS_PINID='VCCIN226';
NODE_NAME     U2 CA37
 '@S9S_MB_2U_LIB.S9S_MB_2U(SCH_1):PAGE36_I1@PURE_QUANTA.SOCKET4677_AZIF0045P001C01CS(CHIPS)':
 'VCCIN227': CDS_PINID='VCCIN227';
NODE_NAME     U2 CA39
 '@S9S_MB_2U_LIB.S9S_MB_2U(SCH_1):PAGE36_I1@PURE_QUANTA.SOCKET4677_AZIF0045P001C01CS(CHIPS)':
 'VCCIN228': CDS_PINID='VCCIN228';
NODE_NAME     U2 CA41
 '@S9S_MB_2U_LIB.S9S_MB_2U(SCH_1):PAGE36_I1@PURE_QUANTA.SOCKET4677_AZIF0045P001C01CS(CHIPS)':
 'VCCIN229': CDS_PINID='VCCIN229';
NODE_NAME     U2 CA43
 '@S9S_MB_2U_LIB.S9S_MB_2U(SCH_1):PAGE36_I1@PURE_QUANTA.SOCKET4677_AZIF0045P001C01CS(CHIPS)':
 'VCCIN230': CDS_PINID='VCCIN230';
NODE_NAME     U2 CA45
 '@S9S_MB_2U_LIB.S9S_MB_2U(SCH_1):PAGE36_I1@PURE_QUANTA.SOCKET4677_AZIF0045P001C01CS(CHIPS)':
 'VCCIN231': CDS_PINID='VCCIN231';
NODE_NAME     U2 CA48
 '@S9S_MB_2U_LIB.S9S_MB_2U(SCH_1):PAGE36_I1@PURE_QUANTA.SOCKET4677_AZIF0045P001C01CS(CHIPS)':
 'VCCIN232': CDS_PINID='VCCIN232';
NODE_NAME     U2 CA50
 '@S9S_MB_2U_LIB.S9S_MB_2U(SCH_1):PAGE36_I1@PURE_QUANTA.SOCKET4677_AZIF0045P001C01CS(CHIPS)':
 'VCCIN233': CDS_PINID='VCCIN233';
NODE_NAME     U2 CA52
 '@S9S_MB_2U_LIB.S9S_MB_2U(SCH_1):PAGE36_I1@PURE_QUANTA.SOCKET4677_AZIF0045P001C01CS(CHIPS)':
 'VCCIN234': CDS_PINID='VCCIN234';
NODE_NAME     U2 CA54
 '@S9S_MB_2U_LIB.S9S_MB_2U(SCH_1):PAGE36_I1@PURE_QUANTA.SOCKET4677_AZIF0045P001C01CS(CHIPS)':
 'VCCIN235': CDS_PINID='VCCIN235';
NODE_NAME     U2 CA56
 '@S9S_MB_2U_LIB.S9S_MB_2U(SCH_1):PAGE36_I1@PURE_QUANTA.SOCKET4677_AZIF0045P001C01CS(CHIPS)':
 'VCCIN236': CDS_PINID='VCCIN236';
NODE_NAME     U2 CA58
 '@S9S_MB_2U_LIB.S9S_MB_2U(SCH_1):PAGE36_I1@PURE_QUANTA.SOCKET4677_AZIF0045P001C01CS(CHIPS)':
 'VCCIN237': CDS_PINID='VCCIN237';
NODE_NAME     U2 CA60
 '@S9S_MB_2U_LIB.S9S_MB_2U(SCH_1):PAGE36_I1@PURE_QUANTA.SOCKET4677_AZIF0045P001C01CS(CHIPS)':
 'VCCIN238': CDS_PINID='VCCIN238';
NODE_NAME     U2 CA62
 '@S9S_MB_2U_LIB.S9S_MB_2U(SCH_1):PAGE36_I1@PURE_QUANTA.SOCKET4677_AZIF0045P001C01CS(CHIPS)':
 'VCCIN239': CDS_PINID='VCCIN239';
NODE_NAME     U2 CA64
 '@S9S_MB_2U_LIB.S9S_MB_2U(SCH_1):PAGE36_I1@PURE_QUANTA.SOCKET4677_AZIF0045P001C01CS(CHIPS)':
 'VCCIN240': CDS_PINID='VCCIN240';
NODE_NAME     U2 CA66
 '@S9S_MB_2U_LIB.S9S_MB_2U(SCH_1):PAGE36_I1@PURE_QUANTA.SOCKET4677_AZIF0045P001C01CS(CHIPS)':
 'VCCIN241': CDS_PINID='VCCIN241';
NODE_NAME     U2 CA68
 '@S9S_MB_2U_LIB.S9S_MB_2U(SCH_1):PAGE36_I1@PURE_QUANTA.SOCKET4677_AZIF0045P001C01CS(CHIPS)':
 'VCCIN242': CDS_PINID='VCCIN242';
NODE_NAME     U2 CA70
 '@S9S_MB_2U_LIB.S9S_MB_2U(SCH_1):PAGE36_I1@PURE_QUANTA.SOCKET4677_AZIF0045P001C01CS(CHIPS)':
 'VCCIN243': CDS_PINID='VCCIN243';
NODE_NAME     U2 CA72
 '@S9S_MB_2U_LIB.S9S_MB_2U(SCH_1):PAGE36_I1@PURE_QUANTA.SOCKET4677_AZIF0045P001C01CS(CHIPS)':
 'VCCIN244': CDS_PINID='VCCIN244';
NODE_NAME     U2 CA74
 '@S9S_MB_2U_LIB.S9S_MB_2U(SCH_1):PAGE36_I1@PURE_QUANTA.SOCKET4677_AZIF0045P001C01CS(CHIPS)':
 'VCCIN245': CDS_PINID='VCCIN245';
NODE_NAME     U2 CA76
 '@S9S_MB_2U_LIB.S9S_MB_2U(SCH_1):PAGE36_I1@PURE_QUANTA.SOCKET4677_AZIF0045P001C01CS(CHIPS)':
 'VCCIN246': CDS_PINID='VCCIN246';
NODE_NAME     U2 CA78
 '@S9S_MB_2U_LIB.S9S_MB_2U(SCH_1):PAGE36_I1@PURE_QUANTA.SOCKET4677_AZIF0045P001C01CS(CHIPS)':
 'VCCIN247': CDS_PINID='VCCIN247';
NODE_NAME     U2 CA80
 '@S9S_MB_2U_LIB.S9S_MB_2U(SCH_1):PAGE36_I1@PURE_QUANTA.SOCKET4677_AZIF0045P001C01CS(CHIPS)':
 'VCCIN248': CDS_PINID='VCCIN248';
NODE_NAME     U2 CA82
 '@S9S_MB_2U_LIB.S9S_MB_2U(SCH_1):PAGE36_I1@PURE_QUANTA.SOCKET4677_AZIF0045P001C01CS(CHIPS)':
 'VCCIN249': CDS_PINID='VCCIN249';
NODE_NAME     U2 CA84
 '@S9S_MB_2U_LIB.S9S_MB_2U(SCH_1):PAGE36_I1@PURE_QUANTA.SOCKET4677_AZIF0045P001C01CS(CHIPS)':
 'VCCIN250': CDS_PINID='VCCIN250';
NODE_NAME     U2 CA86
 '@S9S_MB_2U_LIB.S9S_MB_2U(SCH_1):PAGE36_I1@PURE_QUANTA.SOCKET4677_AZIF0045P001C01CS(CHIPS)':
 'VCCIN251': CDS_PINID='VCCIN251';
NODE_NAME     U2 CA88
 '@S9S_MB_2U_LIB.S9S_MB_2U(SCH_1):PAGE36_I1@PURE_QUANTA.SOCKET4677_AZIF0045P001C01CS(CHIPS)':
 'VCCIN252': CDS_PINID='VCCIN252';
NODE_NAME     U2 CA90
 '@S9S_MB_2U_LIB.S9S_MB_2U(SCH_1):PAGE36_I1@PURE_QUANTA.SOCKET4677_AZIF0045P001C01CS(CHIPS)':
 'VCCIN253': CDS_PINID='VCCIN253';
NODE_NAME     U2 CB61
 '@S9S_MB_2U_LIB.S9S_MB_2U(SCH_1):PAGE36_I1@PURE_QUANTA.SOCKET4677_AZIF0045P001C01CS(CHIPS)':
 'VCCIN254': CDS_PINID='VCCIN254';
NODE_NAME     U2 CB75
 '@S9S_MB_2U_LIB.S9S_MB_2U(SCH_1):PAGE36_I1@PURE_QUANTA.SOCKET4677_AZIF0045P001C01CS(CHIPS)':
 'VCCIN255': CDS_PINID='VCCIN255';
NODE_NAME     U2 CB77
 '@S9S_MB_2U_LIB.S9S_MB_2U(SCH_1):PAGE36_I1@PURE_QUANTA.SOCKET4677_AZIF0045P001C01CS(CHIPS)':
 'VCCIN256': CDS_PINID='VCCIN256';
NODE_NAME     U2 CC33
 '@S9S_MB_2U_LIB.S9S_MB_2U(SCH_1):PAGE36_I1@PURE_QUANTA.SOCKET4677_AZIF0045P001C01CS(CHIPS)':
 'VCCIN257': CDS_PINID='VCCIN257';
NODE_NAME     U2 CC35
 '@S9S_MB_2U_LIB.S9S_MB_2U(SCH_1):PAGE36_I1@PURE_QUANTA.SOCKET4677_AZIF0045P001C01CS(CHIPS)':
 'VCCIN258': CDS_PINID='VCCIN258';
NODE_NAME     U2 CC37
 '@S9S_MB_2U_LIB.S9S_MB_2U(SCH_1):PAGE36_I1@PURE_QUANTA.SOCKET4677_AZIF0045P001C01CS(CHIPS)':
 'VCCIN259': CDS_PINID='VCCIN259';
NODE_NAME     U2 CC39
 '@S9S_MB_2U_LIB.S9S_MB_2U(SCH_1):PAGE36_I1@PURE_QUANTA.SOCKET4677_AZIF0045P001C01CS(CHIPS)':
 'VCCIN260': CDS_PINID='VCCIN260';
NODE_NAME     U2 CC41
 '@S9S_MB_2U_LIB.S9S_MB_2U(SCH_1):PAGE36_I1@PURE_QUANTA.SOCKET4677_AZIF0045P001C01CS(CHIPS)':
 'VCCIN261': CDS_PINID='VCCIN261';
NODE_NAME     U2 CC43
 '@S9S_MB_2U_LIB.S9S_MB_2U(SCH_1):PAGE36_I1@PURE_QUANTA.SOCKET4677_AZIF0045P001C01CS(CHIPS)':
 'VCCIN262': CDS_PINID='VCCIN262';
NODE_NAME     U2 CC45
 '@S9S_MB_2U_LIB.S9S_MB_2U(SCH_1):PAGE36_I1@PURE_QUANTA.SOCKET4677_AZIF0045P001C01CS(CHIPS)':
 'VCCIN263': CDS_PINID='VCCIN263';
NODE_NAME     U2 CC48
 '@S9S_MB_2U_LIB.S9S_MB_2U(SCH_1):PAGE36_I1@PURE_QUANTA.SOCKET4677_AZIF0045P001C01CS(CHIPS)':
 'VCCIN264': CDS_PINID='VCCIN264';
NODE_NAME     U2 CC50
 '@S9S_MB_2U_LIB.S9S_MB_2U(SCH_1):PAGE36_I1@PURE_QUANTA.SOCKET4677_AZIF0045P001C01CS(CHIPS)':
 'VCCIN265': CDS_PINID='VCCIN265';
NODE_NAME     U2 CC52
 '@S9S_MB_2U_LIB.S9S_MB_2U(SCH_1):PAGE36_I1@PURE_QUANTA.SOCKET4677_AZIF0045P001C01CS(CHIPS)':
 'VCCIN266': CDS_PINID='VCCIN266';
NODE_NAME     U2 CC54
 '@S9S_MB_2U_LIB.S9S_MB_2U(SCH_1):PAGE36_I1@PURE_QUANTA.SOCKET4677_AZIF0045P001C01CS(CHIPS)':
 'VCCIN267': CDS_PINID='VCCIN267';
NODE_NAME     U2 CC56
 '@S9S_MB_2U_LIB.S9S_MB_2U(SCH_1):PAGE36_I1@PURE_QUANTA.SOCKET4677_AZIF0045P001C01CS(CHIPS)':
 'VCCIN268': CDS_PINID='VCCIN268';
NODE_NAME     U2 CC58
 '@S9S_MB_2U_LIB.S9S_MB_2U(SCH_1):PAGE36_I1@PURE_QUANTA.SOCKET4677_AZIF0045P001C01CS(CHIPS)':
 'VCCIN269': CDS_PINID='VCCIN269';
NODE_NAME     U2 CC60
 '@S9S_MB_2U_LIB.S9S_MB_2U(SCH_1):PAGE36_I1@PURE_QUANTA.SOCKET4677_AZIF0045P001C01CS(CHIPS)':
 'VCCIN270': CDS_PINID='VCCIN270';
NODE_NAME     U2 CC76
 '@S9S_MB_2U_LIB.S9S_MB_2U(SCH_1):PAGE36_I1@PURE_QUANTA.SOCKET4677_AZIF0045P001C01CS(CHIPS)':
 'VCCIN271': CDS_PINID='VCCIN271';
NODE_NAME     U2 CC78
 '@S9S_MB_2U_LIB.S9S_MB_2U(SCH_1):PAGE36_I1@PURE_QUANTA.SOCKET4677_AZIF0045P001C01CS(CHIPS)':
 'VCCIN272': CDS_PINID='VCCIN272';
NODE_NAME     U2 CC80
 '@S9S_MB_2U_LIB.S9S_MB_2U(SCH_1):PAGE36_I1@PURE_QUANTA.SOCKET4677_AZIF0045P001C01CS(CHIPS)':
 'VCCIN273': CDS_PINID='VCCIN273';
NODE_NAME     U2 CC82
 '@S9S_MB_2U_LIB.S9S_MB_2U(SCH_1):PAGE36_I1@PURE_QUANTA.SOCKET4677_AZIF0045P001C01CS(CHIPS)':
 'VCCIN274': CDS_PINID='VCCIN274';
NODE_NAME     U2 CC84
 '@S9S_MB_2U_LIB.S9S_MB_2U(SCH_1):PAGE36_I1@PURE_QUANTA.SOCKET4677_AZIF0045P001C01CS(CHIPS)':
 'VCCIN275': CDS_PINID='VCCIN275';
NODE_NAME     U2 CC86
 '@S9S_MB_2U_LIB.S9S_MB_2U(SCH_1):PAGE36_I1@PURE_QUANTA.SOCKET4677_AZIF0045P001C01CS(CHIPS)':
 'VCCIN276': CDS_PINID='VCCIN276';
NODE_NAME     U2 CC88
 '@S9S_MB_2U_LIB.S9S_MB_2U(SCH_1):PAGE36_I1@PURE_QUANTA.SOCKET4677_AZIF0045P001C01CS(CHIPS)':
 'VCCIN277': CDS_PINID='VCCIN277';
NODE_NAME     U2 CC90
 '@S9S_MB_2U_LIB.S9S_MB_2U(SCH_1):PAGE36_I1@PURE_QUANTA.SOCKET4677_AZIF0045P001C01CS(CHIPS)':
 'VCCIN278': CDS_PINID='VCCIN278';
NODE_NAME     U2 CD32
 '@S9S_MB_2U_LIB.S9S_MB_2U(SCH_1):PAGE36_I1@PURE_QUANTA.SOCKET4677_AZIF0045P001C01CS(CHIPS)':
 'VCCIN279': CDS_PINID='VCCIN279';
NODE_NAME     U2 CD34
 '@S9S_MB_2U_LIB.S9S_MB_2U(SCH_1):PAGE36_I1@PURE_QUANTA.SOCKET4677_AZIF0045P001C01CS(CHIPS)':
 'VCCIN280': CDS_PINID='VCCIN280';
NODE_NAME     U2 CD36
 '@S9S_MB_2U_LIB.S9S_MB_2U(SCH_1):PAGE36_I1@PURE_QUANTA.SOCKET4677_AZIF0045P001C01CS(CHIPS)':
 'VCCIN281': CDS_PINID='VCCIN281';
NODE_NAME     U2 CD38
 '@S9S_MB_2U_LIB.S9S_MB_2U(SCH_1):PAGE36_I1@PURE_QUANTA.SOCKET4677_AZIF0045P001C01CS(CHIPS)':
 'VCCIN282': CDS_PINID='VCCIN282';
NODE_NAME     U2 CD40
 '@S9S_MB_2U_LIB.S9S_MB_2U(SCH_1):PAGE36_I1@PURE_QUANTA.SOCKET4677_AZIF0045P001C01CS(CHIPS)':
 'VCCIN283': CDS_PINID='VCCIN283';
NODE_NAME     U2 CD42
 '@S9S_MB_2U_LIB.S9S_MB_2U(SCH_1):PAGE36_I1@PURE_QUANTA.SOCKET4677_AZIF0045P001C01CS(CHIPS)':
 'VCCIN284': CDS_PINID='VCCIN284';
NODE_NAME     U2 CD44
 '@S9S_MB_2U_LIB.S9S_MB_2U(SCH_1):PAGE36_I1@PURE_QUANTA.SOCKET4677_AZIF0045P001C01CS(CHIPS)':
 'VCCIN285': CDS_PINID='VCCIN285';
NODE_NAME     U2 CD47
 '@S9S_MB_2U_LIB.S9S_MB_2U(SCH_1):PAGE36_I1@PURE_QUANTA.SOCKET4677_AZIF0045P001C01CS(CHIPS)':
 'VCCIN286': CDS_PINID='VCCIN286';
NODE_NAME     U2 CD49
 '@S9S_MB_2U_LIB.S9S_MB_2U(SCH_1):PAGE36_I1@PURE_QUANTA.SOCKET4677_AZIF0045P001C01CS(CHIPS)':
 'VCCIN287': CDS_PINID='VCCIN287';
NODE_NAME     U2 CD51
 '@S9S_MB_2U_LIB.S9S_MB_2U(SCH_1):PAGE36_I1@PURE_QUANTA.SOCKET4677_AZIF0045P001C01CS(CHIPS)':
 'VCCIN288': CDS_PINID='VCCIN288';
NODE_NAME     U2 CD53
 '@S9S_MB_2U_LIB.S9S_MB_2U(SCH_1):PAGE36_I1@PURE_QUANTA.SOCKET4677_AZIF0045P001C01CS(CHIPS)':
 'VCCIN289': CDS_PINID='VCCIN289';
NODE_NAME     U2 CD55
 '@S9S_MB_2U_LIB.S9S_MB_2U(SCH_1):PAGE36_I1@PURE_QUANTA.SOCKET4677_AZIF0045P001C01CS(CHIPS)':
 'VCCIN290': CDS_PINID='VCCIN290';
NODE_NAME     U2 CD57
 '@S9S_MB_2U_LIB.S9S_MB_2U(SCH_1):PAGE36_I1@PURE_QUANTA.SOCKET4677_AZIF0045P001C01CS(CHIPS)':
 'VCCIN291': CDS_PINID='VCCIN291';
NODE_NAME     U2 CD59
 '@S9S_MB_2U_LIB.S9S_MB_2U(SCH_1):PAGE36_I1@PURE_QUANTA.SOCKET4677_AZIF0045P001C01CS(CHIPS)':
 'VCCIN292': CDS_PINID='VCCIN292';
NODE_NAME     U2 CD79
 '@S9S_MB_2U_LIB.S9S_MB_2U(SCH_1):PAGE36_I1@PURE_QUANTA.SOCKET4677_AZIF0045P001C01CS(CHIPS)':
 'VCCIN293': CDS_PINID='VCCIN293';
NODE_NAME     U2 CD81
 '@S9S_MB_2U_LIB.S9S_MB_2U(SCH_1):PAGE36_I1@PURE_QUANTA.SOCKET4677_AZIF0045P001C01CS(CHIPS)':
 'VCCIN294': CDS_PINID='VCCIN294';
NODE_NAME     U2 CD83
 '@S9S_MB_2U_LIB.S9S_MB_2U(SCH_1):PAGE36_I1@PURE_QUANTA.SOCKET4677_AZIF0045P001C01CS(CHIPS)':
 'VCCIN295': CDS_PINID='VCCIN295';
NODE_NAME     U2 CD85
 '@S9S_MB_2U_LIB.S9S_MB_2U(SCH_1):PAGE36_I1@PURE_QUANTA.SOCKET4677_AZIF0045P001C01CS(CHIPS)':
 'VCCIN296': CDS_PINID='VCCIN296';
NODE_NAME     U2 CD87
 '@S9S_MB_2U_LIB.S9S_MB_2U(SCH_1):PAGE36_I1@PURE_QUANTA.SOCKET4677_AZIF0045P001C01CS(CHIPS)':
 'VCCIN297': CDS_PINID='VCCIN297';
NODE_NAME     U2 CD89
 '@S9S_MB_2U_LIB.S9S_MB_2U(SCH_1):PAGE36_I1@PURE_QUANTA.SOCKET4677_AZIF0045P001C01CS(CHIPS)':
 'VCCIN298': CDS_PINID='VCCIN298';
NODE_NAME     U2 CE80
 '@S9S_MB_2U_LIB.S9S_MB_2U(SCH_1):PAGE36_I1@PURE_QUANTA.SOCKET4677_AZIF0045P001C01CS(CHIPS)':
 'VCCIN299': CDS_PINID='VCCIN299';
NODE_NAME     U2 CE82
 '@S9S_MB_2U_LIB.S9S_MB_2U(SCH_1):PAGE36_I1@PURE_QUANTA.SOCKET4677_AZIF0045P001C01CS(CHIPS)':
 'VCCIN300': CDS_PINID='VCCIN300';
NODE_NAME     U2 CE84
 '@S9S_MB_2U_LIB.S9S_MB_2U(SCH_1):PAGE36_I1@PURE_QUANTA.SOCKET4677_AZIF0045P001C01CS(CHIPS)':
 'VCCIN301': CDS_PINID='VCCIN301';
NODE_NAME     U2 CE86
 '@S9S_MB_2U_LIB.S9S_MB_2U(SCH_1):PAGE36_I1@PURE_QUANTA.SOCKET4677_AZIF0045P001C01CS(CHIPS)':
 'VCCIN302': CDS_PINID='VCCIN302';
NODE_NAME     U2 CE88
 '@S9S_MB_2U_LIB.S9S_MB_2U(SCH_1):PAGE36_I1@PURE_QUANTA.SOCKET4677_AZIF0045P001C01CS(CHIPS)':
 'VCCIN303': CDS_PINID='VCCIN303';
NODE_NAME     U2 CE90
 '@S9S_MB_2U_LIB.S9S_MB_2U(SCH_1):PAGE36_I1@PURE_QUANTA.SOCKET4677_AZIF0045P001C01CS(CHIPS)':
 'VCCIN304': CDS_PINID='VCCIN304';
NODE_NAME     U2 CF79
 '@S9S_MB_2U_LIB.S9S_MB_2U(SCH_1):PAGE36_I1@PURE_QUANTA.SOCKET4677_AZIF0045P001C01CS(CHIPS)':
 'VCCIN305': CDS_PINID='VCCIN305';
NODE_NAME     U2 CF81
 '@S9S_MB_2U_LIB.S9S_MB_2U(SCH_1):PAGE36_I1@PURE_QUANTA.SOCKET4677_AZIF0045P001C01CS(CHIPS)':
 'VCCIN306': CDS_PINID='VCCIN306';
NODE_NAME     U2 CF83
 '@S9S_MB_2U_LIB.S9S_MB_2U(SCH_1):PAGE36_I1@PURE_QUANTA.SOCKET4677_AZIF0045P001C01CS(CHIPS)':
 'VCCIN307': CDS_PINID='VCCIN307';
NODE_NAME     U2 CF85
 '@S9S_MB_2U_LIB.S9S_MB_2U(SCH_1):PAGE36_I1@PURE_QUANTA.SOCKET4677_AZIF0045P001C01CS(CHIPS)':
 'VCCIN308': CDS_PINID='VCCIN308';
NODE_NAME     U2 CF87
 '@S9S_MB_2U_LIB.S9S_MB_2U(SCH_1):PAGE36_I1@PURE_QUANTA.SOCKET4677_AZIF0045P001C01CS(CHIPS)':
 'VCCIN309': CDS_PINID='VCCIN309';
NODE_NAME     U2 CF89
 '@S9S_MB_2U_LIB.S9S_MB_2U(SCH_1):PAGE36_I1@PURE_QUANTA.SOCKET4677_AZIF0045P001C01CS(CHIPS)':
 'VCCIN310': CDS_PINID='VCCIN310';
NODE_NAME     U2 CF91
 '@S9S_MB_2U_LIB.S9S_MB_2U(SCH_1):PAGE36_I1@PURE_QUANTA.SOCKET4677_AZIF0045P001C01CS(CHIPS)':
 'VCCIN311': CDS_PINID='VCCIN311';
NODE_NAME     U2 CG80
 '@S9S_MB_2U_LIB.S9S_MB_2U(SCH_1):PAGE36_I1@PURE_QUANTA.SOCKET4677_AZIF0045P001C01CS(CHIPS)':
 'VCCIN312': CDS_PINID='VCCIN312';
NODE_NAME     U2 CG82
 '@S9S_MB_2U_LIB.S9S_MB_2U(SCH_1):PAGE36_I1@PURE_QUANTA.SOCKET4677_AZIF0045P001C01CS(CHIPS)':
 'VCCIN313': CDS_PINID='VCCIN313';
NODE_NAME     U2 CG84
 '@S9S_MB_2U_LIB.S9S_MB_2U(SCH_1):PAGE36_I1@PURE_QUANTA.SOCKET4677_AZIF0045P001C01CS(CHIPS)':
 'VCCIN314': CDS_PINID='VCCIN314';
NODE_NAME     U2 CG86
 '@S9S_MB_2U_LIB.S9S_MB_2U(SCH_1):PAGE36_I1@PURE_QUANTA.SOCKET4677_AZIF0045P001C01CS(CHIPS)':
 'VCCIN315': CDS_PINID='VCCIN315';
NODE_NAME     U2 CG88
 '@S9S_MB_2U_LIB.S9S_MB_2U(SCH_1):PAGE36_I1@PURE_QUANTA.SOCKET4677_AZIF0045P001C01CS(CHIPS)':
 'VCCIN316': CDS_PINID='VCCIN316';
NODE_NAME     U2 CG90
 '@S9S_MB_2U_LIB.S9S_MB_2U(SCH_1):PAGE36_I1@PURE_QUANTA.SOCKET4677_AZIF0045P001C01CS(CHIPS)':
 'VCCIN317': CDS_PINID='VCCIN317';
NODE_NAME     U2 CH81
 '@S9S_MB_2U_LIB.S9S_MB_2U(SCH_1):PAGE36_I1@PURE_QUANTA.SOCKET4677_AZIF0045P001C01CS(CHIPS)':
 'VCCIN318': CDS_PINID='VCCIN318';
NODE_NAME     U2 CH91
 '@S9S_MB_2U_LIB.S9S_MB_2U(SCH_1):PAGE36_I1@PURE_QUANTA.SOCKET4677_AZIF0045P001C01CS(CHIPS)':
 'VCCIN319': CDS_PINID='VCCIN319';
NODE_NAME     U2 CJ82
 '@S9S_MB_2U_LIB.S9S_MB_2U(SCH_1):PAGE36_I1@PURE_QUANTA.SOCKET4677_AZIF0045P001C01CS(CHIPS)':
 'VCCIN320': CDS_PINID='VCCIN320';
NODE_NAME     U2 CJ84
 '@S9S_MB_2U_LIB.S9S_MB_2U(SCH_1):PAGE36_I1@PURE_QUANTA.SOCKET4677_AZIF0045P001C01CS(CHIPS)':
 'VCCIN321': CDS_PINID='VCCIN321';
NODE_NAME     U2 CJ86
 '@S9S_MB_2U_LIB.S9S_MB_2U(SCH_1):PAGE36_I1@PURE_QUANTA.SOCKET4677_AZIF0045P001C01CS(CHIPS)':
 'VCCIN322': CDS_PINID='VCCIN322';
NODE_NAME     U2 CJ88
 '@S9S_MB_2U_LIB.S9S_MB_2U(SCH_1):PAGE36_I1@PURE_QUANTA.SOCKET4677_AZIF0045P001C01CS(CHIPS)':
 'VCCIN323': CDS_PINID='VCCIN323';
NODE_NAME     U2 CJ90
 '@S9S_MB_2U_LIB.S9S_MB_2U(SCH_1):PAGE36_I1@PURE_QUANTA.SOCKET4677_AZIF0045P001C01CS(CHIPS)':
 'VCCIN324': CDS_PINID='VCCIN324';
NODE_NAME     U2 CK83
 '@S9S_MB_2U_LIB.S9S_MB_2U(SCH_1):PAGE36_I1@PURE_QUANTA.SOCKET4677_AZIF0045P001C01CS(CHIPS)':
 'VCCIN325': CDS_PINID='VCCIN325';
NODE_NAME     U2 CK85
 '@S9S_MB_2U_LIB.S9S_MB_2U(SCH_1):PAGE36_I1@PURE_QUANTA.SOCKET4677_AZIF0045P001C01CS(CHIPS)':
 'VCCIN326': CDS_PINID='VCCIN326';
NODE_NAME     U2 CK87
 '@S9S_MB_2U_LIB.S9S_MB_2U(SCH_1):PAGE36_I1@PURE_QUANTA.SOCKET4677_AZIF0045P001C01CS(CHIPS)':
 'VCCIN327': CDS_PINID='VCCIN327';
NODE_NAME     U2 CK89
 '@S9S_MB_2U_LIB.S9S_MB_2U(SCH_1):PAGE36_I1@PURE_QUANTA.SOCKET4677_AZIF0045P001C01CS(CHIPS)':
 'VCCIN328': CDS_PINID='VCCIN328';
NODE_NAME     U2 CK91
 '@S9S_MB_2U_LIB.S9S_MB_2U(SCH_1):PAGE36_I1@PURE_QUANTA.SOCKET4677_AZIF0045P001C01CS(CHIPS)':
 'VCCIN329': CDS_PINID='VCCIN329';
NODE_NAME     U2 CL84
 '@S9S_MB_2U_LIB.S9S_MB_2U(SCH_1):PAGE36_I1@PURE_QUANTA.SOCKET4677_AZIF0045P001C01CS(CHIPS)':
 'VCCIN330': CDS_PINID='VCCIN330';
NODE_NAME     U2 CL86
 '@S9S_MB_2U_LIB.S9S_MB_2U(SCH_1):PAGE36_I1@PURE_QUANTA.SOCKET4677_AZIF0045P001C01CS(CHIPS)':
 'VCCIN331': CDS_PINID='VCCIN331';
NODE_NAME     U2 CL88
 '@S9S_MB_2U_LIB.S9S_MB_2U(SCH_1):PAGE36_I1@PURE_QUANTA.SOCKET4677_AZIF0045P001C01CS(CHIPS)':
 'VCCIN332': CDS_PINID='VCCIN332';
NODE_NAME     U2 CL90
 '@S9S_MB_2U_LIB.S9S_MB_2U(SCH_1):PAGE36_I1@PURE_QUANTA.SOCKET4677_AZIF0045P001C01CS(CHIPS)':
 'VCCIN333': CDS_PINID='VCCIN333';
NODE_NAME     U2 CM87
 '@S9S_MB_2U_LIB.S9S_MB_2U(SCH_1):PAGE36_I1@PURE_QUANTA.SOCKET4677_AZIF0045P001C01CS(CHIPS)':
 'VCCIN334': CDS_PINID='VCCIN334';
NODE_NAME     U2 CM91
 '@S9S_MB_2U_LIB.S9S_MB_2U(SCH_1):PAGE36_I1@PURE_QUANTA.SOCKET4677_AZIF0045P001C01CS(CHIPS)':
 'VCCIN335': CDS_PINID='VCCIN335';
NODE_NAME     U2 CN88
 '@S9S_MB_2U_LIB.S9S_MB_2U(SCH_1):PAGE36_I1@PURE_QUANTA.SOCKET4677_AZIF0045P001C01CS(CHIPS)':
 'VCCIN336': CDS_PINID='VCCIN336';
NODE_NAME     U2 CN90
 '@S9S_MB_2U_LIB.S9S_MB_2U(SCH_1):PAGE36_I1@PURE_QUANTA.SOCKET4677_AZIF0045P001C01CS(CHIPS)':
 'VCCIN337': CDS_PINID='VCCIN337';
NODE_NAME     U2 CP89
 '@S9S_MB_2U_LIB.S9S_MB_2U(SCH_1):PAGE36_I1@PURE_QUANTA.SOCKET4677_AZIF0045P001C01CS(CHIPS)':
 'VCCIN338': CDS_PINID='VCCIN338';
NODE_NAME     U2 CM89
 '@S9S_MB_2U_LIB.S9S_MB_2U(SCH_1):PAGE36_I1@PURE_QUANTA.SOCKET4677_AZIF0045P001C01CS(CHIPS)':
 'VCCIN339': CDS_PINID='VCCIN339';
NODE_NAME     U2 BN43
 '@S9S_MB_2U_LIB.S9S_MB_2U(SCH_1):PAGE36_I7@PURE_QUANTA.SOCKET4677_AZIF0045P001C01CS(CHIPS)':
 'VCCIN40': CDS_PINID='VCCIN40';
NODE_NAME     U2 BN45
 '@S9S_MB_2U_LIB.S9S_MB_2U(SCH_1):PAGE36_I7@PURE_QUANTA.SOCKET4677_AZIF0045P001C01CS(CHIPS)':
 'VCCIN41': CDS_PINID='VCCIN41';
NODE_NAME     U2 BN48
 '@S9S_MB_2U_LIB.S9S_MB_2U(SCH_1):PAGE36_I7@PURE_QUANTA.SOCKET4677_AZIF0045P001C01CS(CHIPS)':
 'VCCIN42': CDS_PINID='VCCIN42';
NODE_NAME     U2 BN50
 '@S9S_MB_2U_LIB.S9S_MB_2U(SCH_1):PAGE36_I7@PURE_QUANTA.SOCKET4677_AZIF0045P001C01CS(CHIPS)':
 'VCCIN43': CDS_PINID='VCCIN43';
NODE_NAME     U2 BN52
 '@S9S_MB_2U_LIB.S9S_MB_2U(SCH_1):PAGE36_I7@PURE_QUANTA.SOCKET4677_AZIF0045P001C01CS(CHIPS)':
 'VCCIN44': CDS_PINID='VCCIN44';
NODE_NAME     U2 BN54
 '@S9S_MB_2U_LIB.S9S_MB_2U(SCH_1):PAGE36_I7@PURE_QUANTA.SOCKET4677_AZIF0045P001C01CS(CHIPS)':
 'VCCIN45': CDS_PINID='VCCIN45';
NODE_NAME     U2 BN56
 '@S9S_MB_2U_LIB.S9S_MB_2U(SCH_1):PAGE36_I7@PURE_QUANTA.SOCKET4677_AZIF0045P001C01CS(CHIPS)':
 'VCCIN46': CDS_PINID='VCCIN46';
NODE_NAME     U2 BN58
 '@S9S_MB_2U_LIB.S9S_MB_2U(SCH_1):PAGE36_I7@PURE_QUANTA.SOCKET4677_AZIF0045P001C01CS(CHIPS)':
 'VCCIN47': CDS_PINID='VCCIN47';
NODE_NAME     U2 BN60
 '@S9S_MB_2U_LIB.S9S_MB_2U(SCH_1):PAGE36_I7@PURE_QUANTA.SOCKET4677_AZIF0045P001C01CS(CHIPS)':
 'VCCIN48': CDS_PINID='VCCIN48';
NODE_NAME     U2 BN78
 '@S9S_MB_2U_LIB.S9S_MB_2U(SCH_1):PAGE36_I7@PURE_QUANTA.SOCKET4677_AZIF0045P001C01CS(CHIPS)':
 'VCCIN49': CDS_PINID='VCCIN49';
NODE_NAME     U2 BN80
 '@S9S_MB_2U_LIB.S9S_MB_2U(SCH_1):PAGE36_I7@PURE_QUANTA.SOCKET4677_AZIF0045P001C01CS(CHIPS)':
 'VCCIN50': CDS_PINID='VCCIN50';
NODE_NAME     U2 BN82
 '@S9S_MB_2U_LIB.S9S_MB_2U(SCH_1):PAGE36_I7@PURE_QUANTA.SOCKET4677_AZIF0045P001C01CS(CHIPS)':
 'VCCIN51': CDS_PINID='VCCIN51';
NODE_NAME     U2 BN84
 '@S9S_MB_2U_LIB.S9S_MB_2U(SCH_1):PAGE36_I7@PURE_QUANTA.SOCKET4677_AZIF0045P001C01CS(CHIPS)':
 'VCCIN52': CDS_PINID='VCCIN52';
NODE_NAME     U2 BN86
 '@S9S_MB_2U_LIB.S9S_MB_2U(SCH_1):PAGE36_I7@PURE_QUANTA.SOCKET4677_AZIF0045P001C01CS(CHIPS)':
 'VCCIN53': CDS_PINID='VCCIN53';
NODE_NAME     U2 BN88
 '@S9S_MB_2U_LIB.S9S_MB_2U(SCH_1):PAGE36_I7@PURE_QUANTA.SOCKET4677_AZIF0045P001C01CS(CHIPS)':
 'VCCIN54': CDS_PINID='VCCIN54';
NODE_NAME     U2 BN90
 '@S9S_MB_2U_LIB.S9S_MB_2U(SCH_1):PAGE36_I7@PURE_QUANTA.SOCKET4677_AZIF0045P001C01CS(CHIPS)':
 'VCCIN55': CDS_PINID='VCCIN55';
NODE_NAME     U2 BP32
 '@S9S_MB_2U_LIB.S9S_MB_2U(SCH_1):PAGE36_I7@PURE_QUANTA.SOCKET4677_AZIF0045P001C01CS(CHIPS)':
 'VCCIN56': CDS_PINID='VCCIN56';
NODE_NAME     U2 BP34
 '@S9S_MB_2U_LIB.S9S_MB_2U(SCH_1):PAGE36_I7@PURE_QUANTA.SOCKET4677_AZIF0045P001C01CS(CHIPS)':
 'VCCIN57': CDS_PINID='VCCIN57';
NODE_NAME     U2 BP36
 '@S9S_MB_2U_LIB.S9S_MB_2U(SCH_1):PAGE36_I7@PURE_QUANTA.SOCKET4677_AZIF0045P001C01CS(CHIPS)':
 'VCCIN58': CDS_PINID='VCCIN58';
NODE_NAME     U2 BP38
 '@S9S_MB_2U_LIB.S9S_MB_2U(SCH_1):PAGE36_I7@PURE_QUANTA.SOCKET4677_AZIF0045P001C01CS(CHIPS)':
 'VCCIN59': CDS_PINID='VCCIN59';
NODE_NAME     U2 BP40
 '@S9S_MB_2U_LIB.S9S_MB_2U(SCH_1):PAGE36_I7@PURE_QUANTA.SOCKET4677_AZIF0045P001C01CS(CHIPS)':
 'VCCIN60': CDS_PINID='VCCIN60';
NODE_NAME     U2 BP42
 '@S9S_MB_2U_LIB.S9S_MB_2U(SCH_1):PAGE36_I7@PURE_QUANTA.SOCKET4677_AZIF0045P001C01CS(CHIPS)':
 'VCCIN61': CDS_PINID='VCCIN61';
NODE_NAME     U2 BP44
 '@S9S_MB_2U_LIB.S9S_MB_2U(SCH_1):PAGE36_I7@PURE_QUANTA.SOCKET4677_AZIF0045P001C01CS(CHIPS)':
 'VCCIN62': CDS_PINID='VCCIN62';
NODE_NAME     U2 BP47
 '@S9S_MB_2U_LIB.S9S_MB_2U(SCH_1):PAGE36_I7@PURE_QUANTA.SOCKET4677_AZIF0045P001C01CS(CHIPS)':
 'VCCIN63': CDS_PINID='VCCIN63';
NODE_NAME     U2 BP49
 '@S9S_MB_2U_LIB.S9S_MB_2U(SCH_1):PAGE36_I7@PURE_QUANTA.SOCKET4677_AZIF0045P001C01CS(CHIPS)':
 'VCCIN64': CDS_PINID='VCCIN64';
NODE_NAME     U2 BP51
 '@S9S_MB_2U_LIB.S9S_MB_2U(SCH_1):PAGE36_I7@PURE_QUANTA.SOCKET4677_AZIF0045P001C01CS(CHIPS)':
 'VCCIN65': CDS_PINID='VCCIN65';
NODE_NAME     U2 BP53
 '@S9S_MB_2U_LIB.S9S_MB_2U(SCH_1):PAGE36_I7@PURE_QUANTA.SOCKET4677_AZIF0045P001C01CS(CHIPS)':
 'VCCIN66': CDS_PINID='VCCIN66';
NODE_NAME     U2 BP55
 '@S9S_MB_2U_LIB.S9S_MB_2U(SCH_1):PAGE36_I7@PURE_QUANTA.SOCKET4677_AZIF0045P001C01CS(CHIPS)':
 'VCCIN67': CDS_PINID='VCCIN67';
NODE_NAME     U2 BP57
 '@S9S_MB_2U_LIB.S9S_MB_2U(SCH_1):PAGE36_I7@PURE_QUANTA.SOCKET4677_AZIF0045P001C01CS(CHIPS)':
 'VCCIN68': CDS_PINID='VCCIN68';
NODE_NAME     U2 BP59
 '@S9S_MB_2U_LIB.S9S_MB_2U(SCH_1):PAGE36_I7@PURE_QUANTA.SOCKET4677_AZIF0045P001C01CS(CHIPS)':
 'VCCIN69': CDS_PINID='VCCIN69';
NODE_NAME     U2 BP61
 '@S9S_MB_2U_LIB.S9S_MB_2U(SCH_1):PAGE36_I7@PURE_QUANTA.SOCKET4677_AZIF0045P001C01CS(CHIPS)':
 'VCCIN70': CDS_PINID='VCCIN70';
NODE_NAME     U2 BP79
 '@S9S_MB_2U_LIB.S9S_MB_2U(SCH_1):PAGE36_I7@PURE_QUANTA.SOCKET4677_AZIF0045P001C01CS(CHIPS)':
 'VCCIN71': CDS_PINID='VCCIN71';
NODE_NAME     U2 BP81
 '@S9S_MB_2U_LIB.S9S_MB_2U(SCH_1):PAGE36_I7@PURE_QUANTA.SOCKET4677_AZIF0045P001C01CS(CHIPS)':
 'VCCIN72': CDS_PINID='VCCIN72';
NODE_NAME     U2 BP83
 '@S9S_MB_2U_LIB.S9S_MB_2U(SCH_1):PAGE36_I7@PURE_QUANTA.SOCKET4677_AZIF0045P001C01CS(CHIPS)':
 'VCCIN73': CDS_PINID='VCCIN73';
NODE_NAME     U2 BP85
 '@S9S_MB_2U_LIB.S9S_MB_2U(SCH_1):PAGE36_I7@PURE_QUANTA.SOCKET4677_AZIF0045P001C01CS(CHIPS)':
 'VCCIN74': CDS_PINID='VCCIN74';
NODE_NAME     U2 BP87
 '@S9S_MB_2U_LIB.S9S_MB_2U(SCH_1):PAGE36_I7@PURE_QUANTA.SOCKET4677_AZIF0045P001C01CS(CHIPS)':
 'VCCIN75': CDS_PINID='VCCIN75';
NODE_NAME     U2 BP89
 '@S9S_MB_2U_LIB.S9S_MB_2U(SCH_1):PAGE36_I7@PURE_QUANTA.SOCKET4677_AZIF0045P001C01CS(CHIPS)':
 'VCCIN76': CDS_PINID='VCCIN76';
NODE_NAME     U2 BR60
 '@S9S_MB_2U_LIB.S9S_MB_2U(SCH_1):PAGE36_I7@PURE_QUANTA.SOCKET4677_AZIF0045P001C01CS(CHIPS)':
 'VCCIN77': CDS_PINID='VCCIN77';
NODE_NAME     U2 BR62
 '@S9S_MB_2U_LIB.S9S_MB_2U(SCH_1):PAGE36_I7@PURE_QUANTA.SOCKET4677_AZIF0045P001C01CS(CHIPS)':
 'VCCIN78': CDS_PINID='VCCIN78';
NODE_NAME     U2 BR78
 '@S9S_MB_2U_LIB.S9S_MB_2U(SCH_1):PAGE36_I7@PURE_QUANTA.SOCKET4677_AZIF0045P001C01CS(CHIPS)':
 'VCCIN79': CDS_PINID='VCCIN79';
NODE_NAME     U2 BT32
 '@S9S_MB_2U_LIB.S9S_MB_2U(SCH_1):PAGE36_I7@PURE_QUANTA.SOCKET4677_AZIF0045P001C01CS(CHIPS)':
 'VCCIN80': CDS_PINID='VCCIN80';
NODE_NAME     U2 BT34
 '@S9S_MB_2U_LIB.S9S_MB_2U(SCH_1):PAGE36_I7@PURE_QUANTA.SOCKET4677_AZIF0045P001C01CS(CHIPS)':
 'VCCIN81': CDS_PINID='VCCIN81';
NODE_NAME     U2 BT36
 '@S9S_MB_2U_LIB.S9S_MB_2U(SCH_1):PAGE36_I7@PURE_QUANTA.SOCKET4677_AZIF0045P001C01CS(CHIPS)':
 'VCCIN82': CDS_PINID='VCCIN82';
NODE_NAME     U2 BT38
 '@S9S_MB_2U_LIB.S9S_MB_2U(SCH_1):PAGE36_I7@PURE_QUANTA.SOCKET4677_AZIF0045P001C01CS(CHIPS)':
 'VCCIN83': CDS_PINID='VCCIN83';
NODE_NAME     U2 BT40
 '@S9S_MB_2U_LIB.S9S_MB_2U(SCH_1):PAGE36_I7@PURE_QUANTA.SOCKET4677_AZIF0045P001C01CS(CHIPS)':
 'VCCIN84': CDS_PINID='VCCIN84';
NODE_NAME     U2 BT42
 '@S9S_MB_2U_LIB.S9S_MB_2U(SCH_1):PAGE36_I7@PURE_QUANTA.SOCKET4677_AZIF0045P001C01CS(CHIPS)':
 'VCCIN85': CDS_PINID='VCCIN85';
NODE_NAME     U2 BT44
 '@S9S_MB_2U_LIB.S9S_MB_2U(SCH_1):PAGE36_I7@PURE_QUANTA.SOCKET4677_AZIF0045P001C01CS(CHIPS)':
 'VCCIN86': CDS_PINID='VCCIN86';
NODE_NAME     U2 BT47
 '@S9S_MB_2U_LIB.S9S_MB_2U(SCH_1):PAGE36_I7@PURE_QUANTA.SOCKET4677_AZIF0045P001C01CS(CHIPS)':
 'VCCIN87': CDS_PINID='VCCIN87';
NODE_NAME     U2 BT49
 '@S9S_MB_2U_LIB.S9S_MB_2U(SCH_1):PAGE36_I7@PURE_QUANTA.SOCKET4677_AZIF0045P001C01CS(CHIPS)':
 'VCCIN88': CDS_PINID='VCCIN88';
NODE_NAME     U2 BT51
 '@S9S_MB_2U_LIB.S9S_MB_2U(SCH_1):PAGE36_I7@PURE_QUANTA.SOCKET4677_AZIF0045P001C01CS(CHIPS)':
 'VCCIN89': CDS_PINID='VCCIN89';
NODE_NAME     U2 BT53
 '@S9S_MB_2U_LIB.S9S_MB_2U(SCH_1):PAGE36_I7@PURE_QUANTA.SOCKET4677_AZIF0045P001C01CS(CHIPS)':
 'VCCIN90': CDS_PINID='VCCIN90';
NODE_NAME     U2 BT55
 '@S9S_MB_2U_LIB.S9S_MB_2U(SCH_1):PAGE36_I7@PURE_QUANTA.SOCKET4677_AZIF0045P001C01CS(CHIPS)':
 'VCCIN91': CDS_PINID='VCCIN91';
NODE_NAME     U2 BT57
 '@S9S_MB_2U_LIB.S9S_MB_2U(SCH_1):PAGE36_I7@PURE_QUANTA.SOCKET4677_AZIF0045P001C01CS(CHIPS)':
 'VCCIN92': CDS_PINID='VCCIN92';
NODE_NAME     U2 BT59
 '@S9S_MB_2U_LIB.S9S_MB_2U(SCH_1):PAGE36_I7@PURE_QUANTA.SOCKET4677_AZIF0045P001C01CS(CHIPS)':
 'VCCIN93': CDS_PINID='VCCIN93';
NODE_NAME     U2 BT61
 '@S9S_MB_2U_LIB.S9S_MB_2U(SCH_1):PAGE36_I7@PURE_QUANTA.SOCKET4677_AZIF0045P001C01CS(CHIPS)':
 'VCCIN94': CDS_PINID='VCCIN94';
NODE_NAME     U2 BT63
 '@S9S_MB_2U_LIB.S9S_MB_2U(SCH_1):PAGE36_I7@PURE_QUANTA.SOCKET4677_AZIF0045P001C01CS(CHIPS)':
 'VCCIN95': CDS_PINID='VCCIN95';
NODE_NAME     U2 BT65
 '@S9S_MB_2U_LIB.S9S_MB_2U(SCH_1):PAGE36_I7@PURE_QUANTA.SOCKET4677_AZIF0045P001C01CS(CHIPS)':
 'VCCIN96': CDS_PINID='VCCIN96';
NODE_NAME     U2 BT67
 '@S9S_MB_2U_LIB.S9S_MB_2U(SCH_1):PAGE36_I7@PURE_QUANTA.SOCKET4677_AZIF0045P001C01CS(CHIPS)':
 'VCCIN97': CDS_PINID='VCCIN97';
NODE_NAME     U2 BT69
 '@S9S_MB_2U_LIB.S9S_MB_2U(SCH_1):PAGE36_I7@PURE_QUANTA.SOCKET4677_AZIF0045P001C01CS(CHIPS)':
 'VCCIN98': CDS_PINID='VCCIN98';
NODE_NAME     U2 BT71
 '@S9S_MB_2U_LIB.S9S_MB_2U(SCH_1):PAGE36_I7@PURE_QUANTA.SOCKET4677_AZIF0045P001C01CS(CHIPS)':
 'VCCIN99': CDS_PINID='VCCIN99';
NODE_NAME     U2 BT73
 '@S9S_MB_2U_LIB.S9S_MB_2U(SCH_1):PAGE36_I7@PURE_QUANTA.SOCKET4677_AZIF0045P001C01CS(CHIPS)':
 'VCCIN100': CDS_PINID='VCCIN100';
NODE_NAME     U2 BT75
 '@S9S_MB_2U_LIB.S9S_MB_2U(SCH_1):PAGE36_I7@PURE_QUANTA.SOCKET4677_AZIF0045P001C01CS(CHIPS)':
 'VCCIN101': CDS_PINID='VCCIN101';
NODE_NAME     U2 BT77
 '@S9S_MB_2U_LIB.S9S_MB_2U(SCH_1):PAGE36_I7@PURE_QUANTA.SOCKET4677_AZIF0045P001C01CS(CHIPS)':
 'VCCIN102': CDS_PINID='VCCIN102';
NODE_NAME     U2 BT79
 '@S9S_MB_2U_LIB.S9S_MB_2U(SCH_1):PAGE36_I7@PURE_QUANTA.SOCKET4677_AZIF0045P001C01CS(CHIPS)':
 'VCCIN103': CDS_PINID='VCCIN103';
NODE_NAME     U2 BT81
 '@S9S_MB_2U_LIB.S9S_MB_2U(SCH_1):PAGE36_I7@PURE_QUANTA.SOCKET4677_AZIF0045P001C01CS(CHIPS)':
 'VCCIN104': CDS_PINID='VCCIN104';
NODE_NAME     U2 BT83
 '@S9S_MB_2U_LIB.S9S_MB_2U(SCH_1):PAGE36_I7@PURE_QUANTA.SOCKET4677_AZIF0045P001C01CS(CHIPS)':
 'VCCIN105': CDS_PINID='VCCIN105';
NODE_NAME     U2 BT85
 '@S9S_MB_2U_LIB.S9S_MB_2U(SCH_1):PAGE36_I7@PURE_QUANTA.SOCKET4677_AZIF0045P001C01CS(CHIPS)':
 'VCCIN106': CDS_PINID='VCCIN106';
NODE_NAME     U2 BT87
 '@S9S_MB_2U_LIB.S9S_MB_2U(SCH_1):PAGE36_I7@PURE_QUANTA.SOCKET4677_AZIF0045P001C01CS(CHIPS)':
 'VCCIN107': CDS_PINID='VCCIN107';
NODE_NAME     U2 BT89
 '@S9S_MB_2U_LIB.S9S_MB_2U(SCH_1):PAGE36_I7@PURE_QUANTA.SOCKET4677_AZIF0045P001C01CS(CHIPS)':
 'VCCIN108': CDS_PINID='VCCIN108';
NODE_NAME     U2 BU33
 '@S9S_MB_2U_LIB.S9S_MB_2U(SCH_1):PAGE36_I7@PURE_QUANTA.SOCKET4677_AZIF0045P001C01CS(CHIPS)':
 'VCCIN109': CDS_PINID='VCCIN109';
NODE_NAME     U2 BU35
 '@S9S_MB_2U_LIB.S9S_MB_2U(SCH_1):PAGE36_I7@PURE_QUANTA.SOCKET4677_AZIF0045P001C01CS(CHIPS)':
 'VCCIN110': CDS_PINID='VCCIN110';
NODE_NAME     U2 BU37
 '@S9S_MB_2U_LIB.S9S_MB_2U(SCH_1):PAGE36_I7@PURE_QUANTA.SOCKET4677_AZIF0045P001C01CS(CHIPS)':
 'VCCIN111': CDS_PINID='VCCIN111';
NODE_NAME     U2 BU39
 '@S9S_MB_2U_LIB.S9S_MB_2U(SCH_1):PAGE36_I7@PURE_QUANTA.SOCKET4677_AZIF0045P001C01CS(CHIPS)':
 'VCCIN112': CDS_PINID='VCCIN112';
NODE_NAME     U2 BU41
 '@S9S_MB_2U_LIB.S9S_MB_2U(SCH_1):PAGE36_I7@PURE_QUANTA.SOCKET4677_AZIF0045P001C01CS(CHIPS)':
 'VCCIN113': CDS_PINID='VCCIN113';
NODE_NAME     U2 BU43
 '@S9S_MB_2U_LIB.S9S_MB_2U(SCH_1):PAGE36_I7@PURE_QUANTA.SOCKET4677_AZIF0045P001C01CS(CHIPS)':
 'VCCIN114': CDS_PINID='VCCIN114';
NODE_NAME     U2 BU45
 '@S9S_MB_2U_LIB.S9S_MB_2U(SCH_1):PAGE36_I7@PURE_QUANTA.SOCKET4677_AZIF0045P001C01CS(CHIPS)':
 'VCCIN115': CDS_PINID='VCCIN115';
NODE_NAME     U2 BU48
 '@S9S_MB_2U_LIB.S9S_MB_2U(SCH_1):PAGE36_I7@PURE_QUANTA.SOCKET4677_AZIF0045P001C01CS(CHIPS)':
 'VCCIN116': CDS_PINID='VCCIN116';
NODE_NAME     U2 BU50
 '@S9S_MB_2U_LIB.S9S_MB_2U(SCH_1):PAGE36_I7@PURE_QUANTA.SOCKET4677_AZIF0045P001C01CS(CHIPS)':
 'VCCIN117': CDS_PINID='VCCIN117';
NODE_NAME     U2 BU52
 '@S9S_MB_2U_LIB.S9S_MB_2U(SCH_1):PAGE36_I7@PURE_QUANTA.SOCKET4677_AZIF0045P001C01CS(CHIPS)':
 'VCCIN118': CDS_PINID='VCCIN118';
NODE_NAME     U2 BU54
 '@S9S_MB_2U_LIB.S9S_MB_2U(SCH_1):PAGE36_I7@PURE_QUANTA.SOCKET4677_AZIF0045P001C01CS(CHIPS)':
 'VCCIN119': CDS_PINID='VCCIN119';
NODE_NAME     U2 BU56
 '@S9S_MB_2U_LIB.S9S_MB_2U(SCH_1):PAGE36_I7@PURE_QUANTA.SOCKET4677_AZIF0045P001C01CS(CHIPS)':
 'VCCIN120': CDS_PINID='VCCIN120';
NODE_NAME     U2 BU58
 '@S9S_MB_2U_LIB.S9S_MB_2U(SCH_1):PAGE36_I7@PURE_QUANTA.SOCKET4677_AZIF0045P001C01CS(CHIPS)':
 'VCCIN121': CDS_PINID='VCCIN121';
NODE_NAME     U2 BU60
 '@S9S_MB_2U_LIB.S9S_MB_2U(SCH_1):PAGE36_I7@PURE_QUANTA.SOCKET4677_AZIF0045P001C01CS(CHIPS)':
 'VCCIN122': CDS_PINID='VCCIN122';
NODE_NAME     U2 BU62
 '@S9S_MB_2U_LIB.S9S_MB_2U(SCH_1):PAGE36_I7@PURE_QUANTA.SOCKET4677_AZIF0045P001C01CS(CHIPS)':
 'VCCIN123': CDS_PINID='VCCIN123';
NODE_NAME     U2 BU64
 '@S9S_MB_2U_LIB.S9S_MB_2U(SCH_1):PAGE36_I7@PURE_QUANTA.SOCKET4677_AZIF0045P001C01CS(CHIPS)':
 'VCCIN124': CDS_PINID='VCCIN124';
NODE_NAME     U2 BU66
 '@S9S_MB_2U_LIB.S9S_MB_2U(SCH_1):PAGE36_I7@PURE_QUANTA.SOCKET4677_AZIF0045P001C01CS(CHIPS)':
 'VCCIN125': CDS_PINID='VCCIN125';
NODE_NAME     U2 BU68
 '@S9S_MB_2U_LIB.S9S_MB_2U(SCH_1):PAGE36_I7@PURE_QUANTA.SOCKET4677_AZIF0045P001C01CS(CHIPS)':
 'VCCIN126': CDS_PINID='VCCIN126';
NODE_NAME     U2 BU70
 '@S9S_MB_2U_LIB.S9S_MB_2U(SCH_1):PAGE36_I7@PURE_QUANTA.SOCKET4677_AZIF0045P001C01CS(CHIPS)':
 'VCCIN127': CDS_PINID='VCCIN127';
NODE_NAME     U2 BU72
 '@S9S_MB_2U_LIB.S9S_MB_2U(SCH_1):PAGE36_I7@PURE_QUANTA.SOCKET4677_AZIF0045P001C01CS(CHIPS)':
 'VCCIN128': CDS_PINID='VCCIN128';
NODE_NAME     U2 BU74
 '@S9S_MB_2U_LIB.S9S_MB_2U(SCH_1):PAGE36_I7@PURE_QUANTA.SOCKET4677_AZIF0045P001C01CS(CHIPS)':
 'VCCIN129': CDS_PINID='VCCIN129';
NODE_NAME     U2 BU76
 '@S9S_MB_2U_LIB.S9S_MB_2U(SCH_1):PAGE36_I7@PURE_QUANTA.SOCKET4677_AZIF0045P001C01CS(CHIPS)':
 'VCCIN130': CDS_PINID='VCCIN130';
NODE_NAME     U2 BU78
 '@S9S_MB_2U_LIB.S9S_MB_2U(SCH_1):PAGE36_I7@PURE_QUANTA.SOCKET4677_AZIF0045P001C01CS(CHIPS)':
 'VCCIN131': CDS_PINID='VCCIN131';
NODE_NAME     U2 BU80
 '@S9S_MB_2U_LIB.S9S_MB_2U(SCH_1):PAGE36_I7@PURE_QUANTA.SOCKET4677_AZIF0045P001C01CS(CHIPS)':
 'VCCIN132': CDS_PINID='VCCIN132';
NODE_NAME     U2 BU82
 '@S9S_MB_2U_LIB.S9S_MB_2U(SCH_1):PAGE36_I7@PURE_QUANTA.SOCKET4677_AZIF0045P001C01CS(CHIPS)':
 'VCCIN133': CDS_PINID='VCCIN133';
NODE_NAME     U2 BU84
 '@S9S_MB_2U_LIB.S9S_MB_2U(SCH_1):PAGE36_I7@PURE_QUANTA.SOCKET4677_AZIF0045P001C01CS(CHIPS)':
 'VCCIN134': CDS_PINID='VCCIN134';
NODE_NAME     U2 BU86
 '@S9S_MB_2U_LIB.S9S_MB_2U(SCH_1):PAGE36_I7@PURE_QUANTA.SOCKET4677_AZIF0045P001C01CS(CHIPS)':
 'VCCIN135': CDS_PINID='VCCIN135';
NODE_NAME     U2 BU88
 '@S9S_MB_2U_LIB.S9S_MB_2U(SCH_1):PAGE36_I7@PURE_QUANTA.SOCKET4677_AZIF0045P001C01CS(CHIPS)':
 'VCCIN136': CDS_PINID='VCCIN136';
NODE_NAME     U2 BU90
 '@S9S_MB_2U_LIB.S9S_MB_2U(SCH_1):PAGE36_I7@PURE_QUANTA.SOCKET4677_AZIF0045P001C01CS(CHIPS)':
 'VCCIN137': CDS_PINID='VCCIN137';
NODE_NAME     U2 BV32
 '@S9S_MB_2U_LIB.S9S_MB_2U(SCH_1):PAGE36_I7@PURE_QUANTA.SOCKET4677_AZIF0045P001C01CS(CHIPS)':
 'VCCIN138': CDS_PINID='VCCIN138';
NODE_NAME     U2 BV34
 '@S9S_MB_2U_LIB.S9S_MB_2U(SCH_1):PAGE36_I7@PURE_QUANTA.SOCKET4677_AZIF0045P001C01CS(CHIPS)':
 'VCCIN139': CDS_PINID='VCCIN139';
NODE_NAME     U2 BV36
 '@S9S_MB_2U_LIB.S9S_MB_2U(SCH_1):PAGE36_I7@PURE_QUANTA.SOCKET4677_AZIF0045P001C01CS(CHIPS)':
 'VCCIN140': CDS_PINID='VCCIN140';
NODE_NAME     U2 BV38
 '@S9S_MB_2U_LIB.S9S_MB_2U(SCH_1):PAGE36_I7@PURE_QUANTA.SOCKET4677_AZIF0045P001C01CS(CHIPS)':
 'VCCIN141': CDS_PINID='VCCIN141';
NODE_NAME     U2 BV40
 '@S9S_MB_2U_LIB.S9S_MB_2U(SCH_1):PAGE36_I7@PURE_QUANTA.SOCKET4677_AZIF0045P001C01CS(CHIPS)':
 'VCCIN142': CDS_PINID='VCCIN142';
NODE_NAME     U2 BV42
 '@S9S_MB_2U_LIB.S9S_MB_2U(SCH_1):PAGE36_I7@PURE_QUANTA.SOCKET4677_AZIF0045P001C01CS(CHIPS)':
 'VCCIN143': CDS_PINID='VCCIN143';
NODE_NAME     U2 BV44
 '@S9S_MB_2U_LIB.S9S_MB_2U(SCH_1):PAGE36_I7@PURE_QUANTA.SOCKET4677_AZIF0045P001C01CS(CHIPS)':
 'VCCIN144': CDS_PINID='VCCIN144';
NODE_NAME     U2 BV47
 '@S9S_MB_2U_LIB.S9S_MB_2U(SCH_1):PAGE36_I7@PURE_QUANTA.SOCKET4677_AZIF0045P001C01CS(CHIPS)':
 'VCCIN145': CDS_PINID='VCCIN145';
NODE_NAME     U2 BV49
 '@S9S_MB_2U_LIB.S9S_MB_2U(SCH_1):PAGE36_I7@PURE_QUANTA.SOCKET4677_AZIF0045P001C01CS(CHIPS)':
 'VCCIN146': CDS_PINID='VCCIN146';
NODE_NAME     U2 BV51
 '@S9S_MB_2U_LIB.S9S_MB_2U(SCH_1):PAGE36_I7@PURE_QUANTA.SOCKET4677_AZIF0045P001C01CS(CHIPS)':
 'VCCIN147': CDS_PINID='VCCIN147';
NODE_NAME     U2 BV53
 '@S9S_MB_2U_LIB.S9S_MB_2U(SCH_1):PAGE36_I7@PURE_QUANTA.SOCKET4677_AZIF0045P001C01CS(CHIPS)':
 'VCCIN148': CDS_PINID='VCCIN148';
NODE_NAME     U2 BV55
 '@S9S_MB_2U_LIB.S9S_MB_2U(SCH_1):PAGE36_I7@PURE_QUANTA.SOCKET4677_AZIF0045P001C01CS(CHIPS)':
 'VCCIN149': CDS_PINID='VCCIN149';
NODE_NAME     U2 BV57
 '@S9S_MB_2U_LIB.S9S_MB_2U(SCH_1):PAGE36_I7@PURE_QUANTA.SOCKET4677_AZIF0045P001C01CS(CHIPS)':
 'VCCIN150': CDS_PINID='VCCIN150';
NODE_NAME     U2 BV59
 '@S9S_MB_2U_LIB.S9S_MB_2U(SCH_1):PAGE36_I7@PURE_QUANTA.SOCKET4677_AZIF0045P001C01CS(CHIPS)':
 'VCCIN151': CDS_PINID='VCCIN151';
NODE_NAME     U2 BV61
 '@S9S_MB_2U_LIB.S9S_MB_2U(SCH_1):PAGE36_I7@PURE_QUANTA.SOCKET4677_AZIF0045P001C01CS(CHIPS)':
 'VCCIN152': CDS_PINID='VCCIN152';
NODE_NAME     U2 BV63
 '@S9S_MB_2U_LIB.S9S_MB_2U(SCH_1):PAGE36_I7@PURE_QUANTA.SOCKET4677_AZIF0045P001C01CS(CHIPS)':
 'VCCIN153': CDS_PINID='VCCIN153';
NODE_NAME     U2 BV65
 '@S9S_MB_2U_LIB.S9S_MB_2U(SCH_1):PAGE36_I7@PURE_QUANTA.SOCKET4677_AZIF0045P001C01CS(CHIPS)':
 'VCCIN154': CDS_PINID='VCCIN154';
NODE_NAME     U2 BV67
 '@S9S_MB_2U_LIB.S9S_MB_2U(SCH_1):PAGE36_I7@PURE_QUANTA.SOCKET4677_AZIF0045P001C01CS(CHIPS)':
 'VCCIN155': CDS_PINID='VCCIN155';
NODE_NAME     U2 BV69
 '@S9S_MB_2U_LIB.S9S_MB_2U(SCH_1):PAGE36_I7@PURE_QUANTA.SOCKET4677_AZIF0045P001C01CS(CHIPS)':
 'VCCIN156': CDS_PINID='VCCIN156';
NODE_NAME     U2 BV71
 '@S9S_MB_2U_LIB.S9S_MB_2U(SCH_1):PAGE36_I7@PURE_QUANTA.SOCKET4677_AZIF0045P001C01CS(CHIPS)':
 'VCCIN157': CDS_PINID='VCCIN157';
NODE_NAME     U2 BV73
 '@S9S_MB_2U_LIB.S9S_MB_2U(SCH_1):PAGE36_I7@PURE_QUANTA.SOCKET4677_AZIF0045P001C01CS(CHIPS)':
 'VCCIN158': CDS_PINID='VCCIN158';
NODE_NAME     U2 BV75
 '@S9S_MB_2U_LIB.S9S_MB_2U(SCH_1):PAGE36_I7@PURE_QUANTA.SOCKET4677_AZIF0045P001C01CS(CHIPS)':
 'VCCIN159': CDS_PINID='VCCIN159';
NODE_NAME     U2 BV77
 '@S9S_MB_2U_LIB.S9S_MB_2U(SCH_1):PAGE36_I7@PURE_QUANTA.SOCKET4677_AZIF0045P001C01CS(CHIPS)':
 'VCCIN160': CDS_PINID='VCCIN160';
NODE_NAME     U2 BV79
 '@S9S_MB_2U_LIB.S9S_MB_2U(SCH_1):PAGE36_I7@PURE_QUANTA.SOCKET4677_AZIF0045P001C01CS(CHIPS)':
 'VCCIN161': CDS_PINID='VCCIN161';
NODE_NAME     U2 BV81
 '@S9S_MB_2U_LIB.S9S_MB_2U(SCH_1):PAGE36_I7@PURE_QUANTA.SOCKET4677_AZIF0045P001C01CS(CHIPS)':
 'VCCIN162': CDS_PINID='VCCIN162';
NODE_NAME     U2 BV83
 '@S9S_MB_2U_LIB.S9S_MB_2U(SCH_1):PAGE36_I7@PURE_QUANTA.SOCKET4677_AZIF0045P001C01CS(CHIPS)':
 'VCCIN163': CDS_PINID='VCCIN163';
NODE_NAME     U2 BV85
 '@S9S_MB_2U_LIB.S9S_MB_2U(SCH_1):PAGE36_I7@PURE_QUANTA.SOCKET4677_AZIF0045P001C01CS(CHIPS)':
 'VCCIN164': CDS_PINID='VCCIN164';
NODE_NAME     U2 BV87
 '@S9S_MB_2U_LIB.S9S_MB_2U(SCH_1):PAGE36_I7@PURE_QUANTA.SOCKET4677_AZIF0045P001C01CS(CHIPS)':
 'VCCIN165': CDS_PINID='VCCIN165';
NODE_NAME     U2 BV89
 '@S9S_MB_2U_LIB.S9S_MB_2U(SCH_1):PAGE36_I7@PURE_QUANTA.SOCKET4677_AZIF0045P001C01CS(CHIPS)':
 'VCCIN166': CDS_PINID='VCCIN166';
NODE_NAME     U2 BW33
 '@S9S_MB_2U_LIB.S9S_MB_2U(SCH_1):PAGE36_I7@PURE_QUANTA.SOCKET4677_AZIF0045P001C01CS(CHIPS)':
 'VCCIN167': CDS_PINID='VCCIN167';
NODE_NAME     U2 BW35
 '@S9S_MB_2U_LIB.S9S_MB_2U(SCH_1):PAGE36_I7@PURE_QUANTA.SOCKET4677_AZIF0045P001C01CS(CHIPS)':
 'VCCIN168': CDS_PINID='VCCIN168';
NODE_NAME     U2 BW37
 '@S9S_MB_2U_LIB.S9S_MB_2U(SCH_1):PAGE36_I7@PURE_QUANTA.SOCKET4677_AZIF0045P001C01CS(CHIPS)':
 'VCCIN169': CDS_PINID='VCCIN169';
NODE_NAME     U2 BW39
 '@S9S_MB_2U_LIB.S9S_MB_2U(SCH_1):PAGE36_I7@PURE_QUANTA.SOCKET4677_AZIF0045P001C01CS(CHIPS)':
 'VCCIN170': CDS_PINID='VCCIN170';
NODE_NAME     U2 BW41
 '@S9S_MB_2U_LIB.S9S_MB_2U(SCH_1):PAGE36_I7@PURE_QUANTA.SOCKET4677_AZIF0045P001C01CS(CHIPS)':
 'VCCIN171': CDS_PINID='VCCIN171';
NODE_NAME     U2 BW43
 '@S9S_MB_2U_LIB.S9S_MB_2U(SCH_1):PAGE36_I7@PURE_QUANTA.SOCKET4677_AZIF0045P001C01CS(CHIPS)':
 'VCCIN172': CDS_PINID='VCCIN172';
NODE_NAME     U2 BW45
 '@S9S_MB_2U_LIB.S9S_MB_2U(SCH_1):PAGE36_I7@PURE_QUANTA.SOCKET4677_AZIF0045P001C01CS(CHIPS)':
 'VCCIN173': CDS_PINID='VCCIN173';
NODE_NAME     U2 BW48
 '@S9S_MB_2U_LIB.S9S_MB_2U(SCH_1):PAGE36_I7@PURE_QUANTA.SOCKET4677_AZIF0045P001C01CS(CHIPS)':
 'VCCIN174': CDS_PINID='VCCIN174';
NODE_NAME     U2 BW50
 '@S9S_MB_2U_LIB.S9S_MB_2U(SCH_1):PAGE36_I7@PURE_QUANTA.SOCKET4677_AZIF0045P001C01CS(CHIPS)':
 'VCCIN175': CDS_PINID='VCCIN175';
NODE_NAME     U2 BW52
 '@S9S_MB_2U_LIB.S9S_MB_2U(SCH_1):PAGE36_I7@PURE_QUANTA.SOCKET4677_AZIF0045P001C01CS(CHIPS)':
 'VCCIN176': CDS_PINID='VCCIN176';
NODE_NAME     U2 BW54
 '@S9S_MB_2U_LIB.S9S_MB_2U(SCH_1):PAGE36_I7@PURE_QUANTA.SOCKET4677_AZIF0045P001C01CS(CHIPS)':
 'VCCIN177': CDS_PINID='VCCIN177';
NODE_NAME     U2 BW56
 '@S9S_MB_2U_LIB.S9S_MB_2U(SCH_1):PAGE36_I7@PURE_QUANTA.SOCKET4677_AZIF0045P001C01CS(CHIPS)':
 'VCCIN178': CDS_PINID='VCCIN178';
NODE_NAME     U2 BW58
 '@S9S_MB_2U_LIB.S9S_MB_2U(SCH_1):PAGE36_I7@PURE_QUANTA.SOCKET4677_AZIF0045P001C01CS(CHIPS)':
 'VCCIN179': CDS_PINID='VCCIN179';
NODE_NAME     U2 BW60
 '@S9S_MB_2U_LIB.S9S_MB_2U(SCH_1):PAGE36_I7@PURE_QUANTA.SOCKET4677_AZIF0045P001C01CS(CHIPS)':
 'VCCIN180': CDS_PINID='VCCIN180';
NODE_NAME     U2 BW62
 '@S9S_MB_2U_LIB.S9S_MB_2U(SCH_1):PAGE36_I7@PURE_QUANTA.SOCKET4677_AZIF0045P001C01CS(CHIPS)':
 'VCCIN181': CDS_PINID='VCCIN181';
NODE_NAME     U2 BW64
 '@S9S_MB_2U_LIB.S9S_MB_2U(SCH_1):PAGE36_I7@PURE_QUANTA.SOCKET4677_AZIF0045P001C01CS(CHIPS)':
 'VCCIN182': CDS_PINID='VCCIN182';
NODE_NAME     U2 BW66
 '@S9S_MB_2U_LIB.S9S_MB_2U(SCH_1):PAGE36_I7@PURE_QUANTA.SOCKET4677_AZIF0045P001C01CS(CHIPS)':
 'VCCIN183': CDS_PINID='VCCIN183';
NODE_NAME     U2 BW68
 '@S9S_MB_2U_LIB.S9S_MB_2U(SCH_1):PAGE36_I7@PURE_QUANTA.SOCKET4677_AZIF0045P001C01CS(CHIPS)':
 'VCCIN184': CDS_PINID='VCCIN184';
NODE_NAME     U2 BW70
 '@S9S_MB_2U_LIB.S9S_MB_2U(SCH_1):PAGE36_I7@PURE_QUANTA.SOCKET4677_AZIF0045P001C01CS(CHIPS)':
 'VCCIN185': CDS_PINID='VCCIN185';
NODE_NAME     U2 BW72
 '@S9S_MB_2U_LIB.S9S_MB_2U(SCH_1):PAGE36_I7@PURE_QUANTA.SOCKET4677_AZIF0045P001C01CS(CHIPS)':
 'VCCIN186': CDS_PINID='VCCIN186';
NODE_NAME     U2 BW74
 '@S9S_MB_2U_LIB.S9S_MB_2U(SCH_1):PAGE36_I7@PURE_QUANTA.SOCKET4677_AZIF0045P001C01CS(CHIPS)':
 'VCCIN187': CDS_PINID='VCCIN187';
NODE_NAME     U2 BW76
 '@S9S_MB_2U_LIB.S9S_MB_2U(SCH_1):PAGE36_I7@PURE_QUANTA.SOCKET4677_AZIF0045P001C01CS(CHIPS)':
 'VCCIN188': CDS_PINID='VCCIN188';
NODE_NAME     U2 BW78
 '@S9S_MB_2U_LIB.S9S_MB_2U(SCH_1):PAGE36_I7@PURE_QUANTA.SOCKET4677_AZIF0045P001C01CS(CHIPS)':
 'VCCIN189': CDS_PINID='VCCIN189';
NODE_NAME     U2 BD91
 '@S9S_MB_2U_LIB.S9S_MB_2U(SCH_1):PAGE37_I7@PURE_QUANTA.SOCKET4677_AZIF0045P001C01CS(CHIPS)':
 'VCCIN0': CDS_PINID='VCCIN0';
NODE_NAME     U2 BE86
 '@S9S_MB_2U_LIB.S9S_MB_2U(SCH_1):PAGE37_I7@PURE_QUANTA.SOCKET4677_AZIF0045P001C01CS(CHIPS)':
 'VCCIN1': CDS_PINID='VCCIN1';
NODE_NAME     U2 BE88
 '@S9S_MB_2U_LIB.S9S_MB_2U(SCH_1):PAGE37_I7@PURE_QUANTA.SOCKET4677_AZIF0045P001C01CS(CHIPS)':
 'VCCIN2': CDS_PINID='VCCIN2';
NODE_NAME     U2 BE90
 '@S9S_MB_2U_LIB.S9S_MB_2U(SCH_1):PAGE37_I7@PURE_QUANTA.SOCKET4677_AZIF0045P001C01CS(CHIPS)':
 'VCCIN3': CDS_PINID='VCCIN3';
NODE_NAME     U2 BF85
 '@S9S_MB_2U_LIB.S9S_MB_2U(SCH_1):PAGE37_I7@PURE_QUANTA.SOCKET4677_AZIF0045P001C01CS(CHIPS)':
 'VCCIN4': CDS_PINID='VCCIN4';
NODE_NAME     U2 BF87
 '@S9S_MB_2U_LIB.S9S_MB_2U(SCH_1):PAGE37_I7@PURE_QUANTA.SOCKET4677_AZIF0045P001C01CS(CHIPS)':
 'VCCIN5': CDS_PINID='VCCIN5';
NODE_NAME     U2 BF89
 '@S9S_MB_2U_LIB.S9S_MB_2U(SCH_1):PAGE37_I7@PURE_QUANTA.SOCKET4677_AZIF0045P001C01CS(CHIPS)':
 'VCCIN6': CDS_PINID='VCCIN6';
NODE_NAME     U2 BF91
 '@S9S_MB_2U_LIB.S9S_MB_2U(SCH_1):PAGE37_I7@PURE_QUANTA.SOCKET4677_AZIF0045P001C01CS(CHIPS)':
 'VCCIN7': CDS_PINID='VCCIN7';
NODE_NAME     U2 BG84
 '@S9S_MB_2U_LIB.S9S_MB_2U(SCH_1):PAGE37_I7@PURE_QUANTA.SOCKET4677_AZIF0045P001C01CS(CHIPS)':
 'VCCIN8': CDS_PINID='VCCIN8';
NODE_NAME     U2 BG86
 '@S9S_MB_2U_LIB.S9S_MB_2U(SCH_1):PAGE37_I7@PURE_QUANTA.SOCKET4677_AZIF0045P001C01CS(CHIPS)':
 'VCCIN9': CDS_PINID='VCCIN9';
NODE_NAME     U2 BG88
 '@S9S_MB_2U_LIB.S9S_MB_2U(SCH_1):PAGE37_I7@PURE_QUANTA.SOCKET4677_AZIF0045P001C01CS(CHIPS)':
 'VCCIN10': CDS_PINID='VCCIN10';
NODE_NAME     U2 BG90
 '@S9S_MB_2U_LIB.S9S_MB_2U(SCH_1):PAGE37_I7@PURE_QUANTA.SOCKET4677_AZIF0045P001C01CS(CHIPS)':
 'VCCIN11': CDS_PINID='VCCIN11';
NODE_NAME     U2 BH85
 '@S9S_MB_2U_LIB.S9S_MB_2U(SCH_1):PAGE37_I7@PURE_QUANTA.SOCKET4677_AZIF0045P001C01CS(CHIPS)':
 'VCCIN12': CDS_PINID='VCCIN12';
NODE_NAME     U2 BH87
 '@S9S_MB_2U_LIB.S9S_MB_2U(SCH_1):PAGE37_I7@PURE_QUANTA.SOCKET4677_AZIF0045P001C01CS(CHIPS)':
 'VCCIN13': CDS_PINID='VCCIN13';
NODE_NAME     U2 BH89
 '@S9S_MB_2U_LIB.S9S_MB_2U(SCH_1):PAGE37_I7@PURE_QUANTA.SOCKET4677_AZIF0045P001C01CS(CHIPS)':
 'VCCIN14': CDS_PINID='VCCIN14';
NODE_NAME     U2 BH91
 '@S9S_MB_2U_LIB.S9S_MB_2U(SCH_1):PAGE37_I7@PURE_QUANTA.SOCKET4677_AZIF0045P001C01CS(CHIPS)':
 'VCCIN15': CDS_PINID='VCCIN15';
NODE_NAME     U2 BK81
 '@S9S_MB_2U_LIB.S9S_MB_2U(SCH_1):PAGE37_I7@PURE_QUANTA.SOCKET4677_AZIF0045P001C01CS(CHIPS)':
 'VCCIN16': CDS_PINID='VCCIN16';
NODE_NAME     U2 BK83
 '@S9S_MB_2U_LIB.S9S_MB_2U(SCH_1):PAGE37_I7@PURE_QUANTA.SOCKET4677_AZIF0045P001C01CS(CHIPS)':
 'VCCIN17': CDS_PINID='VCCIN17';
NODE_NAME     U2 BK85
 '@S9S_MB_2U_LIB.S9S_MB_2U(SCH_1):PAGE37_I7@PURE_QUANTA.SOCKET4677_AZIF0045P001C01CS(CHIPS)':
 'VCCIN18': CDS_PINID='VCCIN18';
NODE_NAME     U2 BK87
 '@S9S_MB_2U_LIB.S9S_MB_2U(SCH_1):PAGE37_I7@PURE_QUANTA.SOCKET4677_AZIF0045P001C01CS(CHIPS)':
 'VCCIN19': CDS_PINID='VCCIN19';
NODE_NAME     U2 BK89
 '@S9S_MB_2U_LIB.S9S_MB_2U(SCH_1):PAGE37_I7@PURE_QUANTA.SOCKET4677_AZIF0045P001C01CS(CHIPS)':
 'VCCIN20': CDS_PINID='VCCIN20';
NODE_NAME     U2 BK91
 '@S9S_MB_2U_LIB.S9S_MB_2U(SCH_1):PAGE37_I7@PURE_QUANTA.SOCKET4677_AZIF0045P001C01CS(CHIPS)':
 'VCCIN21': CDS_PINID='VCCIN21';
NODE_NAME     U2 BL80
 '@S9S_MB_2U_LIB.S9S_MB_2U(SCH_1):PAGE37_I7@PURE_QUANTA.SOCKET4677_AZIF0045P001C01CS(CHIPS)':
 'VCCIN22': CDS_PINID='VCCIN22';
NODE_NAME     U2 BL82
 '@S9S_MB_2U_LIB.S9S_MB_2U(SCH_1):PAGE37_I7@PURE_QUANTA.SOCKET4677_AZIF0045P001C01CS(CHIPS)':
 'VCCIN23': CDS_PINID='VCCIN23';
NODE_NAME     U2 BL84
 '@S9S_MB_2U_LIB.S9S_MB_2U(SCH_1):PAGE37_I7@PURE_QUANTA.SOCKET4677_AZIF0045P001C01CS(CHIPS)':
 'VCCIN24': CDS_PINID='VCCIN24';
NODE_NAME     U2 BL86
 '@S9S_MB_2U_LIB.S9S_MB_2U(SCH_1):PAGE37_I7@PURE_QUANTA.SOCKET4677_AZIF0045P001C01CS(CHIPS)':
 'VCCIN25': CDS_PINID='VCCIN25';
NODE_NAME     U2 BL88
 '@S9S_MB_2U_LIB.S9S_MB_2U(SCH_1):PAGE37_I7@PURE_QUANTA.SOCKET4677_AZIF0045P001C01CS(CHIPS)':
 'VCCIN26': CDS_PINID='VCCIN26';
NODE_NAME     U2 BL90
 '@S9S_MB_2U_LIB.S9S_MB_2U(SCH_1):PAGE37_I7@PURE_QUANTA.SOCKET4677_AZIF0045P001C01CS(CHIPS)':
 'VCCIN27': CDS_PINID='VCCIN27';
NODE_NAME     U2 BM79
 '@S9S_MB_2U_LIB.S9S_MB_2U(SCH_1):PAGE37_I7@PURE_QUANTA.SOCKET4677_AZIF0045P001C01CS(CHIPS)':
 'VCCIN28': CDS_PINID='VCCIN28';
NODE_NAME     U2 BM81
 '@S9S_MB_2U_LIB.S9S_MB_2U(SCH_1):PAGE37_I7@PURE_QUANTA.SOCKET4677_AZIF0045P001C01CS(CHIPS)':
 'VCCIN29': CDS_PINID='VCCIN29';
NODE_NAME     U2 BM83
 '@S9S_MB_2U_LIB.S9S_MB_2U(SCH_1):PAGE37_I7@PURE_QUANTA.SOCKET4677_AZIF0045P001C01CS(CHIPS)':
 'VCCIN30': CDS_PINID='VCCIN30';
NODE_NAME     U2 BM85
 '@S9S_MB_2U_LIB.S9S_MB_2U(SCH_1):PAGE37_I7@PURE_QUANTA.SOCKET4677_AZIF0045P001C01CS(CHIPS)':
 'VCCIN31': CDS_PINID='VCCIN31';
NODE_NAME     U2 BM87
 '@S9S_MB_2U_LIB.S9S_MB_2U(SCH_1):PAGE37_I7@PURE_QUANTA.SOCKET4677_AZIF0045P001C01CS(CHIPS)':
 'VCCIN32': CDS_PINID='VCCIN32';
NODE_NAME     U2 BM89
 '@S9S_MB_2U_LIB.S9S_MB_2U(SCH_1):PAGE37_I7@PURE_QUANTA.SOCKET4677_AZIF0045P001C01CS(CHIPS)':
 'VCCIN33': CDS_PINID='VCCIN33';
NODE_NAME     U2 BM91
 '@S9S_MB_2U_LIB.S9S_MB_2U(SCH_1):PAGE37_I7@PURE_QUANTA.SOCKET4677_AZIF0045P001C01CS(CHIPS)':
 'VCCIN34': CDS_PINID='VCCIN34';
NODE_NAME     U2 BN33
 '@S9S_MB_2U_LIB.S9S_MB_2U(SCH_1):PAGE37_I7@PURE_QUANTA.SOCKET4677_AZIF0045P001C01CS(CHIPS)':
 'VCCIN35': CDS_PINID='VCCIN35';
NODE_NAME     U2 BN35
 '@S9S_MB_2U_LIB.S9S_MB_2U(SCH_1):PAGE37_I7@PURE_QUANTA.SOCKET4677_AZIF0045P001C01CS(CHIPS)':
 'VCCIN36': CDS_PINID='VCCIN36';
NODE_NAME     U2 BN37
 '@S9S_MB_2U_LIB.S9S_MB_2U(SCH_1):PAGE37_I7@PURE_QUANTA.SOCKET4677_AZIF0045P001C01CS(CHIPS)':
 'VCCIN37': CDS_PINID='VCCIN37';
NODE_NAME     U2 BN39
 '@S9S_MB_2U_LIB.S9S_MB_2U(SCH_1):PAGE37_I7@PURE_QUANTA.SOCKET4677_AZIF0045P001C01CS(CHIPS)':
 'VCCIN38': CDS_PINID='VCCIN38';
NODE_NAME     U2 BN41
 '@S9S_MB_2U_LIB.S9S_MB_2U(SCH_1):PAGE37_I7@PURE_QUANTA.SOCKET4677_AZIF0045P001C01CS(CHIPS)':
 'VCCIN39': CDS_PINID='VCCIN39';
NODE_NAME     C101 1
 '@S9S_MB_2U_LIB.S9S_MB_2U(SCH_1):PAGE74_I13@PURE_QUANTA.Q_CAP(CHIPS)':
 'A': CDS_PINID='A';
NODE_NAME     C969 1
 '@S9S_MB_2U_LIB.S9S_MB_2U(SCH_1):PAGE74_I15@PURE_QUANTA.Q_CAP(CHIPS)':
 'A': CDS_PINID='A';
NODE_NAME     C212 1
 '@S9S_MB_2U_LIB.S9S_MB_2U(SCH_1):PAGE74_I18@PURE_QUANTA.Q_CAP(CHIPS)':
 'A': CDS_PINID='A';
NODE_NAME     C213 1
 '@S9S_MB_2U_LIB.S9S_MB_2U(SCH_1):PAGE74_I20@PURE_QUANTA.Q_CAP(CHIPS)':
 'A': CDS_PINID='A';
NODE_NAME     C973 1
 '@S9S_MB_2U_LIB.S9S_MB_2U(SCH_1):PAGE74_I21@PURE_QUANTA.Q_CAP(CHIPS)':
 'A': CDS_PINID='A';
NODE_NAME     C977 1
 '@S9S_MB_2U_LIB.S9S_MB_2U(SCH_1):PAGE74_I22@PURE_QUANTA.Q_CAP(CHIPS)':
 'A': CDS_PINID='A';
NODE_NAME     C968 1
 '@S9S_MB_2U_LIB.S9S_MB_2U(SCH_1):PAGE74_I23@PURE_QUANTA.Q_CAP(CHIPS)':
 'A': CDS_PINID='A';
NODE_NAME     C976 1
 '@S9S_MB_2U_LIB.S9S_MB_2U(SCH_1):PAGE74_I29@PURE_QUANTA.Q_CAP(CHIPS)':
 'A': CDS_PINID='A';
NODE_NAME     C971 1
 '@S9S_MB_2U_LIB.S9S_MB_2U(SCH_1):PAGE74_I30@PURE_QUANTA.Q_CAP(CHIPS)':
 'A': CDS_PINID='A';
NODE_NAME     C975 1
 '@S9S_MB_2U_LIB.S9S_MB_2U(SCH_1):PAGE74_I32@PURE_QUANTA.Q_CAP(CHIPS)':
 'A': CDS_PINID='A';
NODE_NAME     C974 1
 '@S9S_MB_2U_LIB.S9S_MB_2U(SCH_1):PAGE74_I33@PURE_QUANTA.Q_CAP(CHIPS)':
 'A': CDS_PINID='A';
NODE_NAME     C214 1
 '@S9S_MB_2U_LIB.S9S_MB_2U(SCH_1):PAGE74_I35@PURE_QUANTA.Q_CAP(CHIPS)':
 'A': CDS_PINID='A';
NODE_NAME     C215 1
 '@S9S_MB_2U_LIB.S9S_MB_2U(SCH_1):PAGE74_I36@PURE_QUANTA.Q_CAP(CHIPS)':
 'A': CDS_PINID='A';
NODE_NAME     C981 1
 '@S9S_MB_2U_LIB.S9S_MB_2U(SCH_1):PAGE74_I37@PURE_QUANTA.Q_CAP(CHIPS)':
 'A': CDS_PINID='A';
NODE_NAME     C985 1
 '@S9S_MB_2U_LIB.S9S_MB_2U(SCH_1):PAGE74_I38@PURE_QUANTA.Q_CAP(CHIPS)':
 'A': CDS_PINID='A';
NODE_NAME     C216 1
 '@S9S_MB_2U_LIB.S9S_MB_2U(SCH_1):PAGE74_I40@PURE_QUANTA.Q_CAP(CHIPS)':
 'A': CDS_PINID='A';
NODE_NAME     C218 1
 '@S9S_MB_2U_LIB.S9S_MB_2U(SCH_1):PAGE74_I44@PURE_QUANTA.Q_CAP(CHIPS)':
 'A': CDS_PINID='A';
NODE_NAME     C993 1
 '@S9S_MB_2U_LIB.S9S_MB_2U(SCH_1):PAGE74_I46@PURE_QUANTA.Q_CAP(CHIPS)':
 'A': CDS_PINID='A';
NODE_NAME     C997 1
 '@S9S_MB_2U_LIB.S9S_MB_2U(SCH_1):PAGE74_I47@PURE_QUANTA.Q_CAP(CHIPS)':
 'A': CDS_PINID='A';
NODE_NAME     C980 1
 '@S9S_MB_2U_LIB.S9S_MB_2U(SCH_1):PAGE74_I48@PURE_QUANTA.Q_CAP(CHIPS)':
 'A': CDS_PINID='A';
NODE_NAME     C984 1
 '@S9S_MB_2U_LIB.S9S_MB_2U(SCH_1):PAGE74_I49@PURE_QUANTA.Q_CAP(CHIPS)':
 'A': CDS_PINID='A';
NODE_NAME     C979 1
 '@S9S_MB_2U_LIB.S9S_MB_2U(SCH_1):PAGE74_I50@PURE_QUANTA.Q_CAP(CHIPS)':
 'A': CDS_PINID='A';
NODE_NAME     C978 1
 '@S9S_MB_2U_LIB.S9S_MB_2U(SCH_1):PAGE74_I51@PURE_QUANTA.Q_CAP(CHIPS)':
 'A': CDS_PINID='A';
NODE_NAME     C983 1
 '@S9S_MB_2U_LIB.S9S_MB_2U(SCH_1):PAGE74_I52@PURE_QUANTA.Q_CAP(CHIPS)':
 'A': CDS_PINID='A';
NODE_NAME     C982 1
 '@S9S_MB_2U_LIB.S9S_MB_2U(SCH_1):PAGE74_I53@PURE_QUANTA.Q_CAP(CHIPS)':
 'A': CDS_PINID='A';
NODE_NAME     C988 1
 '@S9S_MB_2U_LIB.S9S_MB_2U(SCH_1):PAGE74_I54@PURE_QUANTA.Q_CAP(CHIPS)':
 'A': CDS_PINID='A';
NODE_NAME     C996 1
 '@S9S_MB_2U_LIB.S9S_MB_2U(SCH_1):PAGE74_I56@PURE_QUANTA.Q_CAP(CHIPS)':
 'A': CDS_PINID='A';
NODE_NAME     C986 1
 '@S9S_MB_2U_LIB.S9S_MB_2U(SCH_1):PAGE74_I58@PURE_QUANTA.Q_CAP(CHIPS)':
 'A': CDS_PINID='A';
NODE_NAME     C991 1
 '@S9S_MB_2U_LIB.S9S_MB_2U(SCH_1):PAGE74_I59@PURE_QUANTA.Q_CAP(CHIPS)':
 'A': CDS_PINID='A';
NODE_NAME     C990 1
 '@S9S_MB_2U_LIB.S9S_MB_2U(SCH_1):PAGE74_I60@PURE_QUANTA.Q_CAP(CHIPS)':
 'A': CDS_PINID='A';
NODE_NAME     C995 1
 '@S9S_MB_2U_LIB.S9S_MB_2U(SCH_1):PAGE74_I61@PURE_QUANTA.Q_CAP(CHIPS)':
 'A': CDS_PINID='A';
NODE_NAME     C219 1
 '@S9S_MB_2U_LIB.S9S_MB_2U(SCH_1):PAGE74_I71@PURE_QUANTA.Q_CAP(CHIPS)':
 'A': CDS_PINID='A';
NODE_NAME     C220 1
 '@S9S_MB_2U_LIB.S9S_MB_2U(SCH_1):PAGE74_I74@PURE_QUANTA.Q_CAP(CHIPS)':
 'A': CDS_PINID='A';
NODE_NAME     C1001 1
 '@S9S_MB_2U_LIB.S9S_MB_2U(SCH_1):PAGE74_I75@PURE_QUANTA.Q_CAP(CHIPS)':
 'A': CDS_PINID='A';
NODE_NAME     C1005 1
 '@S9S_MB_2U_LIB.S9S_MB_2U(SCH_1):PAGE74_I77@PURE_QUANTA.Q_CAP(CHIPS)':
 'A': CDS_PINID='A';
NODE_NAME     C1009 1
 '@S9S_MB_2U_LIB.S9S_MB_2U(SCH_1):PAGE74_I78@PURE_QUANTA.Q_CAP(CHIPS)':
 'A': CDS_PINID='A';
NODE_NAME     C1013 1
 '@S9S_MB_2U_LIB.S9S_MB_2U(SCH_1):PAGE74_I80@PURE_QUANTA.Q_CAP(CHIPS)':
 'A': CDS_PINID='A';
NODE_NAME     C1000 1
 '@S9S_MB_2U_LIB.S9S_MB_2U(SCH_1):PAGE74_I81@PURE_QUANTA.Q_CAP(CHIPS)':
 'A': CDS_PINID='A';
NODE_NAME     C999 1
 '@S9S_MB_2U_LIB.S9S_MB_2U(SCH_1):PAGE74_I85@PURE_QUANTA.Q_CAP(CHIPS)':
 'A': CDS_PINID='A';
NODE_NAME     C998 1
 '@S9S_MB_2U_LIB.S9S_MB_2U(SCH_1):PAGE74_I86@PURE_QUANTA.Q_CAP(CHIPS)':
 'A': CDS_PINID='A';
NODE_NAME     C1003 1
 '@S9S_MB_2U_LIB.S9S_MB_2U(SCH_1):PAGE74_I87@PURE_QUANTA.Q_CAP(CHIPS)':
 'A': CDS_PINID='A';
NODE_NAME     C1002 1
 '@S9S_MB_2U_LIB.S9S_MB_2U(SCH_1):PAGE74_I89@PURE_QUANTA.Q_CAP(CHIPS)':
 'A': CDS_PINID='A';
NODE_NAME     C1008 1
 '@S9S_MB_2U_LIB.S9S_MB_2U(SCH_1):PAGE74_I90@PURE_QUANTA.Q_CAP(CHIPS)':
 'A': CDS_PINID='A';
NODE_NAME     C1012 1
 '@S9S_MB_2U_LIB.S9S_MB_2U(SCH_1):PAGE74_I92@PURE_QUANTA.Q_CAP(CHIPS)':
 'A': CDS_PINID='A';
NODE_NAME     C1007 1
 '@S9S_MB_2U_LIB.S9S_MB_2U(SCH_1):PAGE74_I93@PURE_QUANTA.Q_CAP(CHIPS)':
 'A': CDS_PINID='A';
NODE_NAME     C1006 1
 '@S9S_MB_2U_LIB.S9S_MB_2U(SCH_1):PAGE74_I95@PURE_QUANTA.Q_CAP(CHIPS)':
 'A': CDS_PINID='A';
NODE_NAME     C1011 1
 '@S9S_MB_2U_LIB.S9S_MB_2U(SCH_1):PAGE74_I96@PURE_QUANTA.Q_CAP(CHIPS)':
 'A': CDS_PINID='A';
NODE_NAME     C1010 1
 '@S9S_MB_2U_LIB.S9S_MB_2U(SCH_1):PAGE74_I97@PURE_QUANTA.Q_CAP(CHIPS)':
 'A': CDS_PINID='A';
NODE_NAME     C1017 1
 '@S9S_MB_2U_LIB.S9S_MB_2U(SCH_1):PAGE74_I105@PURE_QUANTA.Q_CAP(CHIPS)':
 'A': CDS_PINID='A';
NODE_NAME     C1016 1
 '@S9S_MB_2U_LIB.S9S_MB_2U(SCH_1):PAGE74_I111@PURE_QUANTA.Q_CAP(CHIPS)':
 'A': CDS_PINID='A';
NODE_NAME     C1020 1
 '@S9S_MB_2U_LIB.S9S_MB_2U(SCH_1):PAGE74_I112@PURE_QUANTA.Q_CAP(CHIPS)':
 'A': CDS_PINID='A';
NODE_NAME     C1015 1
 '@S9S_MB_2U_LIB.S9S_MB_2U(SCH_1):PAGE74_I113@PURE_QUANTA.Q_CAP(CHIPS)':
 'A': CDS_PINID='A';
NODE_NAME     C1014 1
 '@S9S_MB_2U_LIB.S9S_MB_2U(SCH_1):PAGE74_I114@PURE_QUANTA.Q_CAP(CHIPS)':
 'A': CDS_PINID='A';
NODE_NAME     C1019 1
 '@S9S_MB_2U_LIB.S9S_MB_2U(SCH_1):PAGE74_I115@PURE_QUANTA.Q_CAP(CHIPS)':
 'A': CDS_PINID='A';
NODE_NAME     C1036 1
 '@S9S_MB_2U_LIB.S9S_MB_2U(SCH_1):PAGE74_I131@PURE_QUANTA.Q_CAP(CHIPS)':
 'A': CDS_PINID='A';
NODE_NAME     C1040 1
 '@S9S_MB_2U_LIB.S9S_MB_2U(SCH_1):PAGE74_I132@PURE_QUANTA.Q_CAP(CHIPS)':
 'A': CDS_PINID='A';
NODE_NAME     C1035 1
 '@S9S_MB_2U_LIB.S9S_MB_2U(SCH_1):PAGE74_I133@PURE_QUANTA.Q_CAP(CHIPS)':
 'A': CDS_PINID='A';
NODE_NAME     C1034 1
 '@S9S_MB_2U_LIB.S9S_MB_2U(SCH_1):PAGE74_I134@PURE_QUANTA.Q_CAP(CHIPS)':
 'A': CDS_PINID='A';
NODE_NAME     C1039 1
 '@S9S_MB_2U_LIB.S9S_MB_2U(SCH_1):PAGE74_I135@PURE_QUANTA.Q_CAP(CHIPS)':
 'A': CDS_PINID='A';
NODE_NAME     C1038 1
 '@S9S_MB_2U_LIB.S9S_MB_2U(SCH_1):PAGE74_I137@PURE_QUANTA.Q_CAP(CHIPS)':
 'A': CDS_PINID='A';
NODE_NAME     C1044 1
 '@S9S_MB_2U_LIB.S9S_MB_2U(SCH_1):PAGE74_I139@PURE_QUANTA.Q_CAP(CHIPS)':
 'A': CDS_PINID='A';
NODE_NAME     C1043 1
 '@S9S_MB_2U_LIB.S9S_MB_2U(SCH_1):PAGE74_I141@PURE_QUANTA.Q_CAP(CHIPS)':
 'A': CDS_PINID='A';
NODE_NAME     C359 1
 '@S9S_MB_2U_LIB.S9S_MB_2U(SCH_1):PAGE75_I25@PURE_QUANTA.Q_CAP(CHIPS)':
 'A': CDS_PINID='A';
NODE_NAME     C362 1
 '@S9S_MB_2U_LIB.S9S_MB_2U(SCH_1):PAGE75_I26@PURE_QUANTA.Q_CAP(CHIPS)':
 'A': CDS_PINID='A';
NODE_NAME     C358 1
 '@S9S_MB_2U_LIB.S9S_MB_2U(SCH_1):PAGE75_I27@PURE_QUANTA.Q_CAP(CHIPS)':
 'A': CDS_PINID='A';
NODE_NAME     C361 1
 '@S9S_MB_2U_LIB.S9S_MB_2U(SCH_1):PAGE75_I28@PURE_QUANTA.Q_CAP(CHIPS)':
 'A': CDS_PINID='A';
NODE_NAME     C368 1
 '@S9S_MB_2U_LIB.S9S_MB_2U(SCH_1):PAGE75_I33@PURE_QUANTA.Q_CAP(CHIPS)':
 'A': CDS_PINID='A';
NODE_NAME     C391 1
 '@S9S_MB_2U_LIB.S9S_MB_2U(SCH_1):PAGE75_I49@PURE_QUANTA.Q_CAP(CHIPS)':
 'A': CDS_PINID='A';
NODE_NAME     C379 1
 '@S9S_MB_2U_LIB.S9S_MB_2U(SCH_1):PAGE75_I50@PURE_QUANTA.Q_CAP(CHIPS)':
 'A': CDS_PINID='A';
NODE_NAME     C393 1
 '@S9S_MB_2U_LIB.S9S_MB_2U(SCH_1):PAGE75_I52@PURE_QUANTA.Q_CAP(CHIPS)':
 'A': CDS_PINID='A';
NODE_NAME     C360 1
 '@S9S_MB_2U_LIB.S9S_MB_2U(SCH_1):PAGE75_I54@PURE_QUANTA.Q_CAP(CHIPS)':
 'A': CDS_PINID='A';
NODE_NAME     C381 1
 '@S9S_MB_2U_LIB.S9S_MB_2U(SCH_1):PAGE75_I67@PURE_QUANTA.Q_CAP(CHIPS)':
 'A': CDS_PINID='A';
NODE_NAME     C396 1
 '@S9S_MB_2U_LIB.S9S_MB_2U(SCH_1):PAGE76_I46@PURE_QUANTA.Q_CAP(CHIPS)':
 'A': CDS_PINID='A';
NODE_NAME     C398 1
 '@S9S_MB_2U_LIB.S9S_MB_2U(SCH_1):PAGE76_I47@PURE_QUANTA.Q_CAP(CHIPS)':
 'A': CDS_PINID='A';
NODE_NAME     PL114 4
 '@S9S_MB_2U_LIB.S9S_MB_2U(SCH_1):PAGE253_I46@PURE_QUANTA.Q_INDUCTOR4P_14(CHIPS)':
 '4': CDS_PINID='\4\';
NODE_NAME     PC16 1
 '@S9S_MB_2U_LIB.S9S_MB_2U(SCH_1):PAGE253_I56@PURE_QUANTA.Q_CAPP(CHIPS)':
 'A': CDS_PINID='A';
NODE_NAME     PC319 1
 '@S9S_MB_2U_LIB.S9S_MB_2U(SCH_1):PAGE253_I62@PURE_QUANTA.Q_CAPP(CHIPS)':
 'A': CDS_PINID='A';
NODE_NAME     PC310_P0_1 1
 '@S9S_MB_2U_LIB.S9S_MB_2U(SCH_1):PAGE253_I84@PURE_QUANTA.Q_CAP(CHIPS)':
 'A': CDS_PINID='A';
NODE_NAME     PL112 4
 '@S9S_MB_2U_LIB.S9S_MB_2U(SCH_1):PAGE254_I50@PURE_QUANTA.Q_INDUCTOR4P_14(CHIPS)':
 '4': CDS_PINID='\4\';
NODE_NAME     PL9 4
 '@S9S_MB_2U_LIB.S9S_MB_2U(SCH_1):PAGE255_I32@PURE_QUANTA.Q_INDUCTOR4P_14(CHIPS)':
 '4': CDS_PINID='\4\';
NODE_NAME     PR142 2
 '@S9S_MB_2U_LIB.S9S_MB_2U(SCH_1):PAGE255_I40@PURE_QUANTA.Q_RES(CHIPS)':
 'B': CDS_PINID='B';
NODE_NAME     PC266_P0_6 1
 '@S9S_MB_2U_LIB.S9S_MB_2U(SCH_1):PAGE255_I42@PURE_QUANTA.Q_CAP(CHIPS)':
 'A': CDS_PINID='A';
NODE_NAME     PC268_P0_6 1
 '@S9S_MB_2U_LIB.S9S_MB_2U(SCH_1):PAGE255_I59@PURE_QUANTA.Q_CAP(CHIPS)':
 'A': CDS_PINID='A';
NODE_NAME     PC242_P0_8 1
 '@S9S_MB_2U_LIB.S9S_MB_2U(SCH_1):PAGE256_I52@PURE_QUANTA.Q_CAP(CHIPS)':
 'A': CDS_PINID='A';
NODE_NAME     PR137 2
 '@S9S_MB_2U_LIB.S9S_MB_2U(SCH_1):PAGE256_I57@PURE_QUANTA.Q_RES(CHIPS)':
 'B': CDS_PINID='B';
NODE_NAME     PL8 4
 '@S9S_MB_2U_LIB.S9S_MB_2U(SCH_1):PAGE256_I58@PURE_QUANTA.Q_INDUCTOR4P_14(CHIPS)':
 '4': CDS_PINID='\4\';
NODE_NAME     C967 1
 '@S9S_MB_2U_LIB.S9S_MB_2U(SCH_1):PAGE74_I25@PURE_QUANTA.Q_CAP(CHIPS)':
 'A': CDS_PINID='A';
NODE_NAME     C966 1
 '@S9S_MB_2U_LIB.S9S_MB_2U(SCH_1):PAGE74_I27@PURE_QUANTA.Q_CAP(CHIPS)':
 'A': CDS_PINID='A';
NODE_NAME     C972 1
 '@S9S_MB_2U_LIB.S9S_MB_2U(SCH_1):PAGE74_I28@PURE_QUANTA.Q_CAP(CHIPS)':
 'A': CDS_PINID='A';
NODE_NAME     C970 1
 '@S9S_MB_2U_LIB.S9S_MB_2U(SCH_1):PAGE74_I31@PURE_QUANTA.Q_CAP(CHIPS)':
 'A': CDS_PINID='A';
NODE_NAME     C217 1
 '@S9S_MB_2U_LIB.S9S_MB_2U(SCH_1):PAGE74_I43@PURE_QUANTA.Q_CAP(CHIPS)':
 'A': CDS_PINID='A';
NODE_NAME     C989 1
 '@S9S_MB_2U_LIB.S9S_MB_2U(SCH_1):PAGE74_I45@PURE_QUANTA.Q_CAP(CHIPS)':
 'A': CDS_PINID='A';
NODE_NAME     C992 1
 '@S9S_MB_2U_LIB.S9S_MB_2U(SCH_1):PAGE74_I55@PURE_QUANTA.Q_CAP(CHIPS)':
 'A': CDS_PINID='A';
NODE_NAME     C987 1
 '@S9S_MB_2U_LIB.S9S_MB_2U(SCH_1):PAGE74_I57@PURE_QUANTA.Q_CAP(CHIPS)':
 'A': CDS_PINID='A';
NODE_NAME     C994 1
 '@S9S_MB_2U_LIB.S9S_MB_2U(SCH_1):PAGE74_I62@PURE_QUANTA.Q_CAP(CHIPS)':
 'A': CDS_PINID='A';
NODE_NAME     C1004 1
 '@S9S_MB_2U_LIB.S9S_MB_2U(SCH_1):PAGE74_I83@PURE_QUANTA.Q_CAP(CHIPS)':
 'A': CDS_PINID='A';
NODE_NAME     C1021 1
 '@S9S_MB_2U_LIB.S9S_MB_2U(SCH_1):PAGE74_I106@PURE_QUANTA.Q_CAP(CHIPS)':
 'A': CDS_PINID='A';
NODE_NAME     C1025 1
 '@S9S_MB_2U_LIB.S9S_MB_2U(SCH_1):PAGE74_I108@PURE_QUANTA.Q_CAP(CHIPS)':
 'A': CDS_PINID='A';
NODE_NAME     C1029 1
 '@S9S_MB_2U_LIB.S9S_MB_2U(SCH_1):PAGE74_I109@PURE_QUANTA.Q_CAP(CHIPS)':
 'A': CDS_PINID='A';
NODE_NAME     C1033 1
 '@S9S_MB_2U_LIB.S9S_MB_2U(SCH_1):PAGE74_I110@PURE_QUANTA.Q_CAP(CHIPS)':
 'A': CDS_PINID='A';
NODE_NAME     C1018 1
 '@S9S_MB_2U_LIB.S9S_MB_2U(SCH_1):PAGE74_I116@PURE_QUANTA.Q_CAP(CHIPS)':
 'A': CDS_PINID='A';
NODE_NAME     C1024 1
 '@S9S_MB_2U_LIB.S9S_MB_2U(SCH_1):PAGE74_I117@PURE_QUANTA.Q_CAP(CHIPS)':
 'A': CDS_PINID='A';
NODE_NAME     C1028 1
 '@S9S_MB_2U_LIB.S9S_MB_2U(SCH_1):PAGE74_I118@PURE_QUANTA.Q_CAP(CHIPS)':
 'A': CDS_PINID='A';
NODE_NAME     C1032 1
 '@S9S_MB_2U_LIB.S9S_MB_2U(SCH_1):PAGE74_I119@PURE_QUANTA.Q_CAP(CHIPS)':
 'A': CDS_PINID='A';
NODE_NAME     C1023 1
 '@S9S_MB_2U_LIB.S9S_MB_2U(SCH_1):PAGE74_I120@PURE_QUANTA.Q_CAP(CHIPS)':
 'A': CDS_PINID='A';
NODE_NAME     C1027 1
 '@S9S_MB_2U_LIB.S9S_MB_2U(SCH_1):PAGE74_I121@PURE_QUANTA.Q_CAP(CHIPS)':
 'A': CDS_PINID='A';
NODE_NAME     C1022 1
 '@S9S_MB_2U_LIB.S9S_MB_2U(SCH_1):PAGE74_I122@PURE_QUANTA.Q_CAP(CHIPS)':
 'A': CDS_PINID='A';
NODE_NAME     C1026 1
 '@S9S_MB_2U_LIB.S9S_MB_2U(SCH_1):PAGE74_I123@PURE_QUANTA.Q_CAP(CHIPS)':
 'A': CDS_PINID='A';
NODE_NAME     C1031 1
 '@S9S_MB_2U_LIB.S9S_MB_2U(SCH_1):PAGE74_I124@PURE_QUANTA.Q_CAP(CHIPS)':
 'A': CDS_PINID='A';
NODE_NAME     C1030 1
 '@S9S_MB_2U_LIB.S9S_MB_2U(SCH_1):PAGE74_I125@PURE_QUANTA.Q_CAP(CHIPS)':
 'A': CDS_PINID='A';
NODE_NAME     C1037 1
 '@S9S_MB_2U_LIB.S9S_MB_2U(SCH_1):PAGE74_I127@PURE_QUANTA.Q_CAP(CHIPS)':
 'A': CDS_PINID='A';
NODE_NAME     C1041 1
 '@S9S_MB_2U_LIB.S9S_MB_2U(SCH_1):PAGE74_I128@PURE_QUANTA.Q_CAP(CHIPS)':
 'A': CDS_PINID='A';
NODE_NAME     C1045 1
 '@S9S_MB_2U_LIB.S9S_MB_2U(SCH_1):PAGE74_I130@PURE_QUANTA.Q_CAP(CHIPS)':
 'A': CDS_PINID='A';
NODE_NAME     C356 1
 '@S9S_MB_2U_LIB.S9S_MB_2U(SCH_1):PAGE75_I21@PURE_QUANTA.Q_CAP(CHIPS)':
 'A': CDS_PINID='A';
NODE_NAME     C355 1
 '@S9S_MB_2U_LIB.S9S_MB_2U(SCH_1):PAGE75_I23@PURE_QUANTA.Q_CAP(CHIPS)':
 'A': CDS_PINID='A';
NODE_NAME     C365 1
 '@S9S_MB_2U_LIB.S9S_MB_2U(SCH_1):PAGE75_I32@PURE_QUANTA.Q_CAP(CHIPS)':
 'A': CDS_PINID='A';
NODE_NAME     C364 1
 '@S9S_MB_2U_LIB.S9S_MB_2U(SCH_1):PAGE75_I34@PURE_QUANTA.Q_CAP(CHIPS)':
 'A': CDS_PINID='A';
NODE_NAME     C367 1
 '@S9S_MB_2U_LIB.S9S_MB_2U(SCH_1):PAGE75_I35@PURE_QUANTA.Q_CAP(CHIPS)':
 'A': CDS_PINID='A';
NODE_NAME     C371 1
 '@S9S_MB_2U_LIB.S9S_MB_2U(SCH_1):PAGE75_I36@PURE_QUANTA.Q_CAP(CHIPS)':
 'A': CDS_PINID='A';
NODE_NAME     C397 1
 '@S9S_MB_2U_LIB.S9S_MB_2U(SCH_1):PAGE75_I37@PURE_QUANTA.Q_CAP(CHIPS)':
 'A': CDS_PINID='A';
NODE_NAME     C357 1
 '@S9S_MB_2U_LIB.S9S_MB_2U(SCH_1):PAGE75_I38@PURE_QUANTA.Q_CAP(CHIPS)':
 'A': CDS_PINID='A';
NODE_NAME     C370 1
 '@S9S_MB_2U_LIB.S9S_MB_2U(SCH_1):PAGE75_I39@PURE_QUANTA.Q_CAP(CHIPS)':
 'A': CDS_PINID='A';
NODE_NAME     C373 1
 '@S9S_MB_2U_LIB.S9S_MB_2U(SCH_1):PAGE75_I40@PURE_QUANTA.Q_CAP(CHIPS)':
 'A': CDS_PINID='A';
NODE_NAME     C376 1
 '@S9S_MB_2U_LIB.S9S_MB_2U(SCH_1):PAGE75_I41@PURE_QUANTA.Q_CAP(CHIPS)':
 'A': CDS_PINID='A';
NODE_NAME     C389 1
 '@S9S_MB_2U_LIB.S9S_MB_2U(SCH_1):PAGE75_I48@PURE_QUANTA.Q_CAP(CHIPS)':
 'A': CDS_PINID='A';
NODE_NAME     C382 1
 '@S9S_MB_2U_LIB.S9S_MB_2U(SCH_1):PAGE75_I51@PURE_QUANTA.Q_CAP(CHIPS)':
 'A': CDS_PINID='A';
NODE_NAME     C385 1
 '@S9S_MB_2U_LIB.S9S_MB_2U(SCH_1):PAGE75_I55@PURE_QUANTA.Q_CAP(CHIPS)':
 'A': CDS_PINID='A';
NODE_NAME     C387 1
 '@S9S_MB_2U_LIB.S9S_MB_2U(SCH_1):PAGE75_I56@PURE_QUANTA.Q_CAP(CHIPS)':
 'A': CDS_PINID='A';
NODE_NAME     C363 1
 '@S9S_MB_2U_LIB.S9S_MB_2U(SCH_1):PAGE75_I64@PURE_QUANTA.Q_CAP(CHIPS)':
 'A': CDS_PINID='A';
NODE_NAME     C527 1
 '@S9S_MB_2U_LIB.S9S_MB_2U(SCH_1):PAGE75_I68@PURE_QUANTA.Q_CAP(CHIPS)':
 'A': CDS_PINID='A';
NODE_NAME     C386 1
 '@S9S_MB_2U_LIB.S9S_MB_2U(SCH_1):PAGE76_I22@PURE_QUANTA.Q_CAP(CHIPS)':
 'A': CDS_PINID='A';
NODE_NAME     C388 1
 '@S9S_MB_2U_LIB.S9S_MB_2U(SCH_1):PAGE76_I23@PURE_QUANTA.Q_CAP(CHIPS)':
 'A': CDS_PINID='A';
NODE_NAME     C390 1
 '@S9S_MB_2U_LIB.S9S_MB_2U(SCH_1):PAGE76_I25@PURE_QUANTA.Q_CAP(CHIPS)':
 'A': CDS_PINID='A';
NODE_NAME     C392 1
 '@S9S_MB_2U_LIB.S9S_MB_2U(SCH_1):PAGE76_I44@PURE_QUANTA.Q_CAP(CHIPS)':
 'A': CDS_PINID='A';
NODE_NAME     C394 1
 '@S9S_MB_2U_LIB.S9S_MB_2U(SCH_1):PAGE76_I45@PURE_QUANTA.Q_CAP(CHIPS)':
 'A': CDS_PINID='A';
NODE_NAME     C366 1
 '@S9S_MB_2U_LIB.S9S_MB_2U(SCH_1):PAGE76_I48@PURE_QUANTA.Q_CAP(CHIPS)':
 'A': CDS_PINID='A';
NODE_NAME     C369 1
 '@S9S_MB_2U_LIB.S9S_MB_2U(SCH_1):PAGE76_I49@PURE_QUANTA.Q_CAP(CHIPS)':
 'A': CDS_PINID='A';
NODE_NAME     C372 1
 '@S9S_MB_2U_LIB.S9S_MB_2U(SCH_1):PAGE76_I50@PURE_QUANTA.Q_CAP(CHIPS)':
 'A': CDS_PINID='A';
NODE_NAME     C374 1
 '@S9S_MB_2U_LIB.S9S_MB_2U(SCH_1):PAGE76_I51@PURE_QUANTA.Q_CAP(CHIPS)':
 'A': CDS_PINID='A';
NODE_NAME     C377 1
 '@S9S_MB_2U_LIB.S9S_MB_2U(SCH_1):PAGE76_I52@PURE_QUANTA.Q_CAP(CHIPS)':
 'A': CDS_PINID='A';
NODE_NAME     C380 1
 '@S9S_MB_2U_LIB.S9S_MB_2U(SCH_1):PAGE76_I53@PURE_QUANTA.Q_CAP(CHIPS)':
 'A': CDS_PINID='A';
NODE_NAME     C383 1
 '@S9S_MB_2U_LIB.S9S_MB_2U(SCH_1):PAGE76_I54@PURE_QUANTA.Q_CAP(CHIPS)':
 'A': CDS_PINID='A';
NODE_NAME     PR531 2
 '@S9S_MB_2U_LIB.S9S_MB_2U(SCH_1):PAGE252_I38@PURE_QUANTA.Q_RES(CHIPS)':
 'B': CDS_PINID='B';
NODE_NAME     PR154 2
 '@S9S_MB_2U_LIB.S9S_MB_2U(SCH_1):PAGE253_I51@PURE_QUANTA.Q_RES(CHIPS)':
 'B': CDS_PINID='B';
NODE_NAME     PC316 1
 '@S9S_MB_2U_LIB.S9S_MB_2U(SCH_1):PAGE253_I61@PURE_QUANTA.Q_CAPP(CHIPS)':
 'A': CDS_PINID='A';
NODE_NAME     PC323 1
 '@S9S_MB_2U_LIB.S9S_MB_2U(SCH_1):PAGE253_I64@PURE_QUANTA.Q_CAPP(CHIPS)':
 'A': CDS_PINID='A';
NODE_NAME     PC325 1
 '@S9S_MB_2U_LIB.S9S_MB_2U(SCH_1):PAGE253_I70@PURE_QUANTA.Q_CAPP(CHIPS)':
 'A': CDS_PINID='A';
NODE_NAME     PR155 2
 '@S9S_MB_2U_LIB.S9S_MB_2U(SCH_1):PAGE253_I73@PURE_QUANTA.Q_RES(CHIPS)':
 'B': CDS_PINID='B';
NODE_NAME     PC314_P0_1 1
 '@S9S_MB_2U_LIB.S9S_MB_2U(SCH_1):PAGE253_I86@PURE_QUANTA.Q_CAP(CHIPS)':
 'A': CDS_PINID='A';
NODE_NAME     PL11 4
 '@S9S_MB_2U_LIB.S9S_MB_2U(SCH_1):PAGE254_I33@PURE_QUANTA.Q_INDUCTOR4P_14(CHIPS)':
 '4': CDS_PINID='\4\';
NODE_NAME     PR148 2
 '@S9S_MB_2U_LIB.S9S_MB_2U(SCH_1):PAGE254_I41@PURE_QUANTA.Q_RES(CHIPS)':
 'B': CDS_PINID='B';
NODE_NAME     PR149 2
 '@S9S_MB_2U_LIB.S9S_MB_2U(SCH_1):PAGE254_I46@PURE_QUANTA.Q_RES(CHIPS)':
 'B': CDS_PINID='B';
NODE_NAME     PC289_P0_3 1
 '@S9S_MB_2U_LIB.S9S_MB_2U(SCH_1):PAGE254_I59@PURE_QUANTA.Q_CAP(CHIPS)':
 'A': CDS_PINID='A';
NODE_NAME     PC288_P0_4 1
 '@S9S_MB_2U_LIB.S9S_MB_2U(SCH_1):PAGE254_I60@PURE_QUANTA.Q_CAP(CHIPS)':
 'A': CDS_PINID='A';
NODE_NAME     PC290_P0_4 1
 '@S9S_MB_2U_LIB.S9S_MB_2U(SCH_1):PAGE254_I61@PURE_QUANTA.Q_CAP(CHIPS)':
 'A': CDS_PINID='A';
NODE_NAME     PC291_P0_3 1
 '@S9S_MB_2U_LIB.S9S_MB_2U(SCH_1):PAGE254_I65@PURE_QUANTA.Q_CAP(CHIPS)':
 'A': CDS_PINID='A';
NODE_NAME     PR143 2
 '@S9S_MB_2U_LIB.S9S_MB_2U(SCH_1):PAGE255_I46@PURE_QUANTA.Q_RES(CHIPS)':
 'B': CDS_PINID='B';
NODE_NAME     PL10 4
 '@S9S_MB_2U_LIB.S9S_MB_2U(SCH_1):PAGE255_I50@PURE_QUANTA.Q_INDUCTOR4P_14(CHIPS)':
 '4': CDS_PINID='\4\';
NODE_NAME     PC267_P0_5 1
 '@S9S_MB_2U_LIB.S9S_MB_2U(SCH_1):PAGE255_I63@PURE_QUANTA.Q_CAP(CHIPS)':
 'A': CDS_PINID='A';
NODE_NAME     PC269_P0_5 1
 '@S9S_MB_2U_LIB.S9S_MB_2U(SCH_1):PAGE255_I64@PURE_QUANTA.Q_CAP(CHIPS)':
 'A': CDS_PINID='A';
NODE_NAME     PL7 4
 '@S9S_MB_2U_LIB.S9S_MB_2U(SCH_1):PAGE256_I44@PURE_QUANTA.Q_INDUCTOR4P_14(CHIPS)':
 '4': CDS_PINID='\4\';
NODE_NAME     PR136 2
 '@S9S_MB_2U_LIB.S9S_MB_2U(SCH_1):PAGE256_I46@PURE_QUANTA.Q_RES(CHIPS)':
 'B': CDS_PINID='B';
NODE_NAME     PC244_P0_8 1
 '@S9S_MB_2U_LIB.S9S_MB_2U(SCH_1):PAGE256_I53@PURE_QUANTA.Q_CAP(CHIPS)':
 'A': CDS_PINID='A';
NODE_NAME     PC246_P0_8 1
 '@S9S_MB_2U_LIB.S9S_MB_2U(SCH_1):PAGE256_I54@PURE_QUANTA.Q_CAP(CHIPS)':
 'A': CDS_PINID='A';
NODE_NAME     PC243_P0_7 1
 '@S9S_MB_2U_LIB.S9S_MB_2U(SCH_1):PAGE256_I62@PURE_QUANTA.Q_CAP(CHIPS)':
 'A': CDS_PINID='A';
NODE_NAME     PC245_P0_7 1
 '@S9S_MB_2U_LIB.S9S_MB_2U(SCH_1):PAGE256_I66@PURE_QUANTA.Q_CAP(CHIPS)':
 'A': CDS_PINID='A';
NODE_NAME     PC247_P0_7 1
 '@S9S_MB_2U_LIB.S9S_MB_2U(SCH_1):PAGE256_I67@PURE_QUANTA.Q_CAP(CHIPS)':
 'A': CDS_PINID='A';
NODE_NAME     PL13 4
 '@S9S_MB_2U_LIB.S9S_MB_2U(SCH_1):PAGE253_I21@PURE_QUANTA.Q_INDUCTOR4P_14(CHIPS)':
 '4': CDS_PINID='\4\';
NODE_NAME     PR4219 1
 '@S9S_MB_2U_LIB.S9S_MB_2U(SCH_1):PAGE253_I59@PURE_QUANTA.Q_RES(CHIPS)':
 'A': CDS_PINID='A';
NODE_NAME     PC1920 1
 '@S9S_MB_2U_LIB.S9S_MB_2U(SCH_1):PAGE253_I63@PURE_QUANTA.Q_CAPP(CHIPS)':
 'A': CDS_PINID='A';
NODE_NAME     PC326 1
 '@S9S_MB_2U_LIB.S9S_MB_2U(SCH_1):PAGE253_I66@PURE_QUANTA.Q_CAPP(CHIPS)':
 'A': CDS_PINID='A';
NODE_NAME     PC322 1
 '@S9S_MB_2U_LIB.S9S_MB_2U(SCH_1):PAGE253_I67@PURE_QUANTA.Q_CAPP(CHIPS)':
 'A': CDS_PINID='A';
NODE_NAME     PC311_P0_2 1
 '@S9S_MB_2U_LIB.S9S_MB_2U(SCH_1):PAGE253_I57@PURE_QUANTA.Q_CAP(CHIPS)':
 'A': CDS_PINID='A';
NODE_NAME     PC313_P0_2 1
 '@S9S_MB_2U_LIB.S9S_MB_2U(SCH_1):PAGE253_I58@PURE_QUANTA.Q_CAP(CHIPS)':
 'A': CDS_PINID='A';
NODE_NAME     PC2336 1
 '@S9S_MB_2U_LIB.S9S_MB_2U(SCH_1):PAGE253_I60@PURE_QUANTA.Q_CAPP(CHIPS)':
 'A': CDS_PINID='A';
NODE_NAME     PC308_P0_1 1
 '@S9S_MB_2U_LIB.S9S_MB_2U(SCH_1):PAGE253_I83@PURE_QUANTA.Q_CAP(CHIPS)':
 'A': CDS_PINID='A';
NODE_NAME     PC312_P0_1 1
 '@S9S_MB_2U_LIB.S9S_MB_2U(SCH_1):PAGE253_I85@PURE_QUANTA.Q_CAP(CHIPS)':
 'A': CDS_PINID='A';
NET_NAME
'PVCCIN_CPU0_ADDR'
 '@S9S_MB_2U_LIB.S9S_MB_2U(SCH_1):PVCCIN_CPU0_ADDR':
 C_SIGNAL='@s9s_mb_2u_lib.s9s_mb_2u(sch_1):pvccin_cpu0_addr';
NODE_NAME     PU14 42
 '@S9S_MB_2U_LIB.S9S_MB_2U(SCH_1):PAGE252_I63@PURE_QUANTA.RAA229126GNPHA0(CHIPS)':
 'ADDR_CFG': CDS_PINID='ADDR_CFG';
NODE_NAME     PR159 2
 '@S9S_MB_2U_LIB.S9S_MB_2U(SCH_1):PAGE252_I5@PURE_QUANTA.Q_RES(CHIPS)':
 'B': CDS_PINID='B';
NODE_NAME     PR171 1
 '@S9S_MB_2U_LIB.S9S_MB_2U(SCH_1):PAGE252_I8@PURE_QUANTA.Q_RES(CHIPS)':
 'A': CDS_PINID='A';
NET_NAME
'PVCCIN_CPU0_ATSEN'
 '@S9S_MB_2U_LIB.S9S_MB_2U(SCH_1):PVCCIN_CPU0_ATSEN':
 C_SIGNAL='@s9s_mb_2u_lib.s9s_mb_2u(sch_1):pvccin_cpu0_atsen';
NODE_NAME     PU13_P0_1 36
 '@S9S_MB_2U_LIB.S9S_MB_2U(SCH_1):PAGE253_I40@PURE_QUANTA.ISL99390FRZTR5935(CHIPS)':
 'TOUT_FLT': CDS_PINID='TOUT_FLT';
NODE_NAME     PU10_P0_4 36
 '@S9S_MB_2U_LIB.S9S_MB_2U(SCH_1):PAGE254_I13@PURE_QUANTA.ISL99390FRZTR5935(CHIPS)':
 'TOUT_FLT': CDS_PINID='TOUT_FLT';
NODE_NAME     PU8_P0_6 36
 '@S9S_MB_2U_LIB.S9S_MB_2U(SCH_1):PAGE255_I12@PURE_QUANTA.ISL99390FRZTR5935(CHIPS)':
 'TOUT_FLT': CDS_PINID='TOUT_FLT';
NODE_NAME     PU6_P0_8 36
 '@S9S_MB_2U_LIB.S9S_MB_2U(SCH_1):PAGE256_I2@PURE_QUANTA.ISL99390FRZTR5935(CHIPS)':
 'TOUT_FLT': CDS_PINID='TOUT_FLT';
NODE_NAME     PU11_P0_3 36
 '@S9S_MB_2U_LIB.S9S_MB_2U(SCH_1):PAGE254_I20@PURE_QUANTA.ISL99390FRZTR5935(CHIPS)':
 'TOUT_FLT': CDS_PINID='TOUT_FLT';
NODE_NAME     PU9_P0_5 36
 '@S9S_MB_2U_LIB.S9S_MB_2U(SCH_1):PAGE255_I66@PURE_QUANTA.ISL99390FRZTR5935(CHIPS)':
 'TOUT_FLT': CDS_PINID='TOUT_FLT';
NODE_NAME     PU7_P0_7 36
 '@S9S_MB_2U_LIB.S9S_MB_2U(SCH_1):PAGE256_I32@PURE_QUANTA.ISL99390FRZTR5935(CHIPS)':
 'TOUT_FLT': CDS_PINID='TOUT_FLT';
NODE_NAME     PU14 43
 '@S9S_MB_2U_LIB.S9S_MB_2U(SCH_1):PAGE252_I63@PURE_QUANTA.RAA229126GNPHA0(CHIPS)':
 'TEMP0': CDS_PINID='TEMP0';
NODE_NAME     PU12_P0_2 36
 '@S9S_MB_2U_LIB.S9S_MB_2U(SCH_1):PAGE253_I6@PURE_QUANTA.ISL99390FRZTR5935(CHIPS)':
 'TOUT_FLT': CDS_PINID='TOUT_FLT';
NODE_NAME     PC336 1
 '@S9S_MB_2U_LIB.S9S_MB_2U(SCH_1):PAGE252_I70@PURE_QUANTA.Q_CAP(CHIPS)':
 'A': CDS_PINID='A';
NODE_NAME     PR400 1
 '@S9S_MB_2U_LIB.S9S_MB_2U(SCH_1):PAGE252_I72@PURE_QUANTA.Q_RES(CHIPS)':
 'A': CDS_PINID='A';
NET_NAME
'PVCCIN_CPU0_CSPIN'
 '@S9S_MB_2U_LIB.S9S_MB_2U(SCH_1):PVCCIN_CPU0_CSPIN':
 C_SIGNAL='@s9s_mb_2u_lib.s9s_mb_2u(sch_1):pvccin_cpu0_cspin';
NODE_NAME     PR158 1
 '@S9S_MB_2U_LIB.S9S_MB_2U(SCH_1):PAGE252_I51@PURE_QUANTA.Q_RES(CHIPS)':
 'A': CDS_PINID='A';
NODE_NAME     PU14 45
 '@S9S_MB_2U_LIB.S9S_MB_2U(SCH_1):PAGE252_I63@PURE_QUANTA.RAA229126GNPHA0(CHIPS)':
 'VMON||IINSEN||VSYS||ISYS': CDS_PINID='\vmon||iinsen||vsys||isys\';
NODE_NAME     PR157 2
 '@S9S_MB_2U_LIB.S9S_MB_2U(SCH_1):PAGE252_I11@PURE_QUANTA.Q_RES(CHIPS)':
 'B': CDS_PINID='B';
NODE_NAME     PC329 1
 '@S9S_MB_2U_LIB.S9S_MB_2U(SCH_1):PAGE252_I53@PURE_QUANTA.Q_CAP(CHIPS)':
 'A': CDS_PINID='A';
NET_NAME
'PVCCIN_CPU0_EN_R'
 '@S9S_MB_2U_LIB.S9S_MB_2U(SCH_1):PVCCIN_CPU0_EN_R':
 C_SIGNAL='@s9s_mb_2u_lib.s9s_mb_2u(sch_1):pvccin_cpu0_en_r';
NODE_NAME     PU14 17
 '@S9S_MB_2U_LIB.S9S_MB_2U(SCH_1):PAGE252_I63@PURE_QUANTA.RAA229126GNPHA0(CHIPS)':
 'EN0': CDS_PINID='EN0';
NODE_NAME     R2591 2
 '@S9S_MB_2U_LIB.S9S_MB_2U(SCH_1):PAGE252_I48@PURE_QUANTA.Q_RES(CHIPS)':
 'B': CDS_PINID='B';
NODE_NAME     C3267 1
 '@S9S_MB_2U_LIB.S9S_MB_2U(SCH_1):PAGE252_I82@PURE_QUANTA.Q_CAP(CHIPS)':
 'A': CDS_PINID='A';
NET_NAME
'PVCCIN_CPU0_IMON1'
 '@S9S_MB_2U_LIB.S9S_MB_2U(SCH_1):PVCCIN_CPU0_IMON1':
 C_SIGNAL='@s9s_mb_2u_lib.s9s_mb_2u(sch_1):pvccin_cpu0_imon1';
NODE_NAME     PU13_P0_1 38
 '@S9S_MB_2U_LIB.S9S_MB_2U(SCH_1):PAGE253_I40@PURE_QUANTA.ISL99390FRZTR5935(CHIPS)':
 'IOUT': CDS_PINID='IOUT';
NODE_NAME     PU14 27
 '@S9S_MB_2U_LIB.S9S_MB_2U(SCH_1):PAGE252_I63@PURE_QUANTA.RAA229126GNPHA0(CHIPS)':
 'CS11': CDS_PINID='CS11';
NET_NAME
'PVCCIN_CPU0_IMON2'
 '@S9S_MB_2U_LIB.S9S_MB_2U(SCH_1):PVCCIN_CPU0_IMON2':
 C_SIGNAL='@s9s_mb_2u_lib.s9s_mb_2u(sch_1):pvccin_cpu0_imon2';
NODE_NAME     PU14 28
 '@S9S_MB_2U_LIB.S9S_MB_2U(SCH_1):PAGE252_I63@PURE_QUANTA.RAA229126GNPHA0(CHIPS)':
 'CS10': CDS_PINID='CS10';
NODE_NAME     PU12_P0_2 38
 '@S9S_MB_2U_LIB.S9S_MB_2U(SCH_1):PAGE253_I6@PURE_QUANTA.ISL99390FRZTR5935(CHIPS)':
 'IOUT': CDS_PINID='IOUT';
NET_NAME
'PVCCIN_CPU0_IMON3'
 '@S9S_MB_2U_LIB.S9S_MB_2U(SCH_1):PVCCIN_CPU0_IMON3':
 C_SIGNAL='@s9s_mb_2u_lib.s9s_mb_2u(sch_1):pvccin_cpu0_imon3';
NODE_NAME     PU11_P0_3 38
 '@S9S_MB_2U_LIB.S9S_MB_2U(SCH_1):PAGE254_I20@PURE_QUANTA.ISL99390FRZTR5935(CHIPS)':
 'IOUT': CDS_PINID='IOUT';
NODE_NAME     PU14 29
 '@S9S_MB_2U_LIB.S9S_MB_2U(SCH_1):PAGE252_I63@PURE_QUANTA.RAA229126GNPHA0(CHIPS)':
 'CS9': CDS_PINID='CS9';
NET_NAME
'PVCCIN_CPU0_IMON4'
 '@S9S_MB_2U_LIB.S9S_MB_2U(SCH_1):PVCCIN_CPU0_IMON4':
 C_SIGNAL='@s9s_mb_2u_lib.s9s_mb_2u(sch_1):pvccin_cpu0_imon4';
NODE_NAME     PU10_P0_4 38
 '@S9S_MB_2U_LIB.S9S_MB_2U(SCH_1):PAGE254_I13@PURE_QUANTA.ISL99390FRZTR5935(CHIPS)':
 'IOUT': CDS_PINID='IOUT';
NODE_NAME     PU14 30
 '@S9S_MB_2U_LIB.S9S_MB_2U(SCH_1):PAGE252_I63@PURE_QUANTA.RAA229126GNPHA0(CHIPS)':
 'CS8': CDS_PINID='CS8';
NET_NAME
'PVCCIN_CPU0_IMON5'
 '@S9S_MB_2U_LIB.S9S_MB_2U(SCH_1):PVCCIN_CPU0_IMON5':
 C_SIGNAL='@s9s_mb_2u_lib.s9s_mb_2u(sch_1):pvccin_cpu0_imon5';
NODE_NAME     PU9_P0_5 38
 '@S9S_MB_2U_LIB.S9S_MB_2U(SCH_1):PAGE255_I66@PURE_QUANTA.ISL99390FRZTR5935(CHIPS)':
 'IOUT': CDS_PINID='IOUT';
NODE_NAME     PU14 31
 '@S9S_MB_2U_LIB.S9S_MB_2U(SCH_1):PAGE252_I63@PURE_QUANTA.RAA229126GNPHA0(CHIPS)':
 'CS7': CDS_PINID='CS7';
NET_NAME
'PVCCIN_CPU0_IMON6'
 '@S9S_MB_2U_LIB.S9S_MB_2U(SCH_1):PVCCIN_CPU0_IMON6':
 C_SIGNAL='@s9s_mb_2u_lib.s9s_mb_2u(sch_1):pvccin_cpu0_imon6';
NODE_NAME     PU8_P0_6 38
 '@S9S_MB_2U_LIB.S9S_MB_2U(SCH_1):PAGE255_I12@PURE_QUANTA.ISL99390FRZTR5935(CHIPS)':
 'IOUT': CDS_PINID='IOUT';
NODE_NAME     PU14 32
 '@S9S_MB_2U_LIB.S9S_MB_2U(SCH_1):PAGE252_I63@PURE_QUANTA.RAA229126GNPHA0(CHIPS)':
 'CS6': CDS_PINID='CS6';
NET_NAME
'PVCCIN_CPU0_IMON7'
 '@S9S_MB_2U_LIB.S9S_MB_2U(SCH_1):PVCCIN_CPU0_IMON7':
 C_SIGNAL='@s9s_mb_2u_lib.s9s_mb_2u(sch_1):pvccin_cpu0_imon7';
NODE_NAME     PU7_P0_7 38
 '@S9S_MB_2U_LIB.S9S_MB_2U(SCH_1):PAGE256_I32@PURE_QUANTA.ISL99390FRZTR5935(CHIPS)':
 'IOUT': CDS_PINID='IOUT';
NODE_NAME     PU14 33
 '@S9S_MB_2U_LIB.S9S_MB_2U(SCH_1):PAGE252_I63@PURE_QUANTA.RAA229126GNPHA0(CHIPS)':
 'CS5': CDS_PINID='CS5';
NET_NAME
'PVCCIN_CPU0_IMON8'
 '@S9S_MB_2U_LIB.S9S_MB_2U(SCH_1):PVCCIN_CPU0_IMON8':
 C_SIGNAL='@s9s_mb_2u_lib.s9s_mb_2u(sch_1):pvccin_cpu0_imon8';
NODE_NAME     PU6_P0_8 38
 '@S9S_MB_2U_LIB.S9S_MB_2U(SCH_1):PAGE256_I2@PURE_QUANTA.ISL99390FRZTR5935(CHIPS)':
 'IOUT': CDS_PINID='IOUT';
NODE_NAME     PU14 34
 '@S9S_MB_2U_LIB.S9S_MB_2U(SCH_1):PAGE252_I63@PURE_QUANTA.RAA229126GNPHA0(CHIPS)':
 'CS4': CDS_PINID='CS4';
NET_NAME
'PVCCIN_CPU0_LSET1'
 '@S9S_MB_2U_LIB.S9S_MB_2U(SCH_1):PVCCIN_CPU0_LSET1':
 C_SIGNAL='@s9s_mb_2u_lib.s9s_mb_2u(sch_1):pvccin_cpu0_lset1';
NODE_NAME     PU13_P0_1 37
 '@S9S_MB_2U_LIB.S9S_MB_2U(SCH_1):PAGE253_I40@PURE_QUANTA.ISL99390FRZTR5935(CHIPS)':
 'LSET': CDS_PINID='LSET';
NODE_NAME     PR151 1
 '@S9S_MB_2U_LIB.S9S_MB_2U(SCH_1):PAGE253_I29@PURE_QUANTA.Q_RES(CHIPS)':
 'A': CDS_PINID='A';
NET_NAME
'PVCCIN_CPU0_LSET2'
 '@S9S_MB_2U_LIB.S9S_MB_2U(SCH_1):PVCCIN_CPU0_LSET2':
 C_SIGNAL='@s9s_mb_2u_lib.s9s_mb_2u(sch_1):pvccin_cpu0_lset2';
NODE_NAME     PR150 1
 '@S9S_MB_2U_LIB.S9S_MB_2U(SCH_1):PAGE253_I2@PURE_QUANTA.Q_RES(CHIPS)':
 'A': CDS_PINID='A';
NODE_NAME     PU12_P0_2 37
 '@S9S_MB_2U_LIB.S9S_MB_2U(SCH_1):PAGE253_I6@PURE_QUANTA.ISL99390FRZTR5935(CHIPS)':
 'LSET': CDS_PINID='LSET';
NET_NAME
'PVCCIN_CPU0_LSET3'
 '@S9S_MB_2U_LIB.S9S_MB_2U(SCH_1):PVCCIN_CPU0_LSET3':
 C_SIGNAL='@s9s_mb_2u_lib.s9s_mb_2u(sch_1):pvccin_cpu0_lset3';
NODE_NAME     PR145 1
 '@S9S_MB_2U_LIB.S9S_MB_2U(SCH_1):PAGE254_I4@PURE_QUANTA.Q_RES(CHIPS)':
 'A': CDS_PINID='A';
NODE_NAME     PU11_P0_3 37
 '@S9S_MB_2U_LIB.S9S_MB_2U(SCH_1):PAGE254_I20@PURE_QUANTA.ISL99390FRZTR5935(CHIPS)':
 'LSET': CDS_PINID='LSET';
NET_NAME
'PVCCIN_CPU0_LSET4'
 '@S9S_MB_2U_LIB.S9S_MB_2U(SCH_1):PVCCIN_CPU0_LSET4':
 C_SIGNAL='@s9s_mb_2u_lib.s9s_mb_2u(sch_1):pvccin_cpu0_lset4';
NODE_NAME     PR144 1
 '@S9S_MB_2U_LIB.S9S_MB_2U(SCH_1):PAGE254_I2@PURE_QUANTA.Q_RES(CHIPS)':
 'A': CDS_PINID='A';
NODE_NAME     PU10_P0_4 37
 '@S9S_MB_2U_LIB.S9S_MB_2U(SCH_1):PAGE254_I13@PURE_QUANTA.ISL99390FRZTR5935(CHIPS)':
 'LSET': CDS_PINID='LSET';
NET_NAME
'PVCCIN_CPU0_LSET5'
 '@S9S_MB_2U_LIB.S9S_MB_2U(SCH_1):PVCCIN_CPU0_LSET5':
 C_SIGNAL='@s9s_mb_2u_lib.s9s_mb_2u(sch_1):pvccin_cpu0_lset5';
NODE_NAME     PR139 1
 '@S9S_MB_2U_LIB.S9S_MB_2U(SCH_1):PAGE255_I4@PURE_QUANTA.Q_RES(CHIPS)':
 'A': CDS_PINID='A';
NODE_NAME     PU9_P0_5 37
 '@S9S_MB_2U_LIB.S9S_MB_2U(SCH_1):PAGE255_I66@PURE_QUANTA.ISL99390FRZTR5935(CHIPS)':
 'LSET': CDS_PINID='LSET';
NET_NAME
'PVCCIN_CPU0_LSET6'
 '@S9S_MB_2U_LIB.S9S_MB_2U(SCH_1):PVCCIN_CPU0_LSET6':
 C_SIGNAL='@s9s_mb_2u_lib.s9s_mb_2u(sch_1):pvccin_cpu0_lset6';
NODE_NAME     PR138 1
 '@S9S_MB_2U_LIB.S9S_MB_2U(SCH_1):PAGE255_I2@PURE_QUANTA.Q_RES(CHIPS)':
 'A': CDS_PINID='A';
NODE_NAME     PU8_P0_6 37
 '@S9S_MB_2U_LIB.S9S_MB_2U(SCH_1):PAGE255_I12@PURE_QUANTA.ISL99390FRZTR5935(CHIPS)':
 'LSET': CDS_PINID='LSET';
NET_NAME
'PVCCIN_CPU0_LSET7'
 '@S9S_MB_2U_LIB.S9S_MB_2U(SCH_1):PVCCIN_CPU0_LSET7':
 C_SIGNAL='@s9s_mb_2u_lib.s9s_mb_2u(sch_1):pvccin_cpu0_lset7';
NODE_NAME     PR133 1
 '@S9S_MB_2U_LIB.S9S_MB_2U(SCH_1):PAGE256_I23@PURE_QUANTA.Q_RES(CHIPS)':
 'A': CDS_PINID='A';
NODE_NAME     PU7_P0_7 37
 '@S9S_MB_2U_LIB.S9S_MB_2U(SCH_1):PAGE256_I32@PURE_QUANTA.ISL99390FRZTR5935(CHIPS)':
 'LSET': CDS_PINID='LSET';
NET_NAME
'PVCCIN_CPU0_LSET8'
 '@S9S_MB_2U_LIB.S9S_MB_2U(SCH_1):PVCCIN_CPU0_LSET8':
 C_SIGNAL='@s9s_mb_2u_lib.s9s_mb_2u(sch_1):pvccin_cpu0_lset8';
NODE_NAME     PU6_P0_8 37
 '@S9S_MB_2U_LIB.S9S_MB_2U(SCH_1):PAGE256_I2@PURE_QUANTA.ISL99390FRZTR5935(CHIPS)':
 'LSET': CDS_PINID='LSET';
NODE_NAME     PR132 1
 '@S9S_MB_2U_LIB.S9S_MB_2U(SCH_1):PAGE256_I4@PURE_QUANTA.Q_RES(CHIPS)':
 'A': CDS_PINID='A';
NET_NAME
'PVCCIN_CPU0_PIN_ALERT'
 '@S9S_MB_2U_LIB.S9S_MB_2U(SCH_1):PVCCIN_CPU0_PIN_ALERT':
 C_SIGNAL='@s9s_mb_2u_lib.s9s_mb_2u(sch_1):pvccin_cpu0_pin_alert';
NODE_NAME     R2375 2
 '@S9S_MB_2U_LIB.S9S_MB_2U(SCH_1):PAGE252_I19@PURE_QUANTA.Q_RES(CHIPS)':
 'B': CDS_PINID='B';
NODE_NAME     PU14 19
 '@S9S_MB_2U_LIB.S9S_MB_2U(SCH_1):PAGE252_I63@PURE_QUANTA.RAA229126GNPHA0(CHIPS)':
 'NPINALERT||NPSYS_CRIT': CDS_PINID='\npinalert||npsys_crit\';
NODE_NAME     R2376 2
 '@S9S_MB_2U_LIB.S9S_MB_2U(SCH_1):PAGE252_I17@PURE_QUANTA.Q_RES(CHIPS)':
 'B': CDS_PINID='B';
NET_NAME
'PVCCIN_CPU0_PVCC'
 '@S9S_MB_2U_LIB.S9S_MB_2U(SCH_1):PVCCIN_CPU0_PVCC':
 C_SIGNAL='@s9s_mb_2u_lib.s9s_mb_2u(sch_1):pvccin_cpu0_pvcc',
 CDS_GLOBAL_NET='TRUE';
NODE_NAME     PC295_P0_1 1
 '@S9S_MB_2U_LIB.S9S_MB_2U(SCH_1):PAGE253_I39@PURE_QUANTA.Q_CAP(CHIPS)':
 'A': CDS_PINID='A';
NODE_NAME     PU13_P0_1 4
 '@S9S_MB_2U_LIB.S9S_MB_2U(SCH_1):PAGE253_I40@PURE_QUANTA.ISL99390FRZTR5935(CHIPS)':
 'PVCC': CDS_PINID='PVCC';
NODE_NAME     PU10_P0_4 4
 '@S9S_MB_2U_LIB.S9S_MB_2U(SCH_1):PAGE254_I13@PURE_QUANTA.ISL99390FRZTR5935(CHIPS)':
 'PVCC': CDS_PINID='PVCC';
NODE_NAME     PR146 1
 '@S9S_MB_2U_LIB.S9S_MB_2U(SCH_1):PAGE254_I14@PURE_QUANTA.Q_RES(CHIPS)':
 'A': CDS_PINID='A';
NODE_NAME     PC272_P0_4 1
 '@S9S_MB_2U_LIB.S9S_MB_2U(SCH_1):PAGE254_I17@PURE_QUANTA.Q_CAP(CHIPS)':
 'A': CDS_PINID='A';
NODE_NAME     PR147 1
 '@S9S_MB_2U_LIB.S9S_MB_2U(SCH_1):PAGE254_I27@PURE_QUANTA.Q_RES(CHIPS)':
 'A': CDS_PINID='A';
NODE_NAME     PC273_P0_3 1
 '@S9S_MB_2U_LIB.S9S_MB_2U(SCH_1):PAGE254_I30@PURE_QUANTA.Q_CAP(CHIPS)':
 'A': CDS_PINID='A';
NODE_NAME     PU8_P0_6 4
 '@S9S_MB_2U_LIB.S9S_MB_2U(SCH_1):PAGE255_I12@PURE_QUANTA.ISL99390FRZTR5935(CHIPS)':
 'PVCC': CDS_PINID='PVCC';
NODE_NAME     PC250_P0_6 1
 '@S9S_MB_2U_LIB.S9S_MB_2U(SCH_1):PAGE255_I17@PURE_QUANTA.Q_CAP(CHIPS)':
 'A': CDS_PINID='A';
NODE_NAME     PU6_P0_8 4
 '@S9S_MB_2U_LIB.S9S_MB_2U(SCH_1):PAGE256_I2@PURE_QUANTA.ISL99390FRZTR5935(CHIPS)':
 'PVCC': CDS_PINID='PVCC';
NODE_NAME     PR135 1
 '@S9S_MB_2U_LIB.S9S_MB_2U(SCH_1):PAGE256_I33@PURE_QUANTA.Q_RES(CHIPS)':
 'A': CDS_PINID='A';
NODE_NAME     PC229_P0_7 1
 '@S9S_MB_2U_LIB.S9S_MB_2U(SCH_1):PAGE256_I36@PURE_QUANTA.Q_CAP(CHIPS)':
 'A': CDS_PINID='A';
NODE_NAME     PR153 1
 '@S9S_MB_2U_LIB.S9S_MB_2U(SCH_1):PAGE253_I37@PURE_QUANTA.Q_RES(CHIPS)':
 'A': CDS_PINID='A';
NODE_NAME     PU11_P0_3 4
 '@S9S_MB_2U_LIB.S9S_MB_2U(SCH_1):PAGE254_I20@PURE_QUANTA.ISL99390FRZTR5935(CHIPS)':
 'PVCC': CDS_PINID='PVCC';
NODE_NAME     PR140 1
 '@S9S_MB_2U_LIB.S9S_MB_2U(SCH_1):PAGE255_I14@PURE_QUANTA.Q_RES(CHIPS)':
 'A': CDS_PINID='A';
NODE_NAME     PR141 1
 '@S9S_MB_2U_LIB.S9S_MB_2U(SCH_1):PAGE255_I26@PURE_QUANTA.Q_RES(CHIPS)':
 'A': CDS_PINID='A';
NODE_NAME     PC251_P0_5 1
 '@S9S_MB_2U_LIB.S9S_MB_2U(SCH_1):PAGE255_I29@PURE_QUANTA.Q_CAP(CHIPS)':
 'A': CDS_PINID='A';
NODE_NAME     PU9_P0_5 4
 '@S9S_MB_2U_LIB.S9S_MB_2U(SCH_1):PAGE255_I66@PURE_QUANTA.ISL99390FRZTR5935(CHIPS)':
 'PVCC': CDS_PINID='PVCC';
NODE_NAME     PR134 1
 '@S9S_MB_2U_LIB.S9S_MB_2U(SCH_1):PAGE256_I12@PURE_QUANTA.Q_RES(CHIPS)':
 'A': CDS_PINID='A';
NODE_NAME     PC228_P0_8 1
 '@S9S_MB_2U_LIB.S9S_MB_2U(SCH_1):PAGE256_I15@PURE_QUANTA.Q_CAP(CHIPS)':
 'A': CDS_PINID='A';
NODE_NAME     PU7_P0_7 4
 '@S9S_MB_2U_LIB.S9S_MB_2U(SCH_1):PAGE256_I32@PURE_QUANTA.ISL99390FRZTR5935(CHIPS)':
 'PVCC': CDS_PINID='PVCC';
NODE_NAME     PR402 2
 '@S9S_MB_2U_LIB.S9S_MB_2U(SCH_1):PAGE253_I26@PURE_QUANTA.Q_RES(CHIPS)':
 'B': CDS_PINID='B';
NODE_NAME     PU12_P0_2 4
 '@S9S_MB_2U_LIB.S9S_MB_2U(SCH_1):PAGE253_I6@PURE_QUANTA.ISL99390FRZTR5935(CHIPS)':
 'PVCC': CDS_PINID='PVCC';
NODE_NAME     PR152 1
 '@S9S_MB_2U_LIB.S9S_MB_2U(SCH_1):PAGE253_I12@PURE_QUANTA.Q_RES(CHIPS)':
 'A': CDS_PINID='A';
NODE_NAME     PC294_P0_2 1
 '@S9S_MB_2U_LIB.S9S_MB_2U(SCH_1):PAGE253_I15@PURE_QUANTA.Q_CAP(CHIPS)':
 'A': CDS_PINID='A';
NODE_NAME     PR403 2
 '@S9S_MB_2U_LIB.S9S_MB_2U(SCH_1):PAGE253_I42@PURE_QUANTA.Q_RES(CHIPS)':
 'B': CDS_PINID='B';
NET_NAME
'PVCCIN_CPU0_PWM1'
 '@S9S_MB_2U_LIB.S9S_MB_2U(SCH_1):PVCCIN_CPU0_PWM1':
 C_SIGNAL='@s9s_mb_2u_lib.s9s_mb_2u(sch_1):pvccin_cpu0_pwm1';
NODE_NAME     PU13_P0_1 34
 '@S9S_MB_2U_LIB.S9S_MB_2U(SCH_1):PAGE253_I40@PURE_QUANTA.ISL99390FRZTR5935(CHIPS)':
 'PWM': CDS_PINID='PWM';
NODE_NAME     PU14 12
 '@S9S_MB_2U_LIB.S9S_MB_2U(SCH_1):PAGE252_I63@PURE_QUANTA.RAA229126GNPHA0(CHIPS)':
 'PWM11': CDS_PINID='PWM11';
NET_NAME
'PVCCIN_CPU0_PWM2'
 '@S9S_MB_2U_LIB.S9S_MB_2U(SCH_1):PVCCIN_CPU0_PWM2':
 C_SIGNAL='@s9s_mb_2u_lib.s9s_mb_2u(sch_1):pvccin_cpu0_pwm2';
NODE_NAME     PU14 11
 '@S9S_MB_2U_LIB.S9S_MB_2U(SCH_1):PAGE252_I63@PURE_QUANTA.RAA229126GNPHA0(CHIPS)':
 'PWM10': CDS_PINID='PWM10';
NODE_NAME     PU12_P0_2 34
 '@S9S_MB_2U_LIB.S9S_MB_2U(SCH_1):PAGE253_I6@PURE_QUANTA.ISL99390FRZTR5935(CHIPS)':
 'PWM': CDS_PINID='PWM';
NET_NAME
'PVCCIN_CPU0_PWM3'
 '@S9S_MB_2U_LIB.S9S_MB_2U(SCH_1):PVCCIN_CPU0_PWM3':
 C_SIGNAL='@s9s_mb_2u_lib.s9s_mb_2u(sch_1):pvccin_cpu0_pwm3';
NODE_NAME     PU11_P0_3 34
 '@S9S_MB_2U_LIB.S9S_MB_2U(SCH_1):PAGE254_I20@PURE_QUANTA.ISL99390FRZTR5935(CHIPS)':
 'PWM': CDS_PINID='PWM';
NODE_NAME     PU14 10
 '@S9S_MB_2U_LIB.S9S_MB_2U(SCH_1):PAGE252_I63@PURE_QUANTA.RAA229126GNPHA0(CHIPS)':
 'PWM9': CDS_PINID='PWM9';
NET_NAME
'PVCCIN_CPU0_PWM4'
 '@S9S_MB_2U_LIB.S9S_MB_2U(SCH_1):PVCCIN_CPU0_PWM4':
 C_SIGNAL='@s9s_mb_2u_lib.s9s_mb_2u(sch_1):pvccin_cpu0_pwm4';
NODE_NAME     PU10_P0_4 34
 '@S9S_MB_2U_LIB.S9S_MB_2U(SCH_1):PAGE254_I13@PURE_QUANTA.ISL99390FRZTR5935(CHIPS)':
 'PWM': CDS_PINID='PWM';
NODE_NAME     PU14 9
 '@S9S_MB_2U_LIB.S9S_MB_2U(SCH_1):PAGE252_I63@PURE_QUANTA.RAA229126GNPHA0(CHIPS)':
 'PWM8': CDS_PINID='PWM8';
NET_NAME
'PVCCIN_CPU0_PWM5'
 '@S9S_MB_2U_LIB.S9S_MB_2U(SCH_1):PVCCIN_CPU0_PWM5':
 C_SIGNAL='@s9s_mb_2u_lib.s9s_mb_2u(sch_1):pvccin_cpu0_pwm5';
NODE_NAME     PU9_P0_5 34
 '@S9S_MB_2U_LIB.S9S_MB_2U(SCH_1):PAGE255_I66@PURE_QUANTA.ISL99390FRZTR5935(CHIPS)':
 'PWM': CDS_PINID='PWM';
NODE_NAME     PU14 8
 '@S9S_MB_2U_LIB.S9S_MB_2U(SCH_1):PAGE252_I63@PURE_QUANTA.RAA229126GNPHA0(CHIPS)':
 'PWM7': CDS_PINID='PWM7';
NET_NAME
'PVCCIN_CPU0_PWM6'
 '@S9S_MB_2U_LIB.S9S_MB_2U(SCH_1):PVCCIN_CPU0_PWM6':
 C_SIGNAL='@s9s_mb_2u_lib.s9s_mb_2u(sch_1):pvccin_cpu0_pwm6';
NODE_NAME     PU8_P0_6 34
 '@S9S_MB_2U_LIB.S9S_MB_2U(SCH_1):PAGE255_I12@PURE_QUANTA.ISL99390FRZTR5935(CHIPS)':
 'PWM': CDS_PINID='PWM';
NODE_NAME     PU14 7
 '@S9S_MB_2U_LIB.S9S_MB_2U(SCH_1):PAGE252_I63@PURE_QUANTA.RAA229126GNPHA0(CHIPS)':
 'PWM6': CDS_PINID='PWM6';
NET_NAME
'PVCCIN_CPU0_PWM7'
 '@S9S_MB_2U_LIB.S9S_MB_2U(SCH_1):PVCCIN_CPU0_PWM7':
 C_SIGNAL='@s9s_mb_2u_lib.s9s_mb_2u(sch_1):pvccin_cpu0_pwm7';
NODE_NAME     PU7_P0_7 34
 '@S9S_MB_2U_LIB.S9S_MB_2U(SCH_1):PAGE256_I32@PURE_QUANTA.ISL99390FRZTR5935(CHIPS)':
 'PWM': CDS_PINID='PWM';
NODE_NAME     PU14 6
 '@S9S_MB_2U_LIB.S9S_MB_2U(SCH_1):PAGE252_I63@PURE_QUANTA.RAA229126GNPHA0(CHIPS)':
 'PWM5': CDS_PINID='PWM5';
NET_NAME
'PVCCIN_CPU0_PWM8'
 '@S9S_MB_2U_LIB.S9S_MB_2U(SCH_1):PVCCIN_CPU0_PWM8':
 C_SIGNAL='@s9s_mb_2u_lib.s9s_mb_2u(sch_1):pvccin_cpu0_pwm8';
NODE_NAME     PU6_P0_8 34
 '@S9S_MB_2U_LIB.S9S_MB_2U(SCH_1):PAGE256_I2@PURE_QUANTA.ISL99390FRZTR5935(CHIPS)':
 'PWM': CDS_PINID='PWM';
NODE_NAME     PU14 5
 '@S9S_MB_2U_LIB.S9S_MB_2U(SCH_1):PAGE252_I63@PURE_QUANTA.RAA229126GNPHA0(CHIPS)':
 'PWM4': CDS_PINID='PWM4';
NET_NAME
'PVCCIN_CPU0_VCC'
 '@S9S_MB_2U_LIB.S9S_MB_2U(SCH_1):PVCCIN_CPU0_VCC':
 C_SIGNAL='@s9s_mb_2u_lib.s9s_mb_2u(sch_1):pvccin_cpu0_vcc';
NODE_NAME     PU14 47
 '@S9S_MB_2U_LIB.S9S_MB_2U(SCH_1):PAGE252_I63@PURE_QUANTA.RAA229126GNPHA0(CHIPS)':
 'VCC': CDS_PINID='VCC';
NODE_NAME     PR176 1
 '@S9S_MB_2U_LIB.S9S_MB_2U(SCH_1):PAGE252_I133@PURE_QUANTA.Q_RES(CHIPS)':
 'A': CDS_PINID='A';
NODE_NAME     PC334 1
 '@S9S_MB_2U_LIB.S9S_MB_2U(SCH_1):PAGE252_I88@PURE_QUANTA.Q_CAP(CHIPS)':
 'A': CDS_PINID='A';
NODE_NAME     PC337 1
 '@S9S_MB_2U_LIB.S9S_MB_2U(SCH_1):PAGE252_I89@PURE_QUANTA.Q_CAP(CHIPS)':
 'A': CDS_PINID='A';
NODE_NAME     PC2361 1
 '@S9S_MB_2U_LIB.S9S_MB_2U(SCH_1):PAGE252_I136@PURE_QUANTA.Q_CAP(CHIPS)':
 'A': CDS_PINID='A';
NET_NAME
'PVCCIN_CPU0_VDD1'
 '@S9S_MB_2U_LIB.S9S_MB_2U(SCH_1):PVCCIN_CPU0_VDD1':
 C_SIGNAL='@s9s_mb_2u_lib.s9s_mb_2u(sch_1):pvccin_cpu0_vdd1';
NODE_NAME     PC293 1
 '@S9S_MB_2U_LIB.S9S_MB_2U(SCH_1):PAGE253_I36@PURE_QUANTA.Q_CAP(CHIPS)':
 'A': CDS_PINID='A';
NODE_NAME     PU13_P0_1 35
 '@S9S_MB_2U_LIB.S9S_MB_2U(SCH_1):PAGE253_I40@PURE_QUANTA.ISL99390FRZTR5935(CHIPS)':
 'EN': CDS_PINID='EN';
NODE_NAME     PU13_P0_1 3
 '@S9S_MB_2U_LIB.S9S_MB_2U(SCH_1):PAGE253_I40@PURE_QUANTA.ISL99390FRZTR5935(CHIPS)':
 'VCC': CDS_PINID='VCC';
NODE_NAME     PR153 2
 '@S9S_MB_2U_LIB.S9S_MB_2U(SCH_1):PAGE253_I37@PURE_QUANTA.Q_RES(CHIPS)':
 'B': CDS_PINID='B';
NET_NAME
'PVCCIN_CPU0_VDD2'
 '@S9S_MB_2U_LIB.S9S_MB_2U(SCH_1):PVCCIN_CPU0_VDD2':
 C_SIGNAL='@s9s_mb_2u_lib.s9s_mb_2u(sch_1):pvccin_cpu0_vdd2';
NODE_NAME     PU12_P0_2 35
 '@S9S_MB_2U_LIB.S9S_MB_2U(SCH_1):PAGE253_I6@PURE_QUANTA.ISL99390FRZTR5935(CHIPS)':
 'EN': CDS_PINID='EN';
NODE_NAME     PU12_P0_2 3
 '@S9S_MB_2U_LIB.S9S_MB_2U(SCH_1):PAGE253_I6@PURE_QUANTA.ISL99390FRZTR5935(CHIPS)':
 'VCC': CDS_PINID='VCC';
NODE_NAME     PC292 1
 '@S9S_MB_2U_LIB.S9S_MB_2U(SCH_1):PAGE253_I9@PURE_QUANTA.Q_CAP(CHIPS)':
 'A': CDS_PINID='A';
NODE_NAME     PR152 2
 '@S9S_MB_2U_LIB.S9S_MB_2U(SCH_1):PAGE253_I12@PURE_QUANTA.Q_RES(CHIPS)':
 'B': CDS_PINID='B';
NET_NAME
'PVCCIN_CPU0_VDD3'
 '@S9S_MB_2U_LIB.S9S_MB_2U(SCH_1):PVCCIN_CPU0_VDD3':
 C_SIGNAL='@s9s_mb_2u_lib.s9s_mb_2u(sch_1):pvccin_cpu0_vdd3';
NODE_NAME     PR147 2
 '@S9S_MB_2U_LIB.S9S_MB_2U(SCH_1):PAGE254_I27@PURE_QUANTA.Q_RES(CHIPS)':
 'B': CDS_PINID='B';
NODE_NAME     PU11_P0_3 35
 '@S9S_MB_2U_LIB.S9S_MB_2U(SCH_1):PAGE254_I20@PURE_QUANTA.ISL99390FRZTR5935(CHIPS)':
 'EN': CDS_PINID='EN';
NODE_NAME     PU11_P0_3 3
 '@S9S_MB_2U_LIB.S9S_MB_2U(SCH_1):PAGE254_I20@PURE_QUANTA.ISL99390FRZTR5935(CHIPS)':
 'VCC': CDS_PINID='VCC';
NODE_NAME     PC271 1
 '@S9S_MB_2U_LIB.S9S_MB_2U(SCH_1):PAGE254_I25@PURE_QUANTA.Q_CAP(CHIPS)':
 'A': CDS_PINID='A';
NET_NAME
'PVCCIN_CPU0_VDD4'
 '@S9S_MB_2U_LIB.S9S_MB_2U(SCH_1):PVCCIN_CPU0_VDD4':
 C_SIGNAL='@s9s_mb_2u_lib.s9s_mb_2u(sch_1):pvccin_cpu0_vdd4';
NODE_NAME     PU10_P0_4 35
 '@S9S_MB_2U_LIB.S9S_MB_2U(SCH_1):PAGE254_I13@PURE_QUANTA.ISL99390FRZTR5935(CHIPS)':
 'EN': CDS_PINID='EN';
NODE_NAME     PU10_P0_4 3
 '@S9S_MB_2U_LIB.S9S_MB_2U(SCH_1):PAGE254_I13@PURE_QUANTA.ISL99390FRZTR5935(CHIPS)':
 'VCC': CDS_PINID='VCC';
NODE_NAME     PR146 2
 '@S9S_MB_2U_LIB.S9S_MB_2U(SCH_1):PAGE254_I14@PURE_QUANTA.Q_RES(CHIPS)':
 'B': CDS_PINID='B';
NODE_NAME     PC270 1
 '@S9S_MB_2U_LIB.S9S_MB_2U(SCH_1):PAGE254_I11@PURE_QUANTA.Q_CAP(CHIPS)':
 'A': CDS_PINID='A';
NET_NAME
'PVCCIN_CPU0_VDD5'
 '@S9S_MB_2U_LIB.S9S_MB_2U(SCH_1):PVCCIN_CPU0_VDD5':
 C_SIGNAL='@s9s_mb_2u_lib.s9s_mb_2u(sch_1):pvccin_cpu0_vdd5';
NODE_NAME     PC249 1
 '@S9S_MB_2U_LIB.S9S_MB_2U(SCH_1):PAGE255_I24@PURE_QUANTA.Q_CAP(CHIPS)':
 'A': CDS_PINID='A';
NODE_NAME     PR141 2
 '@S9S_MB_2U_LIB.S9S_MB_2U(SCH_1):PAGE255_I26@PURE_QUANTA.Q_RES(CHIPS)':
 'B': CDS_PINID='B';
NODE_NAME     PU9_P0_5 35
 '@S9S_MB_2U_LIB.S9S_MB_2U(SCH_1):PAGE255_I66@PURE_QUANTA.ISL99390FRZTR5935(CHIPS)':
 'EN': CDS_PINID='EN';
NODE_NAME     PU9_P0_5 3
 '@S9S_MB_2U_LIB.S9S_MB_2U(SCH_1):PAGE255_I66@PURE_QUANTA.ISL99390FRZTR5935(CHIPS)':
 'VCC': CDS_PINID='VCC';
NET_NAME
'PVCCIN_CPU0_VDD6'
 '@S9S_MB_2U_LIB.S9S_MB_2U(SCH_1):PVCCIN_CPU0_VDD6':
 C_SIGNAL='@s9s_mb_2u_lib.s9s_mb_2u(sch_1):pvccin_cpu0_vdd6';
NODE_NAME     PU8_P0_6 35
 '@S9S_MB_2U_LIB.S9S_MB_2U(SCH_1):PAGE255_I12@PURE_QUANTA.ISL99390FRZTR5935(CHIPS)':
 'EN': CDS_PINID='EN';
NODE_NAME     PU8_P0_6 3
 '@S9S_MB_2U_LIB.S9S_MB_2U(SCH_1):PAGE255_I12@PURE_QUANTA.ISL99390FRZTR5935(CHIPS)':
 'VCC': CDS_PINID='VCC';
NODE_NAME     PC248 1
 '@S9S_MB_2U_LIB.S9S_MB_2U(SCH_1):PAGE255_I13@PURE_QUANTA.Q_CAP(CHIPS)':
 'A': CDS_PINID='A';
NODE_NAME     PR140 2
 '@S9S_MB_2U_LIB.S9S_MB_2U(SCH_1):PAGE255_I14@PURE_QUANTA.Q_RES(CHIPS)':
 'B': CDS_PINID='B';
NET_NAME
'PVCCIN_CPU0_VDD7'
 '@S9S_MB_2U_LIB.S9S_MB_2U(SCH_1):PVCCIN_CPU0_VDD7':
 C_SIGNAL='@s9s_mb_2u_lib.s9s_mb_2u(sch_1):pvccin_cpu0_vdd7';
NODE_NAME     PR135 2
 '@S9S_MB_2U_LIB.S9S_MB_2U(SCH_1):PAGE256_I33@PURE_QUANTA.Q_RES(CHIPS)':
 'B': CDS_PINID='B';
NODE_NAME     PC227 1
 '@S9S_MB_2U_LIB.S9S_MB_2U(SCH_1):PAGE256_I31@PURE_QUANTA.Q_CAP(CHIPS)':
 'A': CDS_PINID='A';
NODE_NAME     PU7_P0_7 35
 '@S9S_MB_2U_LIB.S9S_MB_2U(SCH_1):PAGE256_I32@PURE_QUANTA.ISL99390FRZTR5935(CHIPS)':
 'EN': CDS_PINID='EN';
NODE_NAME     PU7_P0_7 3
 '@S9S_MB_2U_LIB.S9S_MB_2U(SCH_1):PAGE256_I32@PURE_QUANTA.ISL99390FRZTR5935(CHIPS)':
 'VCC': CDS_PINID='VCC';
NET_NAME
'PVCCIN_CPU0_VDD8'
 '@S9S_MB_2U_LIB.S9S_MB_2U(SCH_1):PVCCIN_CPU0_VDD8':
 C_SIGNAL='@s9s_mb_2u_lib.s9s_mb_2u(sch_1):pvccin_cpu0_vdd8';
NODE_NAME     PU6_P0_8 35
 '@S9S_MB_2U_LIB.S9S_MB_2U(SCH_1):PAGE256_I2@PURE_QUANTA.ISL99390FRZTR5935(CHIPS)':
 'EN': CDS_PINID='EN';
NODE_NAME     PU6_P0_8 3
 '@S9S_MB_2U_LIB.S9S_MB_2U(SCH_1):PAGE256_I2@PURE_QUANTA.ISL99390FRZTR5935(CHIPS)':
 'VCC': CDS_PINID='VCC';
NODE_NAME     PC226 1
 '@S9S_MB_2U_LIB.S9S_MB_2U(SCH_1):PAGE256_I11@PURE_QUANTA.Q_CAP(CHIPS)':
 'A': CDS_PINID='A';
NODE_NAME     PR134 2
 '@S9S_MB_2U_LIB.S9S_MB_2U(SCH_1):PAGE256_I12@PURE_QUANTA.Q_RES(CHIPS)':
 'B': CDS_PINID='B';
NET_NAME
'PVCCIN_CPU0_VIN_CSNIN'
 '@S9S_MB_2U_LIB.S9S_MB_2U(SCH_1):PVCCIN_CPU0_VIN_CSNIN':
 C_SIGNAL='@s9s_mb_2u_lib.s9s_mb_2u(sch_1):pvccin_cpu0_vin_csnin';
NODE_NAME     PU14 46
 '@S9S_MB_2U_LIB.S9S_MB_2U(SCH_1):PAGE252_I63@PURE_QUANTA.RAA229126GNPHA0(CHIPS)':
 'VINSEN||VSYS': CDS_PINID='\vinsen||vsys\';
NODE_NAME     PR156 2
 '@S9S_MB_2U_LIB.S9S_MB_2U(SCH_1):PAGE252_I10@PURE_QUANTA.Q_RES(CHIPS)':
 'B': CDS_PINID='B';
NODE_NAME     PR166 1
 '@S9S_MB_2U_LIB.S9S_MB_2U(SCH_1):PAGE252_I60@PURE_QUANTA.Q_RES(CHIPS)':
 'A': CDS_PINID='A';
NODE_NAME     PC330 1
 '@S9S_MB_2U_LIB.S9S_MB_2U(SCH_1):PAGE252_I61@PURE_QUANTA.Q_CAP(CHIPS)':
 'A': CDS_PINID='A';
NET_NAME
'PVCCIN_CPU0_VOS1'
 '@S9S_MB_2U_LIB.S9S_MB_2U(SCH_1):PVCCIN_CPU0_VOS1':
 C_SIGNAL='@s9s_mb_2u_lib.s9s_mb_2u(sch_1):pvccin_cpu0_vos1';
NODE_NAME     PU13_P0_1 1
 '@S9S_MB_2U_LIB.S9S_MB_2U(SCH_1):PAGE253_I40@PURE_QUANTA.ISL99390FRZTR5935(CHIPS)':
 'VOS': CDS_PINID='VOS';
NODE_NAME     PR155 1
 '@S9S_MB_2U_LIB.S9S_MB_2U(SCH_1):PAGE253_I73@PURE_QUANTA.Q_RES(CHIPS)':
 'A': CDS_PINID='A';
NET_NAME
'PVCCIN_CPU0_VOS2'
 '@S9S_MB_2U_LIB.S9S_MB_2U(SCH_1):PVCCIN_CPU0_VOS2':
 C_SIGNAL='@s9s_mb_2u_lib.s9s_mb_2u(sch_1):pvccin_cpu0_vos2';
NODE_NAME     PR154 1
 '@S9S_MB_2U_LIB.S9S_MB_2U(SCH_1):PAGE253_I51@PURE_QUANTA.Q_RES(CHIPS)':
 'A': CDS_PINID='A';
NODE_NAME     PU12_P0_2 1
 '@S9S_MB_2U_LIB.S9S_MB_2U(SCH_1):PAGE253_I6@PURE_QUANTA.ISL99390FRZTR5935(CHIPS)':
 'VOS': CDS_PINID='VOS';
NET_NAME
'PVCCIN_CPU0_VOS3'
 '@S9S_MB_2U_LIB.S9S_MB_2U(SCH_1):PVCCIN_CPU0_VOS3':
 C_SIGNAL='@s9s_mb_2u_lib.s9s_mb_2u(sch_1):pvccin_cpu0_vos3';
NODE_NAME     PU11_P0_3 1
 '@S9S_MB_2U_LIB.S9S_MB_2U(SCH_1):PAGE254_I20@PURE_QUANTA.ISL99390FRZTR5935(CHIPS)':
 'VOS': CDS_PINID='VOS';
NODE_NAME     PR149 1
 '@S9S_MB_2U_LIB.S9S_MB_2U(SCH_1):PAGE254_I46@PURE_QUANTA.Q_RES(CHIPS)':
 'A': CDS_PINID='A';
NET_NAME
'PVCCIN_CPU0_VOS4'
 '@S9S_MB_2U_LIB.S9S_MB_2U(SCH_1):PVCCIN_CPU0_VOS4':
 C_SIGNAL='@s9s_mb_2u_lib.s9s_mb_2u(sch_1):pvccin_cpu0_vos4';
NODE_NAME     PU10_P0_4 1
 '@S9S_MB_2U_LIB.S9S_MB_2U(SCH_1):PAGE254_I13@PURE_QUANTA.ISL99390FRZTR5935(CHIPS)':
 'VOS': CDS_PINID='VOS';
NODE_NAME     PR148 1
 '@S9S_MB_2U_LIB.S9S_MB_2U(SCH_1):PAGE254_I41@PURE_QUANTA.Q_RES(CHIPS)':
 'A': CDS_PINID='A';
NET_NAME
'PVCCIN_CPU0_VOS5'
 '@S9S_MB_2U_LIB.S9S_MB_2U(SCH_1):PVCCIN_CPU0_VOS5':
 C_SIGNAL='@s9s_mb_2u_lib.s9s_mb_2u(sch_1):pvccin_cpu0_vos5';
NODE_NAME     PR143 1
 '@S9S_MB_2U_LIB.S9S_MB_2U(SCH_1):PAGE255_I46@PURE_QUANTA.Q_RES(CHIPS)':
 'A': CDS_PINID='A';
NODE_NAME     PU9_P0_5 1
 '@S9S_MB_2U_LIB.S9S_MB_2U(SCH_1):PAGE255_I66@PURE_QUANTA.ISL99390FRZTR5935(CHIPS)':
 'VOS': CDS_PINID='VOS';
NET_NAME
'PVCCIN_CPU0_VOS6'
 '@S9S_MB_2U_LIB.S9S_MB_2U(SCH_1):PVCCIN_CPU0_VOS6':
 C_SIGNAL='@s9s_mb_2u_lib.s9s_mb_2u(sch_1):pvccin_cpu0_vos6';
NODE_NAME     PU8_P0_6 1
 '@S9S_MB_2U_LIB.S9S_MB_2U(SCH_1):PAGE255_I12@PURE_QUANTA.ISL99390FRZTR5935(CHIPS)':
 'VOS': CDS_PINID='VOS';
NODE_NAME     PR142 1
 '@S9S_MB_2U_LIB.S9S_MB_2U(SCH_1):PAGE255_I40@PURE_QUANTA.Q_RES(CHIPS)':
 'A': CDS_PINID='A';
NET_NAME
'PVCCIN_CPU0_VOS7'
 '@S9S_MB_2U_LIB.S9S_MB_2U(SCH_1):PVCCIN_CPU0_VOS7':
 C_SIGNAL='@s9s_mb_2u_lib.s9s_mb_2u(sch_1):pvccin_cpu0_vos7';
NODE_NAME     PR137 1
 '@S9S_MB_2U_LIB.S9S_MB_2U(SCH_1):PAGE256_I57@PURE_QUANTA.Q_RES(CHIPS)':
 'A': CDS_PINID='A';
NODE_NAME     PU7_P0_7 1
 '@S9S_MB_2U_LIB.S9S_MB_2U(SCH_1):PAGE256_I32@PURE_QUANTA.ISL99390FRZTR5935(CHIPS)':
 'VOS': CDS_PINID='VOS';
NET_NAME
'PVCCIN_CPU0_VOS8'
 '@S9S_MB_2U_LIB.S9S_MB_2U(SCH_1):PVCCIN_CPU0_VOS8':
 C_SIGNAL='@s9s_mb_2u_lib.s9s_mb_2u(sch_1):pvccin_cpu0_vos8';
NODE_NAME     PU6_P0_8 1
 '@S9S_MB_2U_LIB.S9S_MB_2U(SCH_1):PAGE256_I2@PURE_QUANTA.ISL99390FRZTR5935(CHIPS)':
 'VOS': CDS_PINID='VOS';
NODE_NAME     PR136 1
 '@S9S_MB_2U_LIB.S9S_MB_2U(SCH_1):PAGE256_I46@PURE_QUANTA.Q_RES(CHIPS)':
 'A': CDS_PINID='A';
NET_NAME
'PVCCIN_CPU0_VREF'
 '@S9S_MB_2U_LIB.S9S_MB_2U(SCH_1):PVCCIN_CPU0_VREF':
 C_SIGNAL='@s9s_mb_2u_lib.s9s_mb_2u(sch_1):pvccin_cpu0_vref';
NODE_NAME     PC1355 2
 '@S9S_MB_2U_LIB.S9S_MB_2U(SCH_1):PAGE253_I11@PURE_QUANTA.Q_CAP(CHIPS)':
 'B': CDS_PINID='B';
NODE_NAME     PU13_P0_1 39
 '@S9S_MB_2U_LIB.S9S_MB_2U(SCH_1):PAGE253_I40@PURE_QUANTA.ISL99390FRZTR5935(CHIPS)':
 'REFIN': CDS_PINID='REFIN';
NODE_NAME     PU10_P0_4 39
 '@S9S_MB_2U_LIB.S9S_MB_2U(SCH_1):PAGE254_I13@PURE_QUANTA.ISL99390FRZTR5935(CHIPS)':
 'REFIN': CDS_PINID='REFIN';
NODE_NAME     PC1341 2
 '@S9S_MB_2U_LIB.S9S_MB_2U(SCH_1):PAGE254_I26@PURE_QUANTA.Q_CAP(CHIPS)':
 'B': CDS_PINID='B';
NODE_NAME     PC1342 2
 '@S9S_MB_2U_LIB.S9S_MB_2U(SCH_1):PAGE255_I11@PURE_QUANTA.Q_CAP(CHIPS)':
 'B': CDS_PINID='B';
NODE_NAME     PU8_P0_6 39
 '@S9S_MB_2U_LIB.S9S_MB_2U(SCH_1):PAGE255_I12@PURE_QUANTA.ISL99390FRZTR5935(CHIPS)':
 'REFIN': CDS_PINID='REFIN';
NODE_NAME     PU6_P0_8 39
 '@S9S_MB_2U_LIB.S9S_MB_2U(SCH_1):PAGE256_I2@PURE_QUANTA.ISL99390FRZTR5935(CHIPS)':
 'REFIN': CDS_PINID='REFIN';
NODE_NAME     PC1340 2
 '@S9S_MB_2U_LIB.S9S_MB_2U(SCH_1):PAGE254_I12@PURE_QUANTA.Q_CAP(CHIPS)':
 'B': CDS_PINID='B';
NODE_NAME     PU11_P0_3 39
 '@S9S_MB_2U_LIB.S9S_MB_2U(SCH_1):PAGE254_I20@PURE_QUANTA.ISL99390FRZTR5935(CHIPS)':
 'REFIN': CDS_PINID='REFIN';
NODE_NAME     PC1343 2
 '@S9S_MB_2U_LIB.S9S_MB_2U(SCH_1):PAGE255_I25@PURE_QUANTA.Q_CAP(CHIPS)':
 'B': CDS_PINID='B';
NODE_NAME     PU9_P0_5 39
 '@S9S_MB_2U_LIB.S9S_MB_2U(SCH_1):PAGE255_I66@PURE_QUANTA.ISL99390FRZTR5935(CHIPS)':
 'REFIN': CDS_PINID='REFIN';
NODE_NAME     PC1344 2
 '@S9S_MB_2U_LIB.S9S_MB_2U(SCH_1):PAGE256_I7@PURE_QUANTA.Q_CAP(CHIPS)':
 'B': CDS_PINID='B';
NODE_NAME     PC1345 2
 '@S9S_MB_2U_LIB.S9S_MB_2U(SCH_1):PAGE256_I29@PURE_QUANTA.Q_CAP(CHIPS)':
 'B': CDS_PINID='B';
NODE_NAME     PU7_P0_7 39
 '@S9S_MB_2U_LIB.S9S_MB_2U(SCH_1):PAGE256_I32@PURE_QUANTA.ISL99390FRZTR5935(CHIPS)':
 'REFIN': CDS_PINID='REFIN';
NODE_NAME     PC1351 2
 '@S9S_MB_2U_LIB.S9S_MB_2U(SCH_1):PAGE258_I25@PURE_QUANTA.Q_CAP(CHIPS)':
 'B': CDS_PINID='B';
NODE_NAME     PU14 48
 '@S9S_MB_2U_LIB.S9S_MB_2U(SCH_1):PAGE252_I63@PURE_QUANTA.RAA229126GNPHA0(CHIPS)':
 'VCCS': CDS_PINID='VCCS';
NODE_NAME     PC1356 2
 '@S9S_MB_2U_LIB.S9S_MB_2U(SCH_1):PAGE253_I34@PURE_QUANTA.Q_CAP(CHIPS)':
 'B': CDS_PINID='B';
NODE_NAME     PU70_P0_2 39
 '@S9S_MB_2U_LIB.S9S_MB_2U(SCH_1):PAGE257_I16@PURE_QUANTA.ISL99390FRZTR5935(CHIPS)':
 'REFIN': CDS_PINID='REFIN';
NODE_NAME     PU71_P0_3 39
 '@S9S_MB_2U_LIB.S9S_MB_2U(SCH_1):PAGE258_I82@PURE_QUANTA.ISL99390FRZTR5935(CHIPS)':
 'REFIN': CDS_PINID='REFIN';
NODE_NAME     PR159 1
 '@S9S_MB_2U_LIB.S9S_MB_2U(SCH_1):PAGE252_I5@PURE_QUANTA.Q_RES(CHIPS)':
 'A': CDS_PINID='A';
NODE_NAME     PC335 1
 '@S9S_MB_2U_LIB.S9S_MB_2U(SCH_1):PAGE252_I86@PURE_QUANTA.Q_CAP(CHIPS)':
 'A': CDS_PINID='A';
NODE_NAME     PC1350 2
 '@S9S_MB_2U_LIB.S9S_MB_2U(SCH_1):PAGE257_I15@PURE_QUANTA.Q_CAP(CHIPS)':
 'B': CDS_PINID='B';
NODE_NAME     PU12_P0_2 39
 '@S9S_MB_2U_LIB.S9S_MB_2U(SCH_1):PAGE253_I6@PURE_QUANTA.ISL99390FRZTR5935(CHIPS)':
 'REFIN': CDS_PINID='REFIN';
NODE_NAME     PU69_P0_1 39
 '@S9S_MB_2U_LIB.S9S_MB_2U(SCH_1):PAGE257_I25@PURE_QUANTA.ISL99390FRZTR5935(CHIPS)':
 'REFIN': CDS_PINID='REFIN';
NODE_NAME     PC1349 2
 '@S9S_MB_2U_LIB.S9S_MB_2U(SCH_1):PAGE257_I35@PURE_QUANTA.Q_CAP(CHIPS)':
 'B': CDS_PINID='B';
NODE_NAME     PC1352 2
 '@S9S_MB_2U_LIB.S9S_MB_2U(SCH_1):PAGE258_I9@PURE_QUANTA.Q_CAP(CHIPS)':
 'B': CDS_PINID='B';
NODE_NAME     PU72_P0_4 39
 '@S9S_MB_2U_LIB.S9S_MB_2U(SCH_1):PAGE258_I10@PURE_QUANTA.ISL99390FRZTR5935(CHIPS)':
 'REFIN': CDS_PINID='REFIN';
NODE_NAME     PC1173 1
 '@S9S_MB_2U_LIB.S9S_MB_2U(SCH_1):PAGE252_I87@PURE_QUANTA.Q_CAP(CHIPS)':
 'A': CDS_PINID='A';
NET_NAME
'PVCCIN_CPU0_VR_FAULT'
 '@S9S_MB_2U_LIB.S9S_MB_2U(SCH_1):PVCCIN_CPU0_VR_FAULT':
 C_SIGNAL='@s9s_mb_2u_lib.s9s_mb_2u(sch_1):pvccin_cpu0_vr_fault';
NODE_NAME     PU14 41
 '@S9S_MB_2U_LIB.S9S_MB_2U(SCH_1):PAGE252_I63@PURE_QUANTA.RAA229126GNPHA0(CHIPS)':
 'CFP': CDS_PINID='CFP';
NODE_NAME     R2589 2
 '@S9S_MB_2U_LIB.S9S_MB_2U(SCH_1):PAGE252_I20@PURE_QUANTA.Q_RES(CHIPS)':
 'B': CDS_PINID='B';
NET_NAME
'PVCCIN_CPU1'
 '@S9S_MB_2U_LIB.S9S_MB_2U(SCH_1):PVCCIN_CPU1':
 C_SIGNAL='@s9s_mb_2u_lib.s9s_mb_2u(sch_1):pvccin_cpu1',
 CDS_GLOBAL_NET='TRUE';
NODE_NAME     U1 BW80
 '@S9S_MB_2U_LIB.S9S_MB_2U(SCH_1):PAGE67_I1@PURE_QUANTA.SOCKET4677_AZIF0045P001C01CS(CHIPS)':
 'VCCIN190': CDS_PINID='VCCIN190';
NODE_NAME     U1 BW82
 '@S9S_MB_2U_LIB.S9S_MB_2U(SCH_1):PAGE67_I1@PURE_QUANTA.SOCKET4677_AZIF0045P001C01CS(CHIPS)':
 'VCCIN191': CDS_PINID='VCCIN191';
NODE_NAME     U1 BW84
 '@S9S_MB_2U_LIB.S9S_MB_2U(SCH_1):PAGE67_I1@PURE_QUANTA.SOCKET4677_AZIF0045P001C01CS(CHIPS)':
 'VCCIN192': CDS_PINID='VCCIN192';
NODE_NAME     U1 BW86
 '@S9S_MB_2U_LIB.S9S_MB_2U(SCH_1):PAGE67_I1@PURE_QUANTA.SOCKET4677_AZIF0045P001C01CS(CHIPS)':
 'VCCIN193': CDS_PINID='VCCIN193';
NODE_NAME     U1 BW88
 '@S9S_MB_2U_LIB.S9S_MB_2U(SCH_1):PAGE67_I1@PURE_QUANTA.SOCKET4677_AZIF0045P001C01CS(CHIPS)':
 'VCCIN194': CDS_PINID='VCCIN194';
NODE_NAME     U1 BW90
 '@S9S_MB_2U_LIB.S9S_MB_2U(SCH_1):PAGE67_I1@PURE_QUANTA.SOCKET4677_AZIF0045P001C01CS(CHIPS)':
 'VCCIN195': CDS_PINID='VCCIN195';
NODE_NAME     U1 BY32
 '@S9S_MB_2U_LIB.S9S_MB_2U(SCH_1):PAGE67_I1@PURE_QUANTA.SOCKET4677_AZIF0045P001C01CS(CHIPS)':
 'VCCIN196': CDS_PINID='VCCIN196';
NODE_NAME     U1 BY34
 '@S9S_MB_2U_LIB.S9S_MB_2U(SCH_1):PAGE67_I1@PURE_QUANTA.SOCKET4677_AZIF0045P001C01CS(CHIPS)':
 'VCCIN197': CDS_PINID='VCCIN197';
NODE_NAME     U1 BY36
 '@S9S_MB_2U_LIB.S9S_MB_2U(SCH_1):PAGE67_I1@PURE_QUANTA.SOCKET4677_AZIF0045P001C01CS(CHIPS)':
 'VCCIN198': CDS_PINID='VCCIN198';
NODE_NAME     U1 BY38
 '@S9S_MB_2U_LIB.S9S_MB_2U(SCH_1):PAGE67_I1@PURE_QUANTA.SOCKET4677_AZIF0045P001C01CS(CHIPS)':
 'VCCIN199': CDS_PINID='VCCIN199';
NODE_NAME     U1 BY40
 '@S9S_MB_2U_LIB.S9S_MB_2U(SCH_1):PAGE67_I1@PURE_QUANTA.SOCKET4677_AZIF0045P001C01CS(CHIPS)':
 'VCCIN200': CDS_PINID='VCCIN200';
NODE_NAME     U1 BY42
 '@S9S_MB_2U_LIB.S9S_MB_2U(SCH_1):PAGE67_I1@PURE_QUANTA.SOCKET4677_AZIF0045P001C01CS(CHIPS)':
 'VCCIN201': CDS_PINID='VCCIN201';
NODE_NAME     U1 BY44
 '@S9S_MB_2U_LIB.S9S_MB_2U(SCH_1):PAGE67_I1@PURE_QUANTA.SOCKET4677_AZIF0045P001C01CS(CHIPS)':
 'VCCIN202': CDS_PINID='VCCIN202';
NODE_NAME     U1 BY47
 '@S9S_MB_2U_LIB.S9S_MB_2U(SCH_1):PAGE67_I1@PURE_QUANTA.SOCKET4677_AZIF0045P001C01CS(CHIPS)':
 'VCCIN203': CDS_PINID='VCCIN203';
NODE_NAME     U1 BY49
 '@S9S_MB_2U_LIB.S9S_MB_2U(SCH_1):PAGE67_I1@PURE_QUANTA.SOCKET4677_AZIF0045P001C01CS(CHIPS)':
 'VCCIN204': CDS_PINID='VCCIN204';
NODE_NAME     U1 BY51
 '@S9S_MB_2U_LIB.S9S_MB_2U(SCH_1):PAGE67_I1@PURE_QUANTA.SOCKET4677_AZIF0045P001C01CS(CHIPS)':
 'VCCIN205': CDS_PINID='VCCIN205';
NODE_NAME     U1 BY53
 '@S9S_MB_2U_LIB.S9S_MB_2U(SCH_1):PAGE67_I1@PURE_QUANTA.SOCKET4677_AZIF0045P001C01CS(CHIPS)':
 'VCCIN206': CDS_PINID='VCCIN206';
NODE_NAME     U1 BY55
 '@S9S_MB_2U_LIB.S9S_MB_2U(SCH_1):PAGE67_I1@PURE_QUANTA.SOCKET4677_AZIF0045P001C01CS(CHIPS)':
 'VCCIN207': CDS_PINID='VCCIN207';
NODE_NAME     U1 BY57
 '@S9S_MB_2U_LIB.S9S_MB_2U(SCH_1):PAGE67_I1@PURE_QUANTA.SOCKET4677_AZIF0045P001C01CS(CHIPS)':
 'VCCIN208': CDS_PINID='VCCIN208';
NODE_NAME     U1 BY59
 '@S9S_MB_2U_LIB.S9S_MB_2U(SCH_1):PAGE67_I1@PURE_QUANTA.SOCKET4677_AZIF0045P001C01CS(CHIPS)':
 'VCCIN209': CDS_PINID='VCCIN209';
NODE_NAME     U1 BY61
 '@S9S_MB_2U_LIB.S9S_MB_2U(SCH_1):PAGE67_I1@PURE_QUANTA.SOCKET4677_AZIF0045P001C01CS(CHIPS)':
 'VCCIN210': CDS_PINID='VCCIN210';
NODE_NAME     U1 BY63
 '@S9S_MB_2U_LIB.S9S_MB_2U(SCH_1):PAGE67_I1@PURE_QUANTA.SOCKET4677_AZIF0045P001C01CS(CHIPS)':
 'VCCIN211': CDS_PINID='VCCIN211';
NODE_NAME     U1 BY65
 '@S9S_MB_2U_LIB.S9S_MB_2U(SCH_1):PAGE67_I1@PURE_QUANTA.SOCKET4677_AZIF0045P001C01CS(CHIPS)':
 'VCCIN212': CDS_PINID='VCCIN212';
NODE_NAME     U1 BY67
 '@S9S_MB_2U_LIB.S9S_MB_2U(SCH_1):PAGE67_I1@PURE_QUANTA.SOCKET4677_AZIF0045P001C01CS(CHIPS)':
 'VCCIN213': CDS_PINID='VCCIN213';
NODE_NAME     U1 BY69
 '@S9S_MB_2U_LIB.S9S_MB_2U(SCH_1):PAGE67_I1@PURE_QUANTA.SOCKET4677_AZIF0045P001C01CS(CHIPS)':
 'VCCIN214': CDS_PINID='VCCIN214';
NODE_NAME     U1 BY71
 '@S9S_MB_2U_LIB.S9S_MB_2U(SCH_1):PAGE67_I1@PURE_QUANTA.SOCKET4677_AZIF0045P001C01CS(CHIPS)':
 'VCCIN215': CDS_PINID='VCCIN215';
NODE_NAME     U1 BY73
 '@S9S_MB_2U_LIB.S9S_MB_2U(SCH_1):PAGE67_I1@PURE_QUANTA.SOCKET4677_AZIF0045P001C01CS(CHIPS)':
 'VCCIN216': CDS_PINID='VCCIN216';
NODE_NAME     U1 BY75
 '@S9S_MB_2U_LIB.S9S_MB_2U(SCH_1):PAGE67_I1@PURE_QUANTA.SOCKET4677_AZIF0045P001C01CS(CHIPS)':
 'VCCIN217': CDS_PINID='VCCIN217';
NODE_NAME     U1 BY77
 '@S9S_MB_2U_LIB.S9S_MB_2U(SCH_1):PAGE67_I1@PURE_QUANTA.SOCKET4677_AZIF0045P001C01CS(CHIPS)':
 'VCCIN218': CDS_PINID='VCCIN218';
NODE_NAME     U1 BY79
 '@S9S_MB_2U_LIB.S9S_MB_2U(SCH_1):PAGE67_I1@PURE_QUANTA.SOCKET4677_AZIF0045P001C01CS(CHIPS)':
 'VCCIN219': CDS_PINID='VCCIN219';
NODE_NAME     U1 BY81
 '@S9S_MB_2U_LIB.S9S_MB_2U(SCH_1):PAGE67_I1@PURE_QUANTA.SOCKET4677_AZIF0045P001C01CS(CHIPS)':
 'VCCIN220': CDS_PINID='VCCIN220';
NODE_NAME     U1 BY83
 '@S9S_MB_2U_LIB.S9S_MB_2U(SCH_1):PAGE67_I1@PURE_QUANTA.SOCKET4677_AZIF0045P001C01CS(CHIPS)':
 'VCCIN221': CDS_PINID='VCCIN221';
NODE_NAME     U1 BY85
 '@S9S_MB_2U_LIB.S9S_MB_2U(SCH_1):PAGE67_I1@PURE_QUANTA.SOCKET4677_AZIF0045P001C01CS(CHIPS)':
 'VCCIN222': CDS_PINID='VCCIN222';
NODE_NAME     U1 BY87
 '@S9S_MB_2U_LIB.S9S_MB_2U(SCH_1):PAGE67_I1@PURE_QUANTA.SOCKET4677_AZIF0045P001C01CS(CHIPS)':
 'VCCIN223': CDS_PINID='VCCIN223';
NODE_NAME     U1 BY89
 '@S9S_MB_2U_LIB.S9S_MB_2U(SCH_1):PAGE67_I1@PURE_QUANTA.SOCKET4677_AZIF0045P001C01CS(CHIPS)':
 'VCCIN224': CDS_PINID='VCCIN224';
NODE_NAME     U1 CA33
 '@S9S_MB_2U_LIB.S9S_MB_2U(SCH_1):PAGE67_I1@PURE_QUANTA.SOCKET4677_AZIF0045P001C01CS(CHIPS)':
 'VCCIN225': CDS_PINID='VCCIN225';
NODE_NAME     U1 CA35
 '@S9S_MB_2U_LIB.S9S_MB_2U(SCH_1):PAGE67_I1@PURE_QUANTA.SOCKET4677_AZIF0045P001C01CS(CHIPS)':
 'VCCIN226': CDS_PINID='VCCIN226';
NODE_NAME     U1 CA37
 '@S9S_MB_2U_LIB.S9S_MB_2U(SCH_1):PAGE67_I1@PURE_QUANTA.SOCKET4677_AZIF0045P001C01CS(CHIPS)':
 'VCCIN227': CDS_PINID='VCCIN227';
NODE_NAME     U1 CA39
 '@S9S_MB_2U_LIB.S9S_MB_2U(SCH_1):PAGE67_I1@PURE_QUANTA.SOCKET4677_AZIF0045P001C01CS(CHIPS)':
 'VCCIN228': CDS_PINID='VCCIN228';
NODE_NAME     U1 CA41
 '@S9S_MB_2U_LIB.S9S_MB_2U(SCH_1):PAGE67_I1@PURE_QUANTA.SOCKET4677_AZIF0045P001C01CS(CHIPS)':
 'VCCIN229': CDS_PINID='VCCIN229';
NODE_NAME     U1 CA43
 '@S9S_MB_2U_LIB.S9S_MB_2U(SCH_1):PAGE67_I1@PURE_QUANTA.SOCKET4677_AZIF0045P001C01CS(CHIPS)':
 'VCCIN230': CDS_PINID='VCCIN230';
NODE_NAME     U1 CA45
 '@S9S_MB_2U_LIB.S9S_MB_2U(SCH_1):PAGE67_I1@PURE_QUANTA.SOCKET4677_AZIF0045P001C01CS(CHIPS)':
 'VCCIN231': CDS_PINID='VCCIN231';
NODE_NAME     U1 CA48
 '@S9S_MB_2U_LIB.S9S_MB_2U(SCH_1):PAGE67_I1@PURE_QUANTA.SOCKET4677_AZIF0045P001C01CS(CHIPS)':
 'VCCIN232': CDS_PINID='VCCIN232';
NODE_NAME     U1 CA50
 '@S9S_MB_2U_LIB.S9S_MB_2U(SCH_1):PAGE67_I1@PURE_QUANTA.SOCKET4677_AZIF0045P001C01CS(CHIPS)':
 'VCCIN233': CDS_PINID='VCCIN233';
NODE_NAME     U1 CA52
 '@S9S_MB_2U_LIB.S9S_MB_2U(SCH_1):PAGE67_I1@PURE_QUANTA.SOCKET4677_AZIF0045P001C01CS(CHIPS)':
 'VCCIN234': CDS_PINID='VCCIN234';
NODE_NAME     U1 CA54
 '@S9S_MB_2U_LIB.S9S_MB_2U(SCH_1):PAGE67_I1@PURE_QUANTA.SOCKET4677_AZIF0045P001C01CS(CHIPS)':
 'VCCIN235': CDS_PINID='VCCIN235';
NODE_NAME     U1 CA56
 '@S9S_MB_2U_LIB.S9S_MB_2U(SCH_1):PAGE67_I1@PURE_QUANTA.SOCKET4677_AZIF0045P001C01CS(CHIPS)':
 'VCCIN236': CDS_PINID='VCCIN236';
NODE_NAME     U1 CA58
 '@S9S_MB_2U_LIB.S9S_MB_2U(SCH_1):PAGE67_I1@PURE_QUANTA.SOCKET4677_AZIF0045P001C01CS(CHIPS)':
 'VCCIN237': CDS_PINID='VCCIN237';
NODE_NAME     U1 CA60
 '@S9S_MB_2U_LIB.S9S_MB_2U(SCH_1):PAGE67_I1@PURE_QUANTA.SOCKET4677_AZIF0045P001C01CS(CHIPS)':
 'VCCIN238': CDS_PINID='VCCIN238';
NODE_NAME     U1 CA62
 '@S9S_MB_2U_LIB.S9S_MB_2U(SCH_1):PAGE67_I1@PURE_QUANTA.SOCKET4677_AZIF0045P001C01CS(CHIPS)':
 'VCCIN239': CDS_PINID='VCCIN239';
NODE_NAME     U1 CA64
 '@S9S_MB_2U_LIB.S9S_MB_2U(SCH_1):PAGE67_I1@PURE_QUANTA.SOCKET4677_AZIF0045P001C01CS(CHIPS)':
 'VCCIN240': CDS_PINID='VCCIN240';
NODE_NAME     U1 CA66
 '@S9S_MB_2U_LIB.S9S_MB_2U(SCH_1):PAGE67_I1@PURE_QUANTA.SOCKET4677_AZIF0045P001C01CS(CHIPS)':
 'VCCIN241': CDS_PINID='VCCIN241';
NODE_NAME     U1 CA68
 '@S9S_MB_2U_LIB.S9S_MB_2U(SCH_1):PAGE67_I1@PURE_QUANTA.SOCKET4677_AZIF0045P001C01CS(CHIPS)':
 'VCCIN242': CDS_PINID='VCCIN242';
NODE_NAME     U1 CA70
 '@S9S_MB_2U_LIB.S9S_MB_2U(SCH_1):PAGE67_I1@PURE_QUANTA.SOCKET4677_AZIF0045P001C01CS(CHIPS)':
 'VCCIN243': CDS_PINID='VCCIN243';
NODE_NAME     U1 CA72
 '@S9S_MB_2U_LIB.S9S_MB_2U(SCH_1):PAGE67_I1@PURE_QUANTA.SOCKET4677_AZIF0045P001C01CS(CHIPS)':
 'VCCIN244': CDS_PINID='VCCIN244';
NODE_NAME     U1 CA74
 '@S9S_MB_2U_LIB.S9S_MB_2U(SCH_1):PAGE67_I1@PURE_QUANTA.SOCKET4677_AZIF0045P001C01CS(CHIPS)':
 'VCCIN245': CDS_PINID='VCCIN245';
NODE_NAME     U1 CA76
 '@S9S_MB_2U_LIB.S9S_MB_2U(SCH_1):PAGE67_I1@PURE_QUANTA.SOCKET4677_AZIF0045P001C01CS(CHIPS)':
 'VCCIN246': CDS_PINID='VCCIN246';
NODE_NAME     U1 CA78
 '@S9S_MB_2U_LIB.S9S_MB_2U(SCH_1):PAGE67_I1@PURE_QUANTA.SOCKET4677_AZIF0045P001C01CS(CHIPS)':
 'VCCIN247': CDS_PINID='VCCIN247';
NODE_NAME     U1 CA80
 '@S9S_MB_2U_LIB.S9S_MB_2U(SCH_1):PAGE67_I1@PURE_QUANTA.SOCKET4677_AZIF0045P001C01CS(CHIPS)':
 'VCCIN248': CDS_PINID='VCCIN248';
NODE_NAME     U1 CA82
 '@S9S_MB_2U_LIB.S9S_MB_2U(SCH_1):PAGE67_I1@PURE_QUANTA.SOCKET4677_AZIF0045P001C01CS(CHIPS)':
 'VCCIN249': CDS_PINID='VCCIN249';
NODE_NAME     U1 CA84
 '@S9S_MB_2U_LIB.S9S_MB_2U(SCH_1):PAGE67_I1@PURE_QUANTA.SOCKET4677_AZIF0045P001C01CS(CHIPS)':
 'VCCIN250': CDS_PINID='VCCIN250';
NODE_NAME     U1 CA86
 '@S9S_MB_2U_LIB.S9S_MB_2U(SCH_1):PAGE67_I1@PURE_QUANTA.SOCKET4677_AZIF0045P001C01CS(CHIPS)':
 'VCCIN251': CDS_PINID='VCCIN251';
NODE_NAME     U1 CA88
 '@S9S_MB_2U_LIB.S9S_MB_2U(SCH_1):PAGE67_I1@PURE_QUANTA.SOCKET4677_AZIF0045P001C01CS(CHIPS)':
 'VCCIN252': CDS_PINID='VCCIN252';
NODE_NAME     U1 CA90
 '@S9S_MB_2U_LIB.S9S_MB_2U(SCH_1):PAGE67_I1@PURE_QUANTA.SOCKET4677_AZIF0045P001C01CS(CHIPS)':
 'VCCIN253': CDS_PINID='VCCIN253';
NODE_NAME     U1 CB61
 '@S9S_MB_2U_LIB.S9S_MB_2U(SCH_1):PAGE67_I1@PURE_QUANTA.SOCKET4677_AZIF0045P001C01CS(CHIPS)':
 'VCCIN254': CDS_PINID='VCCIN254';
NODE_NAME     U1 CB75
 '@S9S_MB_2U_LIB.S9S_MB_2U(SCH_1):PAGE67_I1@PURE_QUANTA.SOCKET4677_AZIF0045P001C01CS(CHIPS)':
 'VCCIN255': CDS_PINID='VCCIN255';
NODE_NAME     U1 CB77
 '@S9S_MB_2U_LIB.S9S_MB_2U(SCH_1):PAGE67_I1@PURE_QUANTA.SOCKET4677_AZIF0045P001C01CS(CHIPS)':
 'VCCIN256': CDS_PINID='VCCIN256';
NODE_NAME     U1 CC33
 '@S9S_MB_2U_LIB.S9S_MB_2U(SCH_1):PAGE67_I1@PURE_QUANTA.SOCKET4677_AZIF0045P001C01CS(CHIPS)':
 'VCCIN257': CDS_PINID='VCCIN257';
NODE_NAME     U1 CC35
 '@S9S_MB_2U_LIB.S9S_MB_2U(SCH_1):PAGE67_I1@PURE_QUANTA.SOCKET4677_AZIF0045P001C01CS(CHIPS)':
 'VCCIN258': CDS_PINID='VCCIN258';
NODE_NAME     U1 CC37
 '@S9S_MB_2U_LIB.S9S_MB_2U(SCH_1):PAGE67_I1@PURE_QUANTA.SOCKET4677_AZIF0045P001C01CS(CHIPS)':
 'VCCIN259': CDS_PINID='VCCIN259';
NODE_NAME     U1 CC39
 '@S9S_MB_2U_LIB.S9S_MB_2U(SCH_1):PAGE67_I1@PURE_QUANTA.SOCKET4677_AZIF0045P001C01CS(CHIPS)':
 'VCCIN260': CDS_PINID='VCCIN260';
NODE_NAME     U1 CC41
 '@S9S_MB_2U_LIB.S9S_MB_2U(SCH_1):PAGE67_I1@PURE_QUANTA.SOCKET4677_AZIF0045P001C01CS(CHIPS)':
 'VCCIN261': CDS_PINID='VCCIN261';
NODE_NAME     U1 CC43
 '@S9S_MB_2U_LIB.S9S_MB_2U(SCH_1):PAGE67_I1@PURE_QUANTA.SOCKET4677_AZIF0045P001C01CS(CHIPS)':
 'VCCIN262': CDS_PINID='VCCIN262';
NODE_NAME     U1 CC45
 '@S9S_MB_2U_LIB.S9S_MB_2U(SCH_1):PAGE67_I1@PURE_QUANTA.SOCKET4677_AZIF0045P001C01CS(CHIPS)':
 'VCCIN263': CDS_PINID='VCCIN263';
NODE_NAME     U1 CC48
 '@S9S_MB_2U_LIB.S9S_MB_2U(SCH_1):PAGE67_I1@PURE_QUANTA.SOCKET4677_AZIF0045P001C01CS(CHIPS)':
 'VCCIN264': CDS_PINID='VCCIN264';
NODE_NAME     U1 CC50
 '@S9S_MB_2U_LIB.S9S_MB_2U(SCH_1):PAGE67_I1@PURE_QUANTA.SOCKET4677_AZIF0045P001C01CS(CHIPS)':
 'VCCIN265': CDS_PINID='VCCIN265';
NODE_NAME     U1 CC52
 '@S9S_MB_2U_LIB.S9S_MB_2U(SCH_1):PAGE67_I1@PURE_QUANTA.SOCKET4677_AZIF0045P001C01CS(CHIPS)':
 'VCCIN266': CDS_PINID='VCCIN266';
NODE_NAME     U1 CC54
 '@S9S_MB_2U_LIB.S9S_MB_2U(SCH_1):PAGE67_I1@PURE_QUANTA.SOCKET4677_AZIF0045P001C01CS(CHIPS)':
 'VCCIN267': CDS_PINID='VCCIN267';
NODE_NAME     U1 CC56
 '@S9S_MB_2U_LIB.S9S_MB_2U(SCH_1):PAGE67_I1@PURE_QUANTA.SOCKET4677_AZIF0045P001C01CS(CHIPS)':
 'VCCIN268': CDS_PINID='VCCIN268';
NODE_NAME     U1 CC58
 '@S9S_MB_2U_LIB.S9S_MB_2U(SCH_1):PAGE67_I1@PURE_QUANTA.SOCKET4677_AZIF0045P001C01CS(CHIPS)':
 'VCCIN269': CDS_PINID='VCCIN269';
NODE_NAME     U1 CC60
 '@S9S_MB_2U_LIB.S9S_MB_2U(SCH_1):PAGE67_I1@PURE_QUANTA.SOCKET4677_AZIF0045P001C01CS(CHIPS)':
 'VCCIN270': CDS_PINID='VCCIN270';
NODE_NAME     U1 CC76
 '@S9S_MB_2U_LIB.S9S_MB_2U(SCH_1):PAGE67_I1@PURE_QUANTA.SOCKET4677_AZIF0045P001C01CS(CHIPS)':
 'VCCIN271': CDS_PINID='VCCIN271';
NODE_NAME     U1 CC78
 '@S9S_MB_2U_LIB.S9S_MB_2U(SCH_1):PAGE67_I1@PURE_QUANTA.SOCKET4677_AZIF0045P001C01CS(CHIPS)':
 'VCCIN272': CDS_PINID='VCCIN272';
NODE_NAME     U1 CC80
 '@S9S_MB_2U_LIB.S9S_MB_2U(SCH_1):PAGE67_I1@PURE_QUANTA.SOCKET4677_AZIF0045P001C01CS(CHIPS)':
 'VCCIN273': CDS_PINID='VCCIN273';
NODE_NAME     U1 CC82
 '@S9S_MB_2U_LIB.S9S_MB_2U(SCH_1):PAGE67_I1@PURE_QUANTA.SOCKET4677_AZIF0045P001C01CS(CHIPS)':
 'VCCIN274': CDS_PINID='VCCIN274';
NODE_NAME     U1 CC84
 '@S9S_MB_2U_LIB.S9S_MB_2U(SCH_1):PAGE67_I1@PURE_QUANTA.SOCKET4677_AZIF0045P001C01CS(CHIPS)':
 'VCCIN275': CDS_PINID='VCCIN275';
NODE_NAME     U1 CC86
 '@S9S_MB_2U_LIB.S9S_MB_2U(SCH_1):PAGE67_I1@PURE_QUANTA.SOCKET4677_AZIF0045P001C01CS(CHIPS)':
 'VCCIN276': CDS_PINID='VCCIN276';
NODE_NAME     U1 CC88
 '@S9S_MB_2U_LIB.S9S_MB_2U(SCH_1):PAGE67_I1@PURE_QUANTA.SOCKET4677_AZIF0045P001C01CS(CHIPS)':
 'VCCIN277': CDS_PINID='VCCIN277';
NODE_NAME     U1 CC90
 '@S9S_MB_2U_LIB.S9S_MB_2U(SCH_1):PAGE67_I1@PURE_QUANTA.SOCKET4677_AZIF0045P001C01CS(CHIPS)':
 'VCCIN278': CDS_PINID='VCCIN278';
NODE_NAME     U1 CD32
 '@S9S_MB_2U_LIB.S9S_MB_2U(SCH_1):PAGE67_I1@PURE_QUANTA.SOCKET4677_AZIF0045P001C01CS(CHIPS)':
 'VCCIN279': CDS_PINID='VCCIN279';
NODE_NAME     U1 CD34
 '@S9S_MB_2U_LIB.S9S_MB_2U(SCH_1):PAGE67_I1@PURE_QUANTA.SOCKET4677_AZIF0045P001C01CS(CHIPS)':
 'VCCIN280': CDS_PINID='VCCIN280';
NODE_NAME     U1 CD36
 '@S9S_MB_2U_LIB.S9S_MB_2U(SCH_1):PAGE67_I1@PURE_QUANTA.SOCKET4677_AZIF0045P001C01CS(CHIPS)':
 'VCCIN281': CDS_PINID='VCCIN281';
NODE_NAME     U1 CD38
 '@S9S_MB_2U_LIB.S9S_MB_2U(SCH_1):PAGE67_I1@PURE_QUANTA.SOCKET4677_AZIF0045P001C01CS(CHIPS)':
 'VCCIN282': CDS_PINID='VCCIN282';
NODE_NAME     U1 CD40
 '@S9S_MB_2U_LIB.S9S_MB_2U(SCH_1):PAGE67_I1@PURE_QUANTA.SOCKET4677_AZIF0045P001C01CS(CHIPS)':
 'VCCIN283': CDS_PINID='VCCIN283';
NODE_NAME     U1 CD42
 '@S9S_MB_2U_LIB.S9S_MB_2U(SCH_1):PAGE67_I1@PURE_QUANTA.SOCKET4677_AZIF0045P001C01CS(CHIPS)':
 'VCCIN284': CDS_PINID='VCCIN284';
NODE_NAME     U1 CD44
 '@S9S_MB_2U_LIB.S9S_MB_2U(SCH_1):PAGE67_I1@PURE_QUANTA.SOCKET4677_AZIF0045P001C01CS(CHIPS)':
 'VCCIN285': CDS_PINID='VCCIN285';
NODE_NAME     U1 CD47
 '@S9S_MB_2U_LIB.S9S_MB_2U(SCH_1):PAGE67_I1@PURE_QUANTA.SOCKET4677_AZIF0045P001C01CS(CHIPS)':
 'VCCIN286': CDS_PINID='VCCIN286';
NODE_NAME     U1 CD49
 '@S9S_MB_2U_LIB.S9S_MB_2U(SCH_1):PAGE67_I1@PURE_QUANTA.SOCKET4677_AZIF0045P001C01CS(CHIPS)':
 'VCCIN287': CDS_PINID='VCCIN287';
NODE_NAME     U1 CD51
 '@S9S_MB_2U_LIB.S9S_MB_2U(SCH_1):PAGE67_I1@PURE_QUANTA.SOCKET4677_AZIF0045P001C01CS(CHIPS)':
 'VCCIN288': CDS_PINID='VCCIN288';
NODE_NAME     U1 CD53
 '@S9S_MB_2U_LIB.S9S_MB_2U(SCH_1):PAGE67_I1@PURE_QUANTA.SOCKET4677_AZIF0045P001C01CS(CHIPS)':
 'VCCIN289': CDS_PINID='VCCIN289';
NODE_NAME     U1 CD55
 '@S9S_MB_2U_LIB.S9S_MB_2U(SCH_1):PAGE67_I1@PURE_QUANTA.SOCKET4677_AZIF0045P001C01CS(CHIPS)':
 'VCCIN290': CDS_PINID='VCCIN290';
NODE_NAME     U1 CD57
 '@S9S_MB_2U_LIB.S9S_MB_2U(SCH_1):PAGE67_I1@PURE_QUANTA.SOCKET4677_AZIF0045P001C01CS(CHIPS)':
 'VCCIN291': CDS_PINID='VCCIN291';
NODE_NAME     U1 CD59
 '@S9S_MB_2U_LIB.S9S_MB_2U(SCH_1):PAGE67_I1@PURE_QUANTA.SOCKET4677_AZIF0045P001C01CS(CHIPS)':
 'VCCIN292': CDS_PINID='VCCIN292';
NODE_NAME     U1 CD79
 '@S9S_MB_2U_LIB.S9S_MB_2U(SCH_1):PAGE67_I1@PURE_QUANTA.SOCKET4677_AZIF0045P001C01CS(CHIPS)':
 'VCCIN293': CDS_PINID='VCCIN293';
NODE_NAME     U1 CD81
 '@S9S_MB_2U_LIB.S9S_MB_2U(SCH_1):PAGE67_I1@PURE_QUANTA.SOCKET4677_AZIF0045P001C01CS(CHIPS)':
 'VCCIN294': CDS_PINID='VCCIN294';
NODE_NAME     U1 CD83
 '@S9S_MB_2U_LIB.S9S_MB_2U(SCH_1):PAGE67_I1@PURE_QUANTA.SOCKET4677_AZIF0045P001C01CS(CHIPS)':
 'VCCIN295': CDS_PINID='VCCIN295';
NODE_NAME     U1 CD85
 '@S9S_MB_2U_LIB.S9S_MB_2U(SCH_1):PAGE67_I1@PURE_QUANTA.SOCKET4677_AZIF0045P001C01CS(CHIPS)':
 'VCCIN296': CDS_PINID='VCCIN296';
NODE_NAME     U1 CD87
 '@S9S_MB_2U_LIB.S9S_MB_2U(SCH_1):PAGE67_I1@PURE_QUANTA.SOCKET4677_AZIF0045P001C01CS(CHIPS)':
 'VCCIN297': CDS_PINID='VCCIN297';
NODE_NAME     U1 CD89
 '@S9S_MB_2U_LIB.S9S_MB_2U(SCH_1):PAGE67_I1@PURE_QUANTA.SOCKET4677_AZIF0045P001C01CS(CHIPS)':
 'VCCIN298': CDS_PINID='VCCIN298';
NODE_NAME     U1 CE80
 '@S9S_MB_2U_LIB.S9S_MB_2U(SCH_1):PAGE67_I1@PURE_QUANTA.SOCKET4677_AZIF0045P001C01CS(CHIPS)':
 'VCCIN299': CDS_PINID='VCCIN299';
NODE_NAME     U1 CE82
 '@S9S_MB_2U_LIB.S9S_MB_2U(SCH_1):PAGE67_I1@PURE_QUANTA.SOCKET4677_AZIF0045P001C01CS(CHIPS)':
 'VCCIN300': CDS_PINID='VCCIN300';
NODE_NAME     U1 CE84
 '@S9S_MB_2U_LIB.S9S_MB_2U(SCH_1):PAGE67_I1@PURE_QUANTA.SOCKET4677_AZIF0045P001C01CS(CHIPS)':
 'VCCIN301': CDS_PINID='VCCIN301';
NODE_NAME     U1 CE86
 '@S9S_MB_2U_LIB.S9S_MB_2U(SCH_1):PAGE67_I1@PURE_QUANTA.SOCKET4677_AZIF0045P001C01CS(CHIPS)':
 'VCCIN302': CDS_PINID='VCCIN302';
NODE_NAME     U1 CE88
 '@S9S_MB_2U_LIB.S9S_MB_2U(SCH_1):PAGE67_I1@PURE_QUANTA.SOCKET4677_AZIF0045P001C01CS(CHIPS)':
 'VCCIN303': CDS_PINID='VCCIN303';
NODE_NAME     U1 CE90
 '@S9S_MB_2U_LIB.S9S_MB_2U(SCH_1):PAGE67_I1@PURE_QUANTA.SOCKET4677_AZIF0045P001C01CS(CHIPS)':
 'VCCIN304': CDS_PINID='VCCIN304';
NODE_NAME     U1 CF79
 '@S9S_MB_2U_LIB.S9S_MB_2U(SCH_1):PAGE67_I1@PURE_QUANTA.SOCKET4677_AZIF0045P001C01CS(CHIPS)':
 'VCCIN305': CDS_PINID='VCCIN305';
NODE_NAME     U1 CF81
 '@S9S_MB_2U_LIB.S9S_MB_2U(SCH_1):PAGE67_I1@PURE_QUANTA.SOCKET4677_AZIF0045P001C01CS(CHIPS)':
 'VCCIN306': CDS_PINID='VCCIN306';
NODE_NAME     U1 CF83
 '@S9S_MB_2U_LIB.S9S_MB_2U(SCH_1):PAGE67_I1@PURE_QUANTA.SOCKET4677_AZIF0045P001C01CS(CHIPS)':
 'VCCIN307': CDS_PINID='VCCIN307';
NODE_NAME     U1 CF85
 '@S9S_MB_2U_LIB.S9S_MB_2U(SCH_1):PAGE67_I1@PURE_QUANTA.SOCKET4677_AZIF0045P001C01CS(CHIPS)':
 'VCCIN308': CDS_PINID='VCCIN308';
NODE_NAME     U1 CF87
 '@S9S_MB_2U_LIB.S9S_MB_2U(SCH_1):PAGE67_I1@PURE_QUANTA.SOCKET4677_AZIF0045P001C01CS(CHIPS)':
 'VCCIN309': CDS_PINID='VCCIN309';
NODE_NAME     U1 CF89
 '@S9S_MB_2U_LIB.S9S_MB_2U(SCH_1):PAGE67_I1@PURE_QUANTA.SOCKET4677_AZIF0045P001C01CS(CHIPS)':
 'VCCIN310': CDS_PINID='VCCIN310';
NODE_NAME     U1 CF91
 '@S9S_MB_2U_LIB.S9S_MB_2U(SCH_1):PAGE67_I1@PURE_QUANTA.SOCKET4677_AZIF0045P001C01CS(CHIPS)':
 'VCCIN311': CDS_PINID='VCCIN311';
NODE_NAME     U1 CG80
 '@S9S_MB_2U_LIB.S9S_MB_2U(SCH_1):PAGE67_I1@PURE_QUANTA.SOCKET4677_AZIF0045P001C01CS(CHIPS)':
 'VCCIN312': CDS_PINID='VCCIN312';
NODE_NAME     U1 CG82
 '@S9S_MB_2U_LIB.S9S_MB_2U(SCH_1):PAGE67_I1@PURE_QUANTA.SOCKET4677_AZIF0045P001C01CS(CHIPS)':
 'VCCIN313': CDS_PINID='VCCIN313';
NODE_NAME     U1 CG84
 '@S9S_MB_2U_LIB.S9S_MB_2U(SCH_1):PAGE67_I1@PURE_QUANTA.SOCKET4677_AZIF0045P001C01CS(CHIPS)':
 'VCCIN314': CDS_PINID='VCCIN314';
NODE_NAME     U1 CG86
 '@S9S_MB_2U_LIB.S9S_MB_2U(SCH_1):PAGE67_I1@PURE_QUANTA.SOCKET4677_AZIF0045P001C01CS(CHIPS)':
 'VCCIN315': CDS_PINID='VCCIN315';
NODE_NAME     U1 CG88
 '@S9S_MB_2U_LIB.S9S_MB_2U(SCH_1):PAGE67_I1@PURE_QUANTA.SOCKET4677_AZIF0045P001C01CS(CHIPS)':
 'VCCIN316': CDS_PINID='VCCIN316';
NODE_NAME     U1 CG90
 '@S9S_MB_2U_LIB.S9S_MB_2U(SCH_1):PAGE67_I1@PURE_QUANTA.SOCKET4677_AZIF0045P001C01CS(CHIPS)':
 'VCCIN317': CDS_PINID='VCCIN317';
NODE_NAME     U1 CH81
 '@S9S_MB_2U_LIB.S9S_MB_2U(SCH_1):PAGE67_I1@PURE_QUANTA.SOCKET4677_AZIF0045P001C01CS(CHIPS)':
 'VCCIN318': CDS_PINID='VCCIN318';
NODE_NAME     U1 CH91
 '@S9S_MB_2U_LIB.S9S_MB_2U(SCH_1):PAGE67_I1@PURE_QUANTA.SOCKET4677_AZIF0045P001C01CS(CHIPS)':
 'VCCIN319': CDS_PINID='VCCIN319';
NODE_NAME     U1 CJ82
 '@S9S_MB_2U_LIB.S9S_MB_2U(SCH_1):PAGE67_I1@PURE_QUANTA.SOCKET4677_AZIF0045P001C01CS(CHIPS)':
 'VCCIN320': CDS_PINID='VCCIN320';
NODE_NAME     U1 CJ84
 '@S9S_MB_2U_LIB.S9S_MB_2U(SCH_1):PAGE67_I1@PURE_QUANTA.SOCKET4677_AZIF0045P001C01CS(CHIPS)':
 'VCCIN321': CDS_PINID='VCCIN321';
NODE_NAME     U1 CJ86
 '@S9S_MB_2U_LIB.S9S_MB_2U(SCH_1):PAGE67_I1@PURE_QUANTA.SOCKET4677_AZIF0045P001C01CS(CHIPS)':
 'VCCIN322': CDS_PINID='VCCIN322';
NODE_NAME     U1 CJ88
 '@S9S_MB_2U_LIB.S9S_MB_2U(SCH_1):PAGE67_I1@PURE_QUANTA.SOCKET4677_AZIF0045P001C01CS(CHIPS)':
 'VCCIN323': CDS_PINID='VCCIN323';
NODE_NAME     U1 CJ90
 '@S9S_MB_2U_LIB.S9S_MB_2U(SCH_1):PAGE67_I1@PURE_QUANTA.SOCKET4677_AZIF0045P001C01CS(CHIPS)':
 'VCCIN324': CDS_PINID='VCCIN324';
NODE_NAME     U1 CK83
 '@S9S_MB_2U_LIB.S9S_MB_2U(SCH_1):PAGE67_I1@PURE_QUANTA.SOCKET4677_AZIF0045P001C01CS(CHIPS)':
 'VCCIN325': CDS_PINID='VCCIN325';
NODE_NAME     U1 CK85
 '@S9S_MB_2U_LIB.S9S_MB_2U(SCH_1):PAGE67_I1@PURE_QUANTA.SOCKET4677_AZIF0045P001C01CS(CHIPS)':
 'VCCIN326': CDS_PINID='VCCIN326';
NODE_NAME     U1 CK87
 '@S9S_MB_2U_LIB.S9S_MB_2U(SCH_1):PAGE67_I1@PURE_QUANTA.SOCKET4677_AZIF0045P001C01CS(CHIPS)':
 'VCCIN327': CDS_PINID='VCCIN327';
NODE_NAME     U1 CK89
 '@S9S_MB_2U_LIB.S9S_MB_2U(SCH_1):PAGE67_I1@PURE_QUANTA.SOCKET4677_AZIF0045P001C01CS(CHIPS)':
 'VCCIN328': CDS_PINID='VCCIN328';
NODE_NAME     U1 CK91
 '@S9S_MB_2U_LIB.S9S_MB_2U(SCH_1):PAGE67_I1@PURE_QUANTA.SOCKET4677_AZIF0045P001C01CS(CHIPS)':
 'VCCIN329': CDS_PINID='VCCIN329';
NODE_NAME     U1 CL84
 '@S9S_MB_2U_LIB.S9S_MB_2U(SCH_1):PAGE67_I1@PURE_QUANTA.SOCKET4677_AZIF0045P001C01CS(CHIPS)':
 'VCCIN330': CDS_PINID='VCCIN330';
NODE_NAME     U1 CL86
 '@S9S_MB_2U_LIB.S9S_MB_2U(SCH_1):PAGE67_I1@PURE_QUANTA.SOCKET4677_AZIF0045P001C01CS(CHIPS)':
 'VCCIN331': CDS_PINID='VCCIN331';
NODE_NAME     U1 CL88
 '@S9S_MB_2U_LIB.S9S_MB_2U(SCH_1):PAGE67_I1@PURE_QUANTA.SOCKET4677_AZIF0045P001C01CS(CHIPS)':
 'VCCIN332': CDS_PINID='VCCIN332';
NODE_NAME     U1 CL90
 '@S9S_MB_2U_LIB.S9S_MB_2U(SCH_1):PAGE67_I1@PURE_QUANTA.SOCKET4677_AZIF0045P001C01CS(CHIPS)':
 'VCCIN333': CDS_PINID='VCCIN333';
NODE_NAME     U1 CM87
 '@S9S_MB_2U_LIB.S9S_MB_2U(SCH_1):PAGE67_I1@PURE_QUANTA.SOCKET4677_AZIF0045P001C01CS(CHIPS)':
 'VCCIN334': CDS_PINID='VCCIN334';
NODE_NAME     U1 CM91
 '@S9S_MB_2U_LIB.S9S_MB_2U(SCH_1):PAGE67_I1@PURE_QUANTA.SOCKET4677_AZIF0045P001C01CS(CHIPS)':
 'VCCIN335': CDS_PINID='VCCIN335';
NODE_NAME     U1 CN88
 '@S9S_MB_2U_LIB.S9S_MB_2U(SCH_1):PAGE67_I1@PURE_QUANTA.SOCKET4677_AZIF0045P001C01CS(CHIPS)':
 'VCCIN336': CDS_PINID='VCCIN336';
NODE_NAME     U1 CN90
 '@S9S_MB_2U_LIB.S9S_MB_2U(SCH_1):PAGE67_I1@PURE_QUANTA.SOCKET4677_AZIF0045P001C01CS(CHIPS)':
 'VCCIN337': CDS_PINID='VCCIN337';
NODE_NAME     U1 CP89
 '@S9S_MB_2U_LIB.S9S_MB_2U(SCH_1):PAGE67_I1@PURE_QUANTA.SOCKET4677_AZIF0045P001C01CS(CHIPS)':
 'VCCIN338': CDS_PINID='VCCIN338';
NODE_NAME     U1 CM89
 '@S9S_MB_2U_LIB.S9S_MB_2U(SCH_1):PAGE67_I1@PURE_QUANTA.SOCKET4677_AZIF0045P001C01CS(CHIPS)':
 'VCCIN339': CDS_PINID='VCCIN339';
NODE_NAME     U1 BN43
 '@S9S_MB_2U_LIB.S9S_MB_2U(SCH_1):PAGE67_I3@PURE_QUANTA.SOCKET4677_AZIF0045P001C01CS(CHIPS)':
 'VCCIN40': CDS_PINID='VCCIN40';
NODE_NAME     U1 BN45
 '@S9S_MB_2U_LIB.S9S_MB_2U(SCH_1):PAGE67_I3@PURE_QUANTA.SOCKET4677_AZIF0045P001C01CS(CHIPS)':
 'VCCIN41': CDS_PINID='VCCIN41';
NODE_NAME     U1 BN48
 '@S9S_MB_2U_LIB.S9S_MB_2U(SCH_1):PAGE67_I3@PURE_QUANTA.SOCKET4677_AZIF0045P001C01CS(CHIPS)':
 'VCCIN42': CDS_PINID='VCCIN42';
NODE_NAME     U1 BN50
 '@S9S_MB_2U_LIB.S9S_MB_2U(SCH_1):PAGE67_I3@PURE_QUANTA.SOCKET4677_AZIF0045P001C01CS(CHIPS)':
 'VCCIN43': CDS_PINID='VCCIN43';
NODE_NAME     U1 BN52
 '@S9S_MB_2U_LIB.S9S_MB_2U(SCH_1):PAGE67_I3@PURE_QUANTA.SOCKET4677_AZIF0045P001C01CS(CHIPS)':
 'VCCIN44': CDS_PINID='VCCIN44';
NODE_NAME     U1 BN54
 '@S9S_MB_2U_LIB.S9S_MB_2U(SCH_1):PAGE67_I3@PURE_QUANTA.SOCKET4677_AZIF0045P001C01CS(CHIPS)':
 'VCCIN45': CDS_PINID='VCCIN45';
NODE_NAME     U1 BN56
 '@S9S_MB_2U_LIB.S9S_MB_2U(SCH_1):PAGE67_I3@PURE_QUANTA.SOCKET4677_AZIF0045P001C01CS(CHIPS)':
 'VCCIN46': CDS_PINID='VCCIN46';
NODE_NAME     U1 BN58
 '@S9S_MB_2U_LIB.S9S_MB_2U(SCH_1):PAGE67_I3@PURE_QUANTA.SOCKET4677_AZIF0045P001C01CS(CHIPS)':
 'VCCIN47': CDS_PINID='VCCIN47';
NODE_NAME     U1 BN60
 '@S9S_MB_2U_LIB.S9S_MB_2U(SCH_1):PAGE67_I3@PURE_QUANTA.SOCKET4677_AZIF0045P001C01CS(CHIPS)':
 'VCCIN48': CDS_PINID='VCCIN48';
NODE_NAME     U1 BN78
 '@S9S_MB_2U_LIB.S9S_MB_2U(SCH_1):PAGE67_I3@PURE_QUANTA.SOCKET4677_AZIF0045P001C01CS(CHIPS)':
 'VCCIN49': CDS_PINID='VCCIN49';
NODE_NAME     U1 BN80
 '@S9S_MB_2U_LIB.S9S_MB_2U(SCH_1):PAGE67_I3@PURE_QUANTA.SOCKET4677_AZIF0045P001C01CS(CHIPS)':
 'VCCIN50': CDS_PINID='VCCIN50';
NODE_NAME     U1 BN82
 '@S9S_MB_2U_LIB.S9S_MB_2U(SCH_1):PAGE67_I3@PURE_QUANTA.SOCKET4677_AZIF0045P001C01CS(CHIPS)':
 'VCCIN51': CDS_PINID='VCCIN51';
NODE_NAME     U1 BN84
 '@S9S_MB_2U_LIB.S9S_MB_2U(SCH_1):PAGE67_I3@PURE_QUANTA.SOCKET4677_AZIF0045P001C01CS(CHIPS)':
 'VCCIN52': CDS_PINID='VCCIN52';
NODE_NAME     U1 BN86
 '@S9S_MB_2U_LIB.S9S_MB_2U(SCH_1):PAGE67_I3@PURE_QUANTA.SOCKET4677_AZIF0045P001C01CS(CHIPS)':
 'VCCIN53': CDS_PINID='VCCIN53';
NODE_NAME     U1 BN88
 '@S9S_MB_2U_LIB.S9S_MB_2U(SCH_1):PAGE67_I3@PURE_QUANTA.SOCKET4677_AZIF0045P001C01CS(CHIPS)':
 'VCCIN54': CDS_PINID='VCCIN54';
NODE_NAME     U1 BN90
 '@S9S_MB_2U_LIB.S9S_MB_2U(SCH_1):PAGE67_I3@PURE_QUANTA.SOCKET4677_AZIF0045P001C01CS(CHIPS)':
 'VCCIN55': CDS_PINID='VCCIN55';
NODE_NAME     U1 BP32
 '@S9S_MB_2U_LIB.S9S_MB_2U(SCH_1):PAGE67_I3@PURE_QUANTA.SOCKET4677_AZIF0045P001C01CS(CHIPS)':
 'VCCIN56': CDS_PINID='VCCIN56';
NODE_NAME     U1 BP34
 '@S9S_MB_2U_LIB.S9S_MB_2U(SCH_1):PAGE67_I3@PURE_QUANTA.SOCKET4677_AZIF0045P001C01CS(CHIPS)':
 'VCCIN57': CDS_PINID='VCCIN57';
NODE_NAME     U1 BP36
 '@S9S_MB_2U_LIB.S9S_MB_2U(SCH_1):PAGE67_I3@PURE_QUANTA.SOCKET4677_AZIF0045P001C01CS(CHIPS)':
 'VCCIN58': CDS_PINID='VCCIN58';
NODE_NAME     U1 BP38
 '@S9S_MB_2U_LIB.S9S_MB_2U(SCH_1):PAGE67_I3@PURE_QUANTA.SOCKET4677_AZIF0045P001C01CS(CHIPS)':
 'VCCIN59': CDS_PINID='VCCIN59';
NODE_NAME     U1 BP40
 '@S9S_MB_2U_LIB.S9S_MB_2U(SCH_1):PAGE67_I3@PURE_QUANTA.SOCKET4677_AZIF0045P001C01CS(CHIPS)':
 'VCCIN60': CDS_PINID='VCCIN60';
NODE_NAME     U1 BP42
 '@S9S_MB_2U_LIB.S9S_MB_2U(SCH_1):PAGE67_I3@PURE_QUANTA.SOCKET4677_AZIF0045P001C01CS(CHIPS)':
 'VCCIN61': CDS_PINID='VCCIN61';
NODE_NAME     U1 BP44
 '@S9S_MB_2U_LIB.S9S_MB_2U(SCH_1):PAGE67_I3@PURE_QUANTA.SOCKET4677_AZIF0045P001C01CS(CHIPS)':
 'VCCIN62': CDS_PINID='VCCIN62';
NODE_NAME     U1 BP47
 '@S9S_MB_2U_LIB.S9S_MB_2U(SCH_1):PAGE67_I3@PURE_QUANTA.SOCKET4677_AZIF0045P001C01CS(CHIPS)':
 'VCCIN63': CDS_PINID='VCCIN63';
NODE_NAME     U1 BP49
 '@S9S_MB_2U_LIB.S9S_MB_2U(SCH_1):PAGE67_I3@PURE_QUANTA.SOCKET4677_AZIF0045P001C01CS(CHIPS)':
 'VCCIN64': CDS_PINID='VCCIN64';
NODE_NAME     U1 BP51
 '@S9S_MB_2U_LIB.S9S_MB_2U(SCH_1):PAGE67_I3@PURE_QUANTA.SOCKET4677_AZIF0045P001C01CS(CHIPS)':
 'VCCIN65': CDS_PINID='VCCIN65';
NODE_NAME     U1 BP53
 '@S9S_MB_2U_LIB.S9S_MB_2U(SCH_1):PAGE67_I3@PURE_QUANTA.SOCKET4677_AZIF0045P001C01CS(CHIPS)':
 'VCCIN66': CDS_PINID='VCCIN66';
NODE_NAME     U1 BP55
 '@S9S_MB_2U_LIB.S9S_MB_2U(SCH_1):PAGE67_I3@PURE_QUANTA.SOCKET4677_AZIF0045P001C01CS(CHIPS)':
 'VCCIN67': CDS_PINID='VCCIN67';
NODE_NAME     U1 BP57
 '@S9S_MB_2U_LIB.S9S_MB_2U(SCH_1):PAGE67_I3@PURE_QUANTA.SOCKET4677_AZIF0045P001C01CS(CHIPS)':
 'VCCIN68': CDS_PINID='VCCIN68';
NODE_NAME     U1 BP59
 '@S9S_MB_2U_LIB.S9S_MB_2U(SCH_1):PAGE67_I3@PURE_QUANTA.SOCKET4677_AZIF0045P001C01CS(CHIPS)':
 'VCCIN69': CDS_PINID='VCCIN69';
NODE_NAME     U1 BP61
 '@S9S_MB_2U_LIB.S9S_MB_2U(SCH_1):PAGE67_I3@PURE_QUANTA.SOCKET4677_AZIF0045P001C01CS(CHIPS)':
 'VCCIN70': CDS_PINID='VCCIN70';
NODE_NAME     U1 BP79
 '@S9S_MB_2U_LIB.S9S_MB_2U(SCH_1):PAGE67_I3@PURE_QUANTA.SOCKET4677_AZIF0045P001C01CS(CHIPS)':
 'VCCIN71': CDS_PINID='VCCIN71';
NODE_NAME     U1 BP81
 '@S9S_MB_2U_LIB.S9S_MB_2U(SCH_1):PAGE67_I3@PURE_QUANTA.SOCKET4677_AZIF0045P001C01CS(CHIPS)':
 'VCCIN72': CDS_PINID='VCCIN72';
NODE_NAME     U1 BP83
 '@S9S_MB_2U_LIB.S9S_MB_2U(SCH_1):PAGE67_I3@PURE_QUANTA.SOCKET4677_AZIF0045P001C01CS(CHIPS)':
 'VCCIN73': CDS_PINID='VCCIN73';
NODE_NAME     U1 BP85
 '@S9S_MB_2U_LIB.S9S_MB_2U(SCH_1):PAGE67_I3@PURE_QUANTA.SOCKET4677_AZIF0045P001C01CS(CHIPS)':
 'VCCIN74': CDS_PINID='VCCIN74';
NODE_NAME     U1 BP87
 '@S9S_MB_2U_LIB.S9S_MB_2U(SCH_1):PAGE67_I3@PURE_QUANTA.SOCKET4677_AZIF0045P001C01CS(CHIPS)':
 'VCCIN75': CDS_PINID='VCCIN75';
NODE_NAME     U1 BP89
 '@S9S_MB_2U_LIB.S9S_MB_2U(SCH_1):PAGE67_I3@PURE_QUANTA.SOCKET4677_AZIF0045P001C01CS(CHIPS)':
 'VCCIN76': CDS_PINID='VCCIN76';
NODE_NAME     U1 BR60
 '@S9S_MB_2U_LIB.S9S_MB_2U(SCH_1):PAGE67_I3@PURE_QUANTA.SOCKET4677_AZIF0045P001C01CS(CHIPS)':
 'VCCIN77': CDS_PINID='VCCIN77';
NODE_NAME     U1 BR62
 '@S9S_MB_2U_LIB.S9S_MB_2U(SCH_1):PAGE67_I3@PURE_QUANTA.SOCKET4677_AZIF0045P001C01CS(CHIPS)':
 'VCCIN78': CDS_PINID='VCCIN78';
NODE_NAME     U1 BR78
 '@S9S_MB_2U_LIB.S9S_MB_2U(SCH_1):PAGE67_I3@PURE_QUANTA.SOCKET4677_AZIF0045P001C01CS(CHIPS)':
 'VCCIN79': CDS_PINID='VCCIN79';
NODE_NAME     U1 BT32
 '@S9S_MB_2U_LIB.S9S_MB_2U(SCH_1):PAGE67_I3@PURE_QUANTA.SOCKET4677_AZIF0045P001C01CS(CHIPS)':
 'VCCIN80': CDS_PINID='VCCIN80';
NODE_NAME     U1 BT34
 '@S9S_MB_2U_LIB.S9S_MB_2U(SCH_1):PAGE67_I3@PURE_QUANTA.SOCKET4677_AZIF0045P001C01CS(CHIPS)':
 'VCCIN81': CDS_PINID='VCCIN81';
NODE_NAME     U1 BT36
 '@S9S_MB_2U_LIB.S9S_MB_2U(SCH_1):PAGE67_I3@PURE_QUANTA.SOCKET4677_AZIF0045P001C01CS(CHIPS)':
 'VCCIN82': CDS_PINID='VCCIN82';
NODE_NAME     U1 BT38
 '@S9S_MB_2U_LIB.S9S_MB_2U(SCH_1):PAGE67_I3@PURE_QUANTA.SOCKET4677_AZIF0045P001C01CS(CHIPS)':
 'VCCIN83': CDS_PINID='VCCIN83';
NODE_NAME     U1 BT40
 '@S9S_MB_2U_LIB.S9S_MB_2U(SCH_1):PAGE67_I3@PURE_QUANTA.SOCKET4677_AZIF0045P001C01CS(CHIPS)':
 'VCCIN84': CDS_PINID='VCCIN84';
NODE_NAME     U1 BT42
 '@S9S_MB_2U_LIB.S9S_MB_2U(SCH_1):PAGE67_I3@PURE_QUANTA.SOCKET4677_AZIF0045P001C01CS(CHIPS)':
 'VCCIN85': CDS_PINID='VCCIN85';
NODE_NAME     U1 BT44
 '@S9S_MB_2U_LIB.S9S_MB_2U(SCH_1):PAGE67_I3@PURE_QUANTA.SOCKET4677_AZIF0045P001C01CS(CHIPS)':
 'VCCIN86': CDS_PINID='VCCIN86';
NODE_NAME     U1 BT47
 '@S9S_MB_2U_LIB.S9S_MB_2U(SCH_1):PAGE67_I3@PURE_QUANTA.SOCKET4677_AZIF0045P001C01CS(CHIPS)':
 'VCCIN87': CDS_PINID='VCCIN87';
NODE_NAME     U1 BT49
 '@S9S_MB_2U_LIB.S9S_MB_2U(SCH_1):PAGE67_I3@PURE_QUANTA.SOCKET4677_AZIF0045P001C01CS(CHIPS)':
 'VCCIN88': CDS_PINID='VCCIN88';
NODE_NAME     U1 BT51
 '@S9S_MB_2U_LIB.S9S_MB_2U(SCH_1):PAGE67_I3@PURE_QUANTA.SOCKET4677_AZIF0045P001C01CS(CHIPS)':
 'VCCIN89': CDS_PINID='VCCIN89';
NODE_NAME     U1 BT53
 '@S9S_MB_2U_LIB.S9S_MB_2U(SCH_1):PAGE67_I3@PURE_QUANTA.SOCKET4677_AZIF0045P001C01CS(CHIPS)':
 'VCCIN90': CDS_PINID='VCCIN90';
NODE_NAME     U1 BT55
 '@S9S_MB_2U_LIB.S9S_MB_2U(SCH_1):PAGE67_I3@PURE_QUANTA.SOCKET4677_AZIF0045P001C01CS(CHIPS)':
 'VCCIN91': CDS_PINID='VCCIN91';
NODE_NAME     U1 BT57
 '@S9S_MB_2U_LIB.S9S_MB_2U(SCH_1):PAGE67_I3@PURE_QUANTA.SOCKET4677_AZIF0045P001C01CS(CHIPS)':
 'VCCIN92': CDS_PINID='VCCIN92';
NODE_NAME     U1 BT59
 '@S9S_MB_2U_LIB.S9S_MB_2U(SCH_1):PAGE67_I3@PURE_QUANTA.SOCKET4677_AZIF0045P001C01CS(CHIPS)':
 'VCCIN93': CDS_PINID='VCCIN93';
NODE_NAME     U1 BT61
 '@S9S_MB_2U_LIB.S9S_MB_2U(SCH_1):PAGE67_I3@PURE_QUANTA.SOCKET4677_AZIF0045P001C01CS(CHIPS)':
 'VCCIN94': CDS_PINID='VCCIN94';
NODE_NAME     U1 BT63
 '@S9S_MB_2U_LIB.S9S_MB_2U(SCH_1):PAGE67_I3@PURE_QUANTA.SOCKET4677_AZIF0045P001C01CS(CHIPS)':
 'VCCIN95': CDS_PINID='VCCIN95';
NODE_NAME     U1 BT65
 '@S9S_MB_2U_LIB.S9S_MB_2U(SCH_1):PAGE67_I3@PURE_QUANTA.SOCKET4677_AZIF0045P001C01CS(CHIPS)':
 'VCCIN96': CDS_PINID='VCCIN96';
NODE_NAME     U1 BT67
 '@S9S_MB_2U_LIB.S9S_MB_2U(SCH_1):PAGE67_I3@PURE_QUANTA.SOCKET4677_AZIF0045P001C01CS(CHIPS)':
 'VCCIN97': CDS_PINID='VCCIN97';
NODE_NAME     U1 BT69
 '@S9S_MB_2U_LIB.S9S_MB_2U(SCH_1):PAGE67_I3@PURE_QUANTA.SOCKET4677_AZIF0045P001C01CS(CHIPS)':
 'VCCIN98': CDS_PINID='VCCIN98';
NODE_NAME     U1 BT71
 '@S9S_MB_2U_LIB.S9S_MB_2U(SCH_1):PAGE67_I3@PURE_QUANTA.SOCKET4677_AZIF0045P001C01CS(CHIPS)':
 'VCCIN99': CDS_PINID='VCCIN99';
NODE_NAME     U1 BT73
 '@S9S_MB_2U_LIB.S9S_MB_2U(SCH_1):PAGE67_I3@PURE_QUANTA.SOCKET4677_AZIF0045P001C01CS(CHIPS)':
 'VCCIN100': CDS_PINID='VCCIN100';
NODE_NAME     U1 BT75
 '@S9S_MB_2U_LIB.S9S_MB_2U(SCH_1):PAGE67_I3@PURE_QUANTA.SOCKET4677_AZIF0045P001C01CS(CHIPS)':
 'VCCIN101': CDS_PINID='VCCIN101';
NODE_NAME     U1 BT77
 '@S9S_MB_2U_LIB.S9S_MB_2U(SCH_1):PAGE67_I3@PURE_QUANTA.SOCKET4677_AZIF0045P001C01CS(CHIPS)':
 'VCCIN102': CDS_PINID='VCCIN102';
NODE_NAME     U1 BT79
 '@S9S_MB_2U_LIB.S9S_MB_2U(SCH_1):PAGE67_I3@PURE_QUANTA.SOCKET4677_AZIF0045P001C01CS(CHIPS)':
 'VCCIN103': CDS_PINID='VCCIN103';
NODE_NAME     U1 BT81
 '@S9S_MB_2U_LIB.S9S_MB_2U(SCH_1):PAGE67_I3@PURE_QUANTA.SOCKET4677_AZIF0045P001C01CS(CHIPS)':
 'VCCIN104': CDS_PINID='VCCIN104';
NODE_NAME     U1 BT83
 '@S9S_MB_2U_LIB.S9S_MB_2U(SCH_1):PAGE67_I3@PURE_QUANTA.SOCKET4677_AZIF0045P001C01CS(CHIPS)':
 'VCCIN105': CDS_PINID='VCCIN105';
NODE_NAME     U1 BT85
 '@S9S_MB_2U_LIB.S9S_MB_2U(SCH_1):PAGE67_I3@PURE_QUANTA.SOCKET4677_AZIF0045P001C01CS(CHIPS)':
 'VCCIN106': CDS_PINID='VCCIN106';
NODE_NAME     U1 BT87
 '@S9S_MB_2U_LIB.S9S_MB_2U(SCH_1):PAGE67_I3@PURE_QUANTA.SOCKET4677_AZIF0045P001C01CS(CHIPS)':
 'VCCIN107': CDS_PINID='VCCIN107';
NODE_NAME     U1 BT89
 '@S9S_MB_2U_LIB.S9S_MB_2U(SCH_1):PAGE67_I3@PURE_QUANTA.SOCKET4677_AZIF0045P001C01CS(CHIPS)':
 'VCCIN108': CDS_PINID='VCCIN108';
NODE_NAME     U1 BU33
 '@S9S_MB_2U_LIB.S9S_MB_2U(SCH_1):PAGE67_I3@PURE_QUANTA.SOCKET4677_AZIF0045P001C01CS(CHIPS)':
 'VCCIN109': CDS_PINID='VCCIN109';
NODE_NAME     U1 BU35
 '@S9S_MB_2U_LIB.S9S_MB_2U(SCH_1):PAGE67_I3@PURE_QUANTA.SOCKET4677_AZIF0045P001C01CS(CHIPS)':
 'VCCIN110': CDS_PINID='VCCIN110';
NODE_NAME     U1 BU37
 '@S9S_MB_2U_LIB.S9S_MB_2U(SCH_1):PAGE67_I3@PURE_QUANTA.SOCKET4677_AZIF0045P001C01CS(CHIPS)':
 'VCCIN111': CDS_PINID='VCCIN111';
NODE_NAME     U1 BU39
 '@S9S_MB_2U_LIB.S9S_MB_2U(SCH_1):PAGE67_I3@PURE_QUANTA.SOCKET4677_AZIF0045P001C01CS(CHIPS)':
 'VCCIN112': CDS_PINID='VCCIN112';
NODE_NAME     U1 BU41
 '@S9S_MB_2U_LIB.S9S_MB_2U(SCH_1):PAGE67_I3@PURE_QUANTA.SOCKET4677_AZIF0045P001C01CS(CHIPS)':
 'VCCIN113': CDS_PINID='VCCIN113';
NODE_NAME     U1 BU43
 '@S9S_MB_2U_LIB.S9S_MB_2U(SCH_1):PAGE67_I3@PURE_QUANTA.SOCKET4677_AZIF0045P001C01CS(CHIPS)':
 'VCCIN114': CDS_PINID='VCCIN114';
NODE_NAME     U1 BU45
 '@S9S_MB_2U_LIB.S9S_MB_2U(SCH_1):PAGE67_I3@PURE_QUANTA.SOCKET4677_AZIF0045P001C01CS(CHIPS)':
 'VCCIN115': CDS_PINID='VCCIN115';
NODE_NAME     U1 BU48
 '@S9S_MB_2U_LIB.S9S_MB_2U(SCH_1):PAGE67_I3@PURE_QUANTA.SOCKET4677_AZIF0045P001C01CS(CHIPS)':
 'VCCIN116': CDS_PINID='VCCIN116';
NODE_NAME     U1 BU50
 '@S9S_MB_2U_LIB.S9S_MB_2U(SCH_1):PAGE67_I3@PURE_QUANTA.SOCKET4677_AZIF0045P001C01CS(CHIPS)':
 'VCCIN117': CDS_PINID='VCCIN117';
NODE_NAME     U1 BU52
 '@S9S_MB_2U_LIB.S9S_MB_2U(SCH_1):PAGE67_I3@PURE_QUANTA.SOCKET4677_AZIF0045P001C01CS(CHIPS)':
 'VCCIN118': CDS_PINID='VCCIN118';
NODE_NAME     U1 BU54
 '@S9S_MB_2U_LIB.S9S_MB_2U(SCH_1):PAGE67_I3@PURE_QUANTA.SOCKET4677_AZIF0045P001C01CS(CHIPS)':
 'VCCIN119': CDS_PINID='VCCIN119';
NODE_NAME     U1 BU56
 '@S9S_MB_2U_LIB.S9S_MB_2U(SCH_1):PAGE67_I3@PURE_QUANTA.SOCKET4677_AZIF0045P001C01CS(CHIPS)':
 'VCCIN120': CDS_PINID='VCCIN120';
NODE_NAME     U1 BU58
 '@S9S_MB_2U_LIB.S9S_MB_2U(SCH_1):PAGE67_I3@PURE_QUANTA.SOCKET4677_AZIF0045P001C01CS(CHIPS)':
 'VCCIN121': CDS_PINID='VCCIN121';
NODE_NAME     U1 BU60
 '@S9S_MB_2U_LIB.S9S_MB_2U(SCH_1):PAGE67_I3@PURE_QUANTA.SOCKET4677_AZIF0045P001C01CS(CHIPS)':
 'VCCIN122': CDS_PINID='VCCIN122';
NODE_NAME     U1 BU62
 '@S9S_MB_2U_LIB.S9S_MB_2U(SCH_1):PAGE67_I3@PURE_QUANTA.SOCKET4677_AZIF0045P001C01CS(CHIPS)':
 'VCCIN123': CDS_PINID='VCCIN123';
NODE_NAME     U1 BU64
 '@S9S_MB_2U_LIB.S9S_MB_2U(SCH_1):PAGE67_I3@PURE_QUANTA.SOCKET4677_AZIF0045P001C01CS(CHIPS)':
 'VCCIN124': CDS_PINID='VCCIN124';
NODE_NAME     U1 BU66
 '@S9S_MB_2U_LIB.S9S_MB_2U(SCH_1):PAGE67_I3@PURE_QUANTA.SOCKET4677_AZIF0045P001C01CS(CHIPS)':
 'VCCIN125': CDS_PINID='VCCIN125';
NODE_NAME     U1 BU68
 '@S9S_MB_2U_LIB.S9S_MB_2U(SCH_1):PAGE67_I3@PURE_QUANTA.SOCKET4677_AZIF0045P001C01CS(CHIPS)':
 'VCCIN126': CDS_PINID='VCCIN126';
NODE_NAME     U1 BU70
 '@S9S_MB_2U_LIB.S9S_MB_2U(SCH_1):PAGE67_I3@PURE_QUANTA.SOCKET4677_AZIF0045P001C01CS(CHIPS)':
 'VCCIN127': CDS_PINID='VCCIN127';
NODE_NAME     U1 BU72
 '@S9S_MB_2U_LIB.S9S_MB_2U(SCH_1):PAGE67_I3@PURE_QUANTA.SOCKET4677_AZIF0045P001C01CS(CHIPS)':
 'VCCIN128': CDS_PINID='VCCIN128';
NODE_NAME     U1 BU74
 '@S9S_MB_2U_LIB.S9S_MB_2U(SCH_1):PAGE67_I3@PURE_QUANTA.SOCKET4677_AZIF0045P001C01CS(CHIPS)':
 'VCCIN129': CDS_PINID='VCCIN129';
NODE_NAME     U1 BU76
 '@S9S_MB_2U_LIB.S9S_MB_2U(SCH_1):PAGE67_I3@PURE_QUANTA.SOCKET4677_AZIF0045P001C01CS(CHIPS)':
 'VCCIN130': CDS_PINID='VCCIN130';
NODE_NAME     U1 BU78
 '@S9S_MB_2U_LIB.S9S_MB_2U(SCH_1):PAGE67_I3@PURE_QUANTA.SOCKET4677_AZIF0045P001C01CS(CHIPS)':
 'VCCIN131': CDS_PINID='VCCIN131';
NODE_NAME     U1 BU80
 '@S9S_MB_2U_LIB.S9S_MB_2U(SCH_1):PAGE67_I3@PURE_QUANTA.SOCKET4677_AZIF0045P001C01CS(CHIPS)':
 'VCCIN132': CDS_PINID='VCCIN132';
NODE_NAME     U1 BU82
 '@S9S_MB_2U_LIB.S9S_MB_2U(SCH_1):PAGE67_I3@PURE_QUANTA.SOCKET4677_AZIF0045P001C01CS(CHIPS)':
 'VCCIN133': CDS_PINID='VCCIN133';
NODE_NAME     U1 BU84
 '@S9S_MB_2U_LIB.S9S_MB_2U(SCH_1):PAGE67_I3@PURE_QUANTA.SOCKET4677_AZIF0045P001C01CS(CHIPS)':
 'VCCIN134': CDS_PINID='VCCIN134';
NODE_NAME     U1 BU86
 '@S9S_MB_2U_LIB.S9S_MB_2U(SCH_1):PAGE67_I3@PURE_QUANTA.SOCKET4677_AZIF0045P001C01CS(CHIPS)':
 'VCCIN135': CDS_PINID='VCCIN135';
NODE_NAME     U1 BU88
 '@S9S_MB_2U_LIB.S9S_MB_2U(SCH_1):PAGE67_I3@PURE_QUANTA.SOCKET4677_AZIF0045P001C01CS(CHIPS)':
 'VCCIN136': CDS_PINID='VCCIN136';
NODE_NAME     U1 BU90
 '@S9S_MB_2U_LIB.S9S_MB_2U(SCH_1):PAGE67_I3@PURE_QUANTA.SOCKET4677_AZIF0045P001C01CS(CHIPS)':
 'VCCIN137': CDS_PINID='VCCIN137';
NODE_NAME     U1 BV32
 '@S9S_MB_2U_LIB.S9S_MB_2U(SCH_1):PAGE67_I3@PURE_QUANTA.SOCKET4677_AZIF0045P001C01CS(CHIPS)':
 'VCCIN138': CDS_PINID='VCCIN138';
NODE_NAME     U1 BV34
 '@S9S_MB_2U_LIB.S9S_MB_2U(SCH_1):PAGE67_I3@PURE_QUANTA.SOCKET4677_AZIF0045P001C01CS(CHIPS)':
 'VCCIN139': CDS_PINID='VCCIN139';
NODE_NAME     U1 BV36
 '@S9S_MB_2U_LIB.S9S_MB_2U(SCH_1):PAGE67_I3@PURE_QUANTA.SOCKET4677_AZIF0045P001C01CS(CHIPS)':
 'VCCIN140': CDS_PINID='VCCIN140';
NODE_NAME     U1 BV38
 '@S9S_MB_2U_LIB.S9S_MB_2U(SCH_1):PAGE67_I3@PURE_QUANTA.SOCKET4677_AZIF0045P001C01CS(CHIPS)':
 'VCCIN141': CDS_PINID='VCCIN141';
NODE_NAME     U1 BV40
 '@S9S_MB_2U_LIB.S9S_MB_2U(SCH_1):PAGE67_I3@PURE_QUANTA.SOCKET4677_AZIF0045P001C01CS(CHIPS)':
 'VCCIN142': CDS_PINID='VCCIN142';
NODE_NAME     U1 BV42
 '@S9S_MB_2U_LIB.S9S_MB_2U(SCH_1):PAGE67_I3@PURE_QUANTA.SOCKET4677_AZIF0045P001C01CS(CHIPS)':
 'VCCIN143': CDS_PINID='VCCIN143';
NODE_NAME     U1 BV44
 '@S9S_MB_2U_LIB.S9S_MB_2U(SCH_1):PAGE67_I3@PURE_QUANTA.SOCKET4677_AZIF0045P001C01CS(CHIPS)':
 'VCCIN144': CDS_PINID='VCCIN144';
NODE_NAME     U1 BV47
 '@S9S_MB_2U_LIB.S9S_MB_2U(SCH_1):PAGE67_I3@PURE_QUANTA.SOCKET4677_AZIF0045P001C01CS(CHIPS)':
 'VCCIN145': CDS_PINID='VCCIN145';
NODE_NAME     U1 BV49
 '@S9S_MB_2U_LIB.S9S_MB_2U(SCH_1):PAGE67_I3@PURE_QUANTA.SOCKET4677_AZIF0045P001C01CS(CHIPS)':
 'VCCIN146': CDS_PINID='VCCIN146';
NODE_NAME     U1 BV51
 '@S9S_MB_2U_LIB.S9S_MB_2U(SCH_1):PAGE67_I3@PURE_QUANTA.SOCKET4677_AZIF0045P001C01CS(CHIPS)':
 'VCCIN147': CDS_PINID='VCCIN147';
NODE_NAME     U1 BV53
 '@S9S_MB_2U_LIB.S9S_MB_2U(SCH_1):PAGE67_I3@PURE_QUANTA.SOCKET4677_AZIF0045P001C01CS(CHIPS)':
 'VCCIN148': CDS_PINID='VCCIN148';
NODE_NAME     U1 BV55
 '@S9S_MB_2U_LIB.S9S_MB_2U(SCH_1):PAGE67_I3@PURE_QUANTA.SOCKET4677_AZIF0045P001C01CS(CHIPS)':
 'VCCIN149': CDS_PINID='VCCIN149';
NODE_NAME     U1 BV57
 '@S9S_MB_2U_LIB.S9S_MB_2U(SCH_1):PAGE67_I3@PURE_QUANTA.SOCKET4677_AZIF0045P001C01CS(CHIPS)':
 'VCCIN150': CDS_PINID='VCCIN150';
NODE_NAME     U1 BV59
 '@S9S_MB_2U_LIB.S9S_MB_2U(SCH_1):PAGE67_I3@PURE_QUANTA.SOCKET4677_AZIF0045P001C01CS(CHIPS)':
 'VCCIN151': CDS_PINID='VCCIN151';
NODE_NAME     U1 BV61
 '@S9S_MB_2U_LIB.S9S_MB_2U(SCH_1):PAGE67_I3@PURE_QUANTA.SOCKET4677_AZIF0045P001C01CS(CHIPS)':
 'VCCIN152': CDS_PINID='VCCIN152';
NODE_NAME     U1 BV63
 '@S9S_MB_2U_LIB.S9S_MB_2U(SCH_1):PAGE67_I3@PURE_QUANTA.SOCKET4677_AZIF0045P001C01CS(CHIPS)':
 'VCCIN153': CDS_PINID='VCCIN153';
NODE_NAME     U1 BV65
 '@S9S_MB_2U_LIB.S9S_MB_2U(SCH_1):PAGE67_I3@PURE_QUANTA.SOCKET4677_AZIF0045P001C01CS(CHIPS)':
 'VCCIN154': CDS_PINID='VCCIN154';
NODE_NAME     U1 BV67
 '@S9S_MB_2U_LIB.S9S_MB_2U(SCH_1):PAGE67_I3@PURE_QUANTA.SOCKET4677_AZIF0045P001C01CS(CHIPS)':
 'VCCIN155': CDS_PINID='VCCIN155';
NODE_NAME     U1 BV69
 '@S9S_MB_2U_LIB.S9S_MB_2U(SCH_1):PAGE67_I3@PURE_QUANTA.SOCKET4677_AZIF0045P001C01CS(CHIPS)':
 'VCCIN156': CDS_PINID='VCCIN156';
NODE_NAME     U1 BV71
 '@S9S_MB_2U_LIB.S9S_MB_2U(SCH_1):PAGE67_I3@PURE_QUANTA.SOCKET4677_AZIF0045P001C01CS(CHIPS)':
 'VCCIN157': CDS_PINID='VCCIN157';
NODE_NAME     U1 BV73
 '@S9S_MB_2U_LIB.S9S_MB_2U(SCH_1):PAGE67_I3@PURE_QUANTA.SOCKET4677_AZIF0045P001C01CS(CHIPS)':
 'VCCIN158': CDS_PINID='VCCIN158';
NODE_NAME     U1 BV75
 '@S9S_MB_2U_LIB.S9S_MB_2U(SCH_1):PAGE67_I3@PURE_QUANTA.SOCKET4677_AZIF0045P001C01CS(CHIPS)':
 'VCCIN159': CDS_PINID='VCCIN159';
NODE_NAME     U1 BV77
 '@S9S_MB_2U_LIB.S9S_MB_2U(SCH_1):PAGE67_I3@PURE_QUANTA.SOCKET4677_AZIF0045P001C01CS(CHIPS)':
 'VCCIN160': CDS_PINID='VCCIN160';
NODE_NAME     U1 BV79
 '@S9S_MB_2U_LIB.S9S_MB_2U(SCH_1):PAGE67_I3@PURE_QUANTA.SOCKET4677_AZIF0045P001C01CS(CHIPS)':
 'VCCIN161': CDS_PINID='VCCIN161';
NODE_NAME     U1 BV81
 '@S9S_MB_2U_LIB.S9S_MB_2U(SCH_1):PAGE67_I3@PURE_QUANTA.SOCKET4677_AZIF0045P001C01CS(CHIPS)':
 'VCCIN162': CDS_PINID='VCCIN162';
NODE_NAME     U1 BV83
 '@S9S_MB_2U_LIB.S9S_MB_2U(SCH_1):PAGE67_I3@PURE_QUANTA.SOCKET4677_AZIF0045P001C01CS(CHIPS)':
 'VCCIN163': CDS_PINID='VCCIN163';
NODE_NAME     U1 BV85
 '@S9S_MB_2U_LIB.S9S_MB_2U(SCH_1):PAGE67_I3@PURE_QUANTA.SOCKET4677_AZIF0045P001C01CS(CHIPS)':
 'VCCIN164': CDS_PINID='VCCIN164';
NODE_NAME     U1 BV87
 '@S9S_MB_2U_LIB.S9S_MB_2U(SCH_1):PAGE67_I3@PURE_QUANTA.SOCKET4677_AZIF0045P001C01CS(CHIPS)':
 'VCCIN165': CDS_PINID='VCCIN165';
NODE_NAME     U1 BV89
 '@S9S_MB_2U_LIB.S9S_MB_2U(SCH_1):PAGE67_I3@PURE_QUANTA.SOCKET4677_AZIF0045P001C01CS(CHIPS)':
 'VCCIN166': CDS_PINID='VCCIN166';
NODE_NAME     U1 BW33
 '@S9S_MB_2U_LIB.S9S_MB_2U(SCH_1):PAGE67_I3@PURE_QUANTA.SOCKET4677_AZIF0045P001C01CS(CHIPS)':
 'VCCIN167': CDS_PINID='VCCIN167';
NODE_NAME     U1 BW35
 '@S9S_MB_2U_LIB.S9S_MB_2U(SCH_1):PAGE67_I3@PURE_QUANTA.SOCKET4677_AZIF0045P001C01CS(CHIPS)':
 'VCCIN168': CDS_PINID='VCCIN168';
NODE_NAME     U1 BW37
 '@S9S_MB_2U_LIB.S9S_MB_2U(SCH_1):PAGE67_I3@PURE_QUANTA.SOCKET4677_AZIF0045P001C01CS(CHIPS)':
 'VCCIN169': CDS_PINID='VCCIN169';
NODE_NAME     U1 BW39
 '@S9S_MB_2U_LIB.S9S_MB_2U(SCH_1):PAGE67_I3@PURE_QUANTA.SOCKET4677_AZIF0045P001C01CS(CHIPS)':
 'VCCIN170': CDS_PINID='VCCIN170';
NODE_NAME     U1 BW41
 '@S9S_MB_2U_LIB.S9S_MB_2U(SCH_1):PAGE67_I3@PURE_QUANTA.SOCKET4677_AZIF0045P001C01CS(CHIPS)':
 'VCCIN171': CDS_PINID='VCCIN171';
NODE_NAME     U1 BW43
 '@S9S_MB_2U_LIB.S9S_MB_2U(SCH_1):PAGE67_I3@PURE_QUANTA.SOCKET4677_AZIF0045P001C01CS(CHIPS)':
 'VCCIN172': CDS_PINID='VCCIN172';
NODE_NAME     U1 BW45
 '@S9S_MB_2U_LIB.S9S_MB_2U(SCH_1):PAGE67_I3@PURE_QUANTA.SOCKET4677_AZIF0045P001C01CS(CHIPS)':
 'VCCIN173': CDS_PINID='VCCIN173';
NODE_NAME     U1 BW48
 '@S9S_MB_2U_LIB.S9S_MB_2U(SCH_1):PAGE67_I3@PURE_QUANTA.SOCKET4677_AZIF0045P001C01CS(CHIPS)':
 'VCCIN174': CDS_PINID='VCCIN174';
NODE_NAME     U1 BW50
 '@S9S_MB_2U_LIB.S9S_MB_2U(SCH_1):PAGE67_I3@PURE_QUANTA.SOCKET4677_AZIF0045P001C01CS(CHIPS)':
 'VCCIN175': CDS_PINID='VCCIN175';
NODE_NAME     U1 BW52
 '@S9S_MB_2U_LIB.S9S_MB_2U(SCH_1):PAGE67_I3@PURE_QUANTA.SOCKET4677_AZIF0045P001C01CS(CHIPS)':
 'VCCIN176': CDS_PINID='VCCIN176';
NODE_NAME     U1 BW54
 '@S9S_MB_2U_LIB.S9S_MB_2U(SCH_1):PAGE67_I3@PURE_QUANTA.SOCKET4677_AZIF0045P001C01CS(CHIPS)':
 'VCCIN177': CDS_PINID='VCCIN177';
NODE_NAME     U1 BW56
 '@S9S_MB_2U_LIB.S9S_MB_2U(SCH_1):PAGE67_I3@PURE_QUANTA.SOCKET4677_AZIF0045P001C01CS(CHIPS)':
 'VCCIN178': CDS_PINID='VCCIN178';
NODE_NAME     U1 BW58
 '@S9S_MB_2U_LIB.S9S_MB_2U(SCH_1):PAGE67_I3@PURE_QUANTA.SOCKET4677_AZIF0045P001C01CS(CHIPS)':
 'VCCIN179': CDS_PINID='VCCIN179';
NODE_NAME     U1 BW60
 '@S9S_MB_2U_LIB.S9S_MB_2U(SCH_1):PAGE67_I3@PURE_QUANTA.SOCKET4677_AZIF0045P001C01CS(CHIPS)':
 'VCCIN180': CDS_PINID='VCCIN180';
NODE_NAME     U1 BW62
 '@S9S_MB_2U_LIB.S9S_MB_2U(SCH_1):PAGE67_I3@PURE_QUANTA.SOCKET4677_AZIF0045P001C01CS(CHIPS)':
 'VCCIN181': CDS_PINID='VCCIN181';
NODE_NAME     U1 BW64
 '@S9S_MB_2U_LIB.S9S_MB_2U(SCH_1):PAGE67_I3@PURE_QUANTA.SOCKET4677_AZIF0045P001C01CS(CHIPS)':
 'VCCIN182': CDS_PINID='VCCIN182';
NODE_NAME     U1 BW66
 '@S9S_MB_2U_LIB.S9S_MB_2U(SCH_1):PAGE67_I3@PURE_QUANTA.SOCKET4677_AZIF0045P001C01CS(CHIPS)':
 'VCCIN183': CDS_PINID='VCCIN183';
NODE_NAME     U1 BW68
 '@S9S_MB_2U_LIB.S9S_MB_2U(SCH_1):PAGE67_I3@PURE_QUANTA.SOCKET4677_AZIF0045P001C01CS(CHIPS)':
 'VCCIN184': CDS_PINID='VCCIN184';
NODE_NAME     U1 BW70
 '@S9S_MB_2U_LIB.S9S_MB_2U(SCH_1):PAGE67_I3@PURE_QUANTA.SOCKET4677_AZIF0045P001C01CS(CHIPS)':
 'VCCIN185': CDS_PINID='VCCIN185';
NODE_NAME     U1 BW72
 '@S9S_MB_2U_LIB.S9S_MB_2U(SCH_1):PAGE67_I3@PURE_QUANTA.SOCKET4677_AZIF0045P001C01CS(CHIPS)':
 'VCCIN186': CDS_PINID='VCCIN186';
NODE_NAME     U1 BW74
 '@S9S_MB_2U_LIB.S9S_MB_2U(SCH_1):PAGE67_I3@PURE_QUANTA.SOCKET4677_AZIF0045P001C01CS(CHIPS)':
 'VCCIN187': CDS_PINID='VCCIN187';
NODE_NAME     U1 BW76
 '@S9S_MB_2U_LIB.S9S_MB_2U(SCH_1):PAGE67_I3@PURE_QUANTA.SOCKET4677_AZIF0045P001C01CS(CHIPS)':
 'VCCIN188': CDS_PINID='VCCIN188';
NODE_NAME     U1 BW78
 '@S9S_MB_2U_LIB.S9S_MB_2U(SCH_1):PAGE67_I3@PURE_QUANTA.SOCKET4677_AZIF0045P001C01CS(CHIPS)':
 'VCCIN189': CDS_PINID='VCCIN189';
NODE_NAME     U1 BD91
 '@S9S_MB_2U_LIB.S9S_MB_2U(SCH_1):PAGE68_I1@PURE_QUANTA.SOCKET4677_AZIF0045P001C01CS(CHIPS)':
 'VCCIN0': CDS_PINID='VCCIN0';
NODE_NAME     U1 BE86
 '@S9S_MB_2U_LIB.S9S_MB_2U(SCH_1):PAGE68_I1@PURE_QUANTA.SOCKET4677_AZIF0045P001C01CS(CHIPS)':
 'VCCIN1': CDS_PINID='VCCIN1';
NODE_NAME     U1 BE88
 '@S9S_MB_2U_LIB.S9S_MB_2U(SCH_1):PAGE68_I1@PURE_QUANTA.SOCKET4677_AZIF0045P001C01CS(CHIPS)':
 'VCCIN2': CDS_PINID='VCCIN2';
NODE_NAME     U1 BE90
 '@S9S_MB_2U_LIB.S9S_MB_2U(SCH_1):PAGE68_I1@PURE_QUANTA.SOCKET4677_AZIF0045P001C01CS(CHIPS)':
 'VCCIN3': CDS_PINID='VCCIN3';
NODE_NAME     U1 BF85
 '@S9S_MB_2U_LIB.S9S_MB_2U(SCH_1):PAGE68_I1@PURE_QUANTA.SOCKET4677_AZIF0045P001C01CS(CHIPS)':
 'VCCIN4': CDS_PINID='VCCIN4';
NODE_NAME     U1 BF87
 '@S9S_MB_2U_LIB.S9S_MB_2U(SCH_1):PAGE68_I1@PURE_QUANTA.SOCKET4677_AZIF0045P001C01CS(CHIPS)':
 'VCCIN5': CDS_PINID='VCCIN5';
NODE_NAME     U1 BF89
 '@S9S_MB_2U_LIB.S9S_MB_2U(SCH_1):PAGE68_I1@PURE_QUANTA.SOCKET4677_AZIF0045P001C01CS(CHIPS)':
 'VCCIN6': CDS_PINID='VCCIN6';
NODE_NAME     U1 BF91
 '@S9S_MB_2U_LIB.S9S_MB_2U(SCH_1):PAGE68_I1@PURE_QUANTA.SOCKET4677_AZIF0045P001C01CS(CHIPS)':
 'VCCIN7': CDS_PINID='VCCIN7';
NODE_NAME     U1 BG84
 '@S9S_MB_2U_LIB.S9S_MB_2U(SCH_1):PAGE68_I1@PURE_QUANTA.SOCKET4677_AZIF0045P001C01CS(CHIPS)':
 'VCCIN8': CDS_PINID='VCCIN8';
NODE_NAME     U1 BG86
 '@S9S_MB_2U_LIB.S9S_MB_2U(SCH_1):PAGE68_I1@PURE_QUANTA.SOCKET4677_AZIF0045P001C01CS(CHIPS)':
 'VCCIN9': CDS_PINID='VCCIN9';
NODE_NAME     U1 BG88
 '@S9S_MB_2U_LIB.S9S_MB_2U(SCH_1):PAGE68_I1@PURE_QUANTA.SOCKET4677_AZIF0045P001C01CS(CHIPS)':
 'VCCIN10': CDS_PINID='VCCIN10';
NODE_NAME     U1 BG90
 '@S9S_MB_2U_LIB.S9S_MB_2U(SCH_1):PAGE68_I1@PURE_QUANTA.SOCKET4677_AZIF0045P001C01CS(CHIPS)':
 'VCCIN11': CDS_PINID='VCCIN11';
NODE_NAME     U1 BH85
 '@S9S_MB_2U_LIB.S9S_MB_2U(SCH_1):PAGE68_I1@PURE_QUANTA.SOCKET4677_AZIF0045P001C01CS(CHIPS)':
 'VCCIN12': CDS_PINID='VCCIN12';
NODE_NAME     U1 BH87
 '@S9S_MB_2U_LIB.S9S_MB_2U(SCH_1):PAGE68_I1@PURE_QUANTA.SOCKET4677_AZIF0045P001C01CS(CHIPS)':
 'VCCIN13': CDS_PINID='VCCIN13';
NODE_NAME     U1 BH89
 '@S9S_MB_2U_LIB.S9S_MB_2U(SCH_1):PAGE68_I1@PURE_QUANTA.SOCKET4677_AZIF0045P001C01CS(CHIPS)':
 'VCCIN14': CDS_PINID='VCCIN14';
NODE_NAME     U1 BH91
 '@S9S_MB_2U_LIB.S9S_MB_2U(SCH_1):PAGE68_I1@PURE_QUANTA.SOCKET4677_AZIF0045P001C01CS(CHIPS)':
 'VCCIN15': CDS_PINID='VCCIN15';
NODE_NAME     U1 BK81
 '@S9S_MB_2U_LIB.S9S_MB_2U(SCH_1):PAGE68_I1@PURE_QUANTA.SOCKET4677_AZIF0045P001C01CS(CHIPS)':
 'VCCIN16': CDS_PINID='VCCIN16';
NODE_NAME     U1 BK83
 '@S9S_MB_2U_LIB.S9S_MB_2U(SCH_1):PAGE68_I1@PURE_QUANTA.SOCKET4677_AZIF0045P001C01CS(CHIPS)':
 'VCCIN17': CDS_PINID='VCCIN17';
NODE_NAME     U1 BK85
 '@S9S_MB_2U_LIB.S9S_MB_2U(SCH_1):PAGE68_I1@PURE_QUANTA.SOCKET4677_AZIF0045P001C01CS(CHIPS)':
 'VCCIN18': CDS_PINID='VCCIN18';
NODE_NAME     U1 BK87
 '@S9S_MB_2U_LIB.S9S_MB_2U(SCH_1):PAGE68_I1@PURE_QUANTA.SOCKET4677_AZIF0045P001C01CS(CHIPS)':
 'VCCIN19': CDS_PINID='VCCIN19';
NODE_NAME     U1 BK89
 '@S9S_MB_2U_LIB.S9S_MB_2U(SCH_1):PAGE68_I1@PURE_QUANTA.SOCKET4677_AZIF0045P001C01CS(CHIPS)':
 'VCCIN20': CDS_PINID='VCCIN20';
NODE_NAME     U1 BK91
 '@S9S_MB_2U_LIB.S9S_MB_2U(SCH_1):PAGE68_I1@PURE_QUANTA.SOCKET4677_AZIF0045P001C01CS(CHIPS)':
 'VCCIN21': CDS_PINID='VCCIN21';
NODE_NAME     U1 BL80
 '@S9S_MB_2U_LIB.S9S_MB_2U(SCH_1):PAGE68_I1@PURE_QUANTA.SOCKET4677_AZIF0045P001C01CS(CHIPS)':
 'VCCIN22': CDS_PINID='VCCIN22';
NODE_NAME     U1 BL82
 '@S9S_MB_2U_LIB.S9S_MB_2U(SCH_1):PAGE68_I1@PURE_QUANTA.SOCKET4677_AZIF0045P001C01CS(CHIPS)':
 'VCCIN23': CDS_PINID='VCCIN23';
NODE_NAME     U1 BL84
 '@S9S_MB_2U_LIB.S9S_MB_2U(SCH_1):PAGE68_I1@PURE_QUANTA.SOCKET4677_AZIF0045P001C01CS(CHIPS)':
 'VCCIN24': CDS_PINID='VCCIN24';
NODE_NAME     U1 BL86
 '@S9S_MB_2U_LIB.S9S_MB_2U(SCH_1):PAGE68_I1@PURE_QUANTA.SOCKET4677_AZIF0045P001C01CS(CHIPS)':
 'VCCIN25': CDS_PINID='VCCIN25';
NODE_NAME     U1 BL88
 '@S9S_MB_2U_LIB.S9S_MB_2U(SCH_1):PAGE68_I1@PURE_QUANTA.SOCKET4677_AZIF0045P001C01CS(CHIPS)':
 'VCCIN26': CDS_PINID='VCCIN26';
NODE_NAME     U1 BL90
 '@S9S_MB_2U_LIB.S9S_MB_2U(SCH_1):PAGE68_I1@PURE_QUANTA.SOCKET4677_AZIF0045P001C01CS(CHIPS)':
 'VCCIN27': CDS_PINID='VCCIN27';
NODE_NAME     U1 BM79
 '@S9S_MB_2U_LIB.S9S_MB_2U(SCH_1):PAGE68_I1@PURE_QUANTA.SOCKET4677_AZIF0045P001C01CS(CHIPS)':
 'VCCIN28': CDS_PINID='VCCIN28';
NODE_NAME     U1 BM81
 '@S9S_MB_2U_LIB.S9S_MB_2U(SCH_1):PAGE68_I1@PURE_QUANTA.SOCKET4677_AZIF0045P001C01CS(CHIPS)':
 'VCCIN29': CDS_PINID='VCCIN29';
NODE_NAME     U1 BM83
 '@S9S_MB_2U_LIB.S9S_MB_2U(SCH_1):PAGE68_I1@PURE_QUANTA.SOCKET4677_AZIF0045P001C01CS(CHIPS)':
 'VCCIN30': CDS_PINID='VCCIN30';
NODE_NAME     U1 BM85
 '@S9S_MB_2U_LIB.S9S_MB_2U(SCH_1):PAGE68_I1@PURE_QUANTA.SOCKET4677_AZIF0045P001C01CS(CHIPS)':
 'VCCIN31': CDS_PINID='VCCIN31';
NODE_NAME     U1 BM87
 '@S9S_MB_2U_LIB.S9S_MB_2U(SCH_1):PAGE68_I1@PURE_QUANTA.SOCKET4677_AZIF0045P001C01CS(CHIPS)':
 'VCCIN32': CDS_PINID='VCCIN32';
NODE_NAME     U1 BM89
 '@S9S_MB_2U_LIB.S9S_MB_2U(SCH_1):PAGE68_I1@PURE_QUANTA.SOCKET4677_AZIF0045P001C01CS(CHIPS)':
 'VCCIN33': CDS_PINID='VCCIN33';
NODE_NAME     U1 BM91
 '@S9S_MB_2U_LIB.S9S_MB_2U(SCH_1):PAGE68_I1@PURE_QUANTA.SOCKET4677_AZIF0045P001C01CS(CHIPS)':
 'VCCIN34': CDS_PINID='VCCIN34';
NODE_NAME     U1 BN33
 '@S9S_MB_2U_LIB.S9S_MB_2U(SCH_1):PAGE68_I1@PURE_QUANTA.SOCKET4677_AZIF0045P001C01CS(CHIPS)':
 'VCCIN35': CDS_PINID='VCCIN35';
NODE_NAME     U1 BN35
 '@S9S_MB_2U_LIB.S9S_MB_2U(SCH_1):PAGE68_I1@PURE_QUANTA.SOCKET4677_AZIF0045P001C01CS(CHIPS)':
 'VCCIN36': CDS_PINID='VCCIN36';
NODE_NAME     U1 BN37
 '@S9S_MB_2U_LIB.S9S_MB_2U(SCH_1):PAGE68_I1@PURE_QUANTA.SOCKET4677_AZIF0045P001C01CS(CHIPS)':
 'VCCIN37': CDS_PINID='VCCIN37';
NODE_NAME     U1 BN39
 '@S9S_MB_2U_LIB.S9S_MB_2U(SCH_1):PAGE68_I1@PURE_QUANTA.SOCKET4677_AZIF0045P001C01CS(CHIPS)':
 'VCCIN38': CDS_PINID='VCCIN38';
NODE_NAME     U1 BN41
 '@S9S_MB_2U_LIB.S9S_MB_2U(SCH_1):PAGE68_I1@PURE_QUANTA.SOCKET4677_AZIF0045P001C01CS(CHIPS)':
 'VCCIN39': CDS_PINID='VCCIN39';
NODE_NAME     C225 1
 '@S9S_MB_2U_LIB.S9S_MB_2U(SCH_1):PAGE77_I10@PURE_QUANTA.Q_CAP(CHIPS)':
 'A': CDS_PINID='A';
NODE_NAME     C230 1
 '@S9S_MB_2U_LIB.S9S_MB_2U(SCH_1):PAGE77_I11@PURE_QUANTA.Q_CAP(CHIPS)':
 'A': CDS_PINID='A';
NODE_NAME     C224 1
 '@S9S_MB_2U_LIB.S9S_MB_2U(SCH_1):PAGE77_I13@PURE_QUANTA.Q_CAP(CHIPS)':
 'A': CDS_PINID='A';
NODE_NAME     C240 1
 '@S9S_MB_2U_LIB.S9S_MB_2U(SCH_1):PAGE77_I18@PURE_QUANTA.Q_CAP(CHIPS)':
 'A': CDS_PINID='A';
NODE_NAME     C234 1
 '@S9S_MB_2U_LIB.S9S_MB_2U(SCH_1):PAGE77_I19@PURE_QUANTA.Q_CAP(CHIPS)':
 'A': CDS_PINID='A';
NODE_NAME     C239 1
 '@S9S_MB_2U_LIB.S9S_MB_2U(SCH_1):PAGE77_I20@PURE_QUANTA.Q_CAP(CHIPS)':
 'A': CDS_PINID='A';
NODE_NAME     C223 1
 '@S9S_MB_2U_LIB.S9S_MB_2U(SCH_1):PAGE77_I22@PURE_QUANTA.Q_CAP(CHIPS)':
 'A': CDS_PINID='A';
NODE_NAME     C228 1
 '@S9S_MB_2U_LIB.S9S_MB_2U(SCH_1):PAGE77_I23@PURE_QUANTA.Q_CAP(CHIPS)':
 'A': CDS_PINID='A';
NODE_NAME     C222 1
 '@S9S_MB_2U_LIB.S9S_MB_2U(SCH_1):PAGE77_I25@PURE_QUANTA.Q_CAP(CHIPS)':
 'A': CDS_PINID='A';
NODE_NAME     C221 1
 '@S9S_MB_2U_LIB.S9S_MB_2U(SCH_1):PAGE77_I28@PURE_QUANTA.Q_CAP(CHIPS)':
 'A': CDS_PINID='A';
NODE_NAME     C226 1
 '@S9S_MB_2U_LIB.S9S_MB_2U(SCH_1):PAGE77_I29@PURE_QUANTA.Q_CAP(CHIPS)':
 'A': CDS_PINID='A';
NODE_NAME     C233 1
 '@S9S_MB_2U_LIB.S9S_MB_2U(SCH_1):PAGE77_I30@PURE_QUANTA.Q_CAP(CHIPS)':
 'A': CDS_PINID='A';
NODE_NAME     C238 1
 '@S9S_MB_2U_LIB.S9S_MB_2U(SCH_1):PAGE77_I31@PURE_QUANTA.Q_CAP(CHIPS)':
 'A': CDS_PINID='A';
NODE_NAME     C232 1
 '@S9S_MB_2U_LIB.S9S_MB_2U(SCH_1):PAGE77_I32@PURE_QUANTA.Q_CAP(CHIPS)':
 'A': CDS_PINID='A';
NODE_NAME     C231 1
 '@S9S_MB_2U_LIB.S9S_MB_2U(SCH_1):PAGE77_I33@PURE_QUANTA.Q_CAP(CHIPS)':
 'A': CDS_PINID='A';
NODE_NAME     C237 1
 '@S9S_MB_2U_LIB.S9S_MB_2U(SCH_1):PAGE77_I34@PURE_QUANTA.Q_CAP(CHIPS)':
 'A': CDS_PINID='A';
NODE_NAME     C236 1
 '@S9S_MB_2U_LIB.S9S_MB_2U(SCH_1):PAGE77_I35@PURE_QUANTA.Q_CAP(CHIPS)':
 'A': CDS_PINID='A';
NODE_NAME     C245 1
 '@S9S_MB_2U_LIB.S9S_MB_2U(SCH_1):PAGE77_I41@PURE_QUANTA.Q_CAP(CHIPS)':
 'A': CDS_PINID='A';
NODE_NAME     C250 1
 '@S9S_MB_2U_LIB.S9S_MB_2U(SCH_1):PAGE77_I44@PURE_QUANTA.Q_CAP(CHIPS)':
 'A': CDS_PINID='A';
NODE_NAME     C244 1
 '@S9S_MB_2U_LIB.S9S_MB_2U(SCH_1):PAGE77_I45@PURE_QUANTA.Q_CAP(CHIPS)':
 'A': CDS_PINID='A';
NODE_NAME     C249 1
 '@S9S_MB_2U_LIB.S9S_MB_2U(SCH_1):PAGE77_I46@PURE_QUANTA.Q_CAP(CHIPS)':
 'A': CDS_PINID='A';
NODE_NAME     C255 1
 '@S9S_MB_2U_LIB.S9S_MB_2U(SCH_1):PAGE77_I48@PURE_QUANTA.Q_CAP(CHIPS)':
 'A': CDS_PINID='A';
NODE_NAME     C260 1
 '@S9S_MB_2U_LIB.S9S_MB_2U(SCH_1):PAGE77_I50@PURE_QUANTA.Q_CAP(CHIPS)':
 'A': CDS_PINID='A';
NODE_NAME     C254 1
 '@S9S_MB_2U_LIB.S9S_MB_2U(SCH_1):PAGE77_I51@PURE_QUANTA.Q_CAP(CHIPS)':
 'A': CDS_PINID='A';
NODE_NAME     C259 1
 '@S9S_MB_2U_LIB.S9S_MB_2U(SCH_1):PAGE77_I52@PURE_QUANTA.Q_CAP(CHIPS)':
 'A': CDS_PINID='A';
NODE_NAME     C265 1
 '@S9S_MB_2U_LIB.S9S_MB_2U(SCH_1):PAGE77_I59@PURE_QUANTA.Q_CAP(CHIPS)':
 'A': CDS_PINID='A';
NODE_NAME     C270 1
 '@S9S_MB_2U_LIB.S9S_MB_2U(SCH_1):PAGE77_I62@PURE_QUANTA.Q_CAP(CHIPS)':
 'A': CDS_PINID='A';
NODE_NAME     C264 1
 '@S9S_MB_2U_LIB.S9S_MB_2U(SCH_1):PAGE77_I63@PURE_QUANTA.Q_CAP(CHIPS)':
 'A': CDS_PINID='A';
NODE_NAME     C274 1
 '@S9S_MB_2U_LIB.S9S_MB_2U(SCH_1):PAGE77_I66@PURE_QUANTA.Q_CAP(CHIPS)':
 'A': CDS_PINID='A';
NODE_NAME     C278 1
 '@S9S_MB_2U_LIB.S9S_MB_2U(SCH_1):PAGE77_I71@PURE_QUANTA.Q_CAP(CHIPS)':
 'A': CDS_PINID='A';
NODE_NAME     C282 1
 '@S9S_MB_2U_LIB.S9S_MB_2U(SCH_1):PAGE77_I73@PURE_QUANTA.Q_CAP(CHIPS)':
 'A': CDS_PINID='A';
NODE_NAME     C248 1
 '@S9S_MB_2U_LIB.S9S_MB_2U(SCH_1):PAGE77_I75@PURE_QUANTA.Q_CAP(CHIPS)':
 'A': CDS_PINID='A';
NODE_NAME     C242 1
 '@S9S_MB_2U_LIB.S9S_MB_2U(SCH_1):PAGE77_I76@PURE_QUANTA.Q_CAP(CHIPS)':
 'A': CDS_PINID='A';
NODE_NAME     C247 1
 '@S9S_MB_2U_LIB.S9S_MB_2U(SCH_1):PAGE77_I78@PURE_QUANTA.Q_CAP(CHIPS)':
 'A': CDS_PINID='A';
NODE_NAME     C246 1
 '@S9S_MB_2U_LIB.S9S_MB_2U(SCH_1):PAGE77_I79@PURE_QUANTA.Q_CAP(CHIPS)':
 'A': CDS_PINID='A';
NODE_NAME     C258 1
 '@S9S_MB_2U_LIB.S9S_MB_2U(SCH_1):PAGE77_I81@PURE_QUANTA.Q_CAP(CHIPS)':
 'A': CDS_PINID='A';
NODE_NAME     C251 1
 '@S9S_MB_2U_LIB.S9S_MB_2U(SCH_1):PAGE77_I83@PURE_QUANTA.Q_CAP(CHIPS)':
 'A': CDS_PINID='A';
NODE_NAME     C257 1
 '@S9S_MB_2U_LIB.S9S_MB_2U(SCH_1):PAGE77_I84@PURE_QUANTA.Q_CAP(CHIPS)':
 'A': CDS_PINID='A';
NODE_NAME     C263 1
 '@S9S_MB_2U_LIB.S9S_MB_2U(SCH_1):PAGE77_I86@PURE_QUANTA.Q_CAP(CHIPS)':
 'A': CDS_PINID='A';
NODE_NAME     C268 1
 '@S9S_MB_2U_LIB.S9S_MB_2U(SCH_1):PAGE77_I88@PURE_QUANTA.Q_CAP(CHIPS)':
 'A': CDS_PINID='A';
NODE_NAME     C262 1
 '@S9S_MB_2U_LIB.S9S_MB_2U(SCH_1):PAGE77_I93@PURE_QUANTA.Q_CAP(CHIPS)':
 'A': CDS_PINID='A';
NODE_NAME     C261 1
 '@S9S_MB_2U_LIB.S9S_MB_2U(SCH_1):PAGE77_I95@PURE_QUANTA.Q_CAP(CHIPS)':
 'A': CDS_PINID='A';
NODE_NAME     C272 1
 '@S9S_MB_2U_LIB.S9S_MB_2U(SCH_1):PAGE77_I98@PURE_QUANTA.Q_CAP(CHIPS)':
 'A': CDS_PINID='A';
NODE_NAME     C271 1
 '@S9S_MB_2U_LIB.S9S_MB_2U(SCH_1):PAGE77_I100@PURE_QUANTA.Q_CAP(CHIPS)':
 'A': CDS_PINID='A';
NODE_NAME     C277 1
 '@S9S_MB_2U_LIB.S9S_MB_2U(SCH_1):PAGE77_I101@PURE_QUANTA.Q_CAP(CHIPS)':
 'A': CDS_PINID='A';
NODE_NAME     C281 1
 '@S9S_MB_2U_LIB.S9S_MB_2U(SCH_1):PAGE77_I102@PURE_QUANTA.Q_CAP(CHIPS)':
 'A': CDS_PINID='A';
NODE_NAME     C276 1
 '@S9S_MB_2U_LIB.S9S_MB_2U(SCH_1):PAGE77_I103@PURE_QUANTA.Q_CAP(CHIPS)':
 'A': CDS_PINID='A';
NODE_NAME     C275 1
 '@S9S_MB_2U_LIB.S9S_MB_2U(SCH_1):PAGE77_I104@PURE_QUANTA.Q_CAP(CHIPS)':
 'A': CDS_PINID='A';
NODE_NAME     C280 1
 '@S9S_MB_2U_LIB.S9S_MB_2U(SCH_1):PAGE77_I105@PURE_QUANTA.Q_CAP(CHIPS)':
 'A': CDS_PINID='A';
NODE_NAME     C279 1
 '@S9S_MB_2U_LIB.S9S_MB_2U(SCH_1):PAGE77_I106@PURE_QUANTA.Q_CAP(CHIPS)':
 'A': CDS_PINID='A';
NODE_NAME     C286 1
 '@S9S_MB_2U_LIB.S9S_MB_2U(SCH_1):PAGE77_I111@PURE_QUANTA.Q_CAP(CHIPS)':
 'A': CDS_PINID='A';
NODE_NAME     C290 1
 '@S9S_MB_2U_LIB.S9S_MB_2U(SCH_1):PAGE77_I112@PURE_QUANTA.Q_CAP(CHIPS)':
 'A': CDS_PINID='A';
NODE_NAME     C294 1
 '@S9S_MB_2U_LIB.S9S_MB_2U(SCH_1):PAGE77_I114@PURE_QUANTA.Q_CAP(CHIPS)':
 'A': CDS_PINID='A';
NODE_NAME     C298 1
 '@S9S_MB_2U_LIB.S9S_MB_2U(SCH_1):PAGE77_I115@PURE_QUANTA.Q_CAP(CHIPS)':
 'A': CDS_PINID='A';
NODE_NAME     C302 1
 '@S9S_MB_2U_LIB.S9S_MB_2U(SCH_1):PAGE77_I117@PURE_QUANTA.Q_CAP(CHIPS)':
 'A': CDS_PINID='A';
NODE_NAME     C306 1
 '@S9S_MB_2U_LIB.S9S_MB_2U(SCH_1):PAGE77_I118@PURE_QUANTA.Q_CAP(CHIPS)':
 'A': CDS_PINID='A';
NODE_NAME     C285 1
 '@S9S_MB_2U_LIB.S9S_MB_2U(SCH_1):PAGE77_I119@PURE_QUANTA.Q_CAP(CHIPS)':
 'A': CDS_PINID='A';
NODE_NAME     C289 1
 '@S9S_MB_2U_LIB.S9S_MB_2U(SCH_1):PAGE77_I120@PURE_QUANTA.Q_CAP(CHIPS)':
 'A': CDS_PINID='A';
NODE_NAME     C284 1
 '@S9S_MB_2U_LIB.S9S_MB_2U(SCH_1):PAGE77_I121@PURE_QUANTA.Q_CAP(CHIPS)':
 'A': CDS_PINID='A';
NODE_NAME     C283 1
 '@S9S_MB_2U_LIB.S9S_MB_2U(SCH_1):PAGE77_I122@PURE_QUANTA.Q_CAP(CHIPS)':
 'A': CDS_PINID='A';
NODE_NAME     C288 1
 '@S9S_MB_2U_LIB.S9S_MB_2U(SCH_1):PAGE77_I123@PURE_QUANTA.Q_CAP(CHIPS)':
 'A': CDS_PINID='A';
NODE_NAME     C293 1
 '@S9S_MB_2U_LIB.S9S_MB_2U(SCH_1):PAGE77_I125@PURE_QUANTA.Q_CAP(CHIPS)':
 'A': CDS_PINID='A';
NODE_NAME     C297 1
 '@S9S_MB_2U_LIB.S9S_MB_2U(SCH_1):PAGE77_I126@PURE_QUANTA.Q_CAP(CHIPS)':
 'A': CDS_PINID='A';
NODE_NAME     C296 1
 '@S9S_MB_2U_LIB.S9S_MB_2U(SCH_1):PAGE77_I129@PURE_QUANTA.Q_CAP(CHIPS)':
 'A': CDS_PINID='A';
NODE_NAME     C295 1
 '@S9S_MB_2U_LIB.S9S_MB_2U(SCH_1):PAGE77_I130@PURE_QUANTA.Q_CAP(CHIPS)':
 'A': CDS_PINID='A';
NODE_NAME     C299 1
 '@S9S_MB_2U_LIB.S9S_MB_2U(SCH_1):PAGE77_I131@PURE_QUANTA.Q_CAP(CHIPS)':
 'A': CDS_PINID='A';
NODE_NAME     C300 1
 '@S9S_MB_2U_LIB.S9S_MB_2U(SCH_1):PAGE77_I132@PURE_QUANTA.Q_CAP(CHIPS)':
 'A': CDS_PINID='A';
NODE_NAME     C301 1
 '@S9S_MB_2U_LIB.S9S_MB_2U(SCH_1):PAGE77_I133@PURE_QUANTA.Q_CAP(CHIPS)':
 'A': CDS_PINID='A';
NODE_NAME     C305 1
 '@S9S_MB_2U_LIB.S9S_MB_2U(SCH_1):PAGE77_I134@PURE_QUANTA.Q_CAP(CHIPS)':
 'A': CDS_PINID='A';
NODE_NAME     C309 1
 '@S9S_MB_2U_LIB.S9S_MB_2U(SCH_1):PAGE77_I136@PURE_QUANTA.Q_CAP(CHIPS)':
 'A': CDS_PINID='A';
NODE_NAME     C304 1
 '@S9S_MB_2U_LIB.S9S_MB_2U(SCH_1):PAGE77_I138@PURE_QUANTA.Q_CAP(CHIPS)':
 'A': CDS_PINID='A';
NODE_NAME     C308 1
 '@S9S_MB_2U_LIB.S9S_MB_2U(SCH_1):PAGE77_I140@PURE_QUANTA.Q_CAP(CHIPS)':
 'A': CDS_PINID='A';
NODE_NAME     C318 1
 '@S9S_MB_2U_LIB.S9S_MB_2U(SCH_1):PAGE78_I27@PURE_QUANTA.Q_CAP(CHIPS)':
 'A': CDS_PINID='A';
NODE_NAME     C327 1
 '@S9S_MB_2U_LIB.S9S_MB_2U(SCH_1):PAGE78_I32@PURE_QUANTA.Q_CAP(CHIPS)':
 'A': CDS_PINID='A';
NODE_NAME     C336 1
 '@S9S_MB_2U_LIB.S9S_MB_2U(SCH_1):PAGE78_I35@PURE_QUANTA.Q_CAP(CHIPS)':
 'A': CDS_PINID='A';
NODE_NAME     C314 1
 '@S9S_MB_2U_LIB.S9S_MB_2U(SCH_1):PAGE78_I37@PURE_QUANTA.Q_CAP(CHIPS)':
 'A': CDS_PINID='A';
NODE_NAME     C320 1
 '@S9S_MB_2U_LIB.S9S_MB_2U(SCH_1):PAGE78_I39@PURE_QUANTA.Q_CAP(CHIPS)':
 'A': CDS_PINID='A';
NODE_NAME     C323 1
 '@S9S_MB_2U_LIB.S9S_MB_2U(SCH_1):PAGE78_I40@PURE_QUANTA.Q_CAP(CHIPS)':
 'A': CDS_PINID='A';
NODE_NAME     C326 1
 '@S9S_MB_2U_LIB.S9S_MB_2U(SCH_1):PAGE78_I41@PURE_QUANTA.Q_CAP(CHIPS)':
 'A': CDS_PINID='A';
NODE_NAME     C313 1
 '@S9S_MB_2U_LIB.S9S_MB_2U(SCH_1):PAGE78_I58@PURE_QUANTA.Q_CAP(CHIPS)':
 'A': CDS_PINID='A';
NODE_NAME     C316 1
 '@S9S_MB_2U_LIB.S9S_MB_2U(SCH_1):PAGE78_I60@PURE_QUANTA.Q_CAP(CHIPS)':
 'A': CDS_PINID='A';
NODE_NAME     C353 1
 '@S9S_MB_2U_LIB.S9S_MB_2U(SCH_1):PAGE78_I65@PURE_QUANTA.Q_CAP(CHIPS)':
 'A': CDS_PINID='A';
NODE_NAME     C337 1
 '@S9S_MB_2U_LIB.S9S_MB_2U(SCH_1):PAGE78_I66@PURE_QUANTA.Q_CAP(CHIPS)':
 'A': CDS_PINID='A';
NODE_NAME     C483 1
 '@S9S_MB_2U_LIB.S9S_MB_2U(SCH_1):PAGE78_I68@PURE_QUANTA.Q_CAP(CHIPS)':
 'A': CDS_PINID='A';
NODE_NAME     PC1990 1
 '@S9S_MB_2U_LIB.S9S_MB_2U(SCH_1):PAGE271_I61@PURE_QUANTA.Q_CAPP(CHIPS)':
 'A': CDS_PINID='A';
NODE_NAME     PC587 1
 '@S9S_MB_2U_LIB.S9S_MB_2U(SCH_1):PAGE271_I65@PURE_QUANTA.Q_CAPP(CHIPS)':
 'A': CDS_PINID='A';
NODE_NAME     PC586 1
 '@S9S_MB_2U_LIB.S9S_MB_2U(SCH_1):PAGE271_I69@PURE_QUANTA.Q_CAPP(CHIPS)':
 'A': CDS_PINID='A';
NODE_NAME     PL31 4
 '@S9S_MB_2U_LIB.S9S_MB_2U(SCH_1):PAGE271_I74@PURE_QUANTA.Q_INDUCTOR4P_14(CHIPS)':
 '4': CDS_PINID='\4\';
NODE_NAME     PC572_P1_1 1
 '@S9S_MB_2U_LIB.S9S_MB_2U(SCH_1):PAGE271_I84@PURE_QUANTA.Q_CAP(CHIPS)':
 'A': CDS_PINID='A';
NODE_NAME     PL26 4
 '@S9S_MB_2U_LIB.S9S_MB_2U(SCH_1):PAGE273_I28@PURE_QUANTA.Q_INDUCTOR4P_14(CHIPS)':
 '4': CDS_PINID='\4\';
NODE_NAME     PL27 4
 '@S9S_MB_2U_LIB.S9S_MB_2U(SCH_1):PAGE273_I48@PURE_QUANTA.Q_INDUCTOR4P_14(CHIPS)':
 '4': CDS_PINID='\4\';
NODE_NAME     PR296 2
 '@S9S_MB_2U_LIB.S9S_MB_2U(SCH_1):PAGE273_I49@PURE_QUANTA.Q_RES(CHIPS)':
 'B': CDS_PINID='B';
NODE_NAME     PC519_P1_6 1
 '@S9S_MB_2U_LIB.S9S_MB_2U(SCH_1):PAGE273_I54@PURE_QUANTA.Q_CAP(CHIPS)':
 'A': CDS_PINID='A';
NODE_NAME     PL24 4
 '@S9S_MB_2U_LIB.S9S_MB_2U(SCH_1):PAGE274_I43@PURE_QUANTA.Q_INDUCTOR4P_14(CHIPS)':
 '4': CDS_PINID='\4\';
NODE_NAME     PR289 2
 '@S9S_MB_2U_LIB.S9S_MB_2U(SCH_1):PAGE274_I44@PURE_QUANTA.Q_RES(CHIPS)':
 'B': CDS_PINID='B';
NODE_NAME     PC495_P1_8 1
 '@S9S_MB_2U_LIB.S9S_MB_2U(SCH_1):PAGE274_I52@PURE_QUANTA.Q_CAP(CHIPS)':
 'A': CDS_PINID='A';
NODE_NAME     PC497_P1_8 1
 '@S9S_MB_2U_LIB.S9S_MB_2U(SCH_1):PAGE274_I53@PURE_QUANTA.Q_CAP(CHIPS)':
 'A': CDS_PINID='A';
NODE_NAME     PC499_P1_8 1
 '@S9S_MB_2U_LIB.S9S_MB_2U(SCH_1):PAGE274_I54@PURE_QUANTA.Q_CAP(CHIPS)':
 'A': CDS_PINID='A';
NODE_NAME     C229 1
 '@S9S_MB_2U_LIB.S9S_MB_2U(SCH_1):PAGE77_I14@PURE_QUANTA.Q_CAP(CHIPS)':
 'A': CDS_PINID='A';
NODE_NAME     C235 1
 '@S9S_MB_2U_LIB.S9S_MB_2U(SCH_1):PAGE77_I16@PURE_QUANTA.Q_CAP(CHIPS)':
 'A': CDS_PINID='A';
NODE_NAME     C227 1
 '@S9S_MB_2U_LIB.S9S_MB_2U(SCH_1):PAGE77_I26@PURE_QUANTA.Q_CAP(CHIPS)':
 'A': CDS_PINID='A';
NODE_NAME     C269 1
 '@S9S_MB_2U_LIB.S9S_MB_2U(SCH_1):PAGE77_I64@PURE_QUANTA.Q_CAP(CHIPS)':
 'A': CDS_PINID='A';
NODE_NAME     C243 1
 '@S9S_MB_2U_LIB.S9S_MB_2U(SCH_1):PAGE77_I74@PURE_QUANTA.Q_CAP(CHIPS)':
 'A': CDS_PINID='A';
NODE_NAME     C241 1
 '@S9S_MB_2U_LIB.S9S_MB_2U(SCH_1):PAGE77_I77@PURE_QUANTA.Q_CAP(CHIPS)':
 'A': CDS_PINID='A';
NODE_NAME     C253 1
 '@S9S_MB_2U_LIB.S9S_MB_2U(SCH_1):PAGE77_I80@PURE_QUANTA.Q_CAP(CHIPS)':
 'A': CDS_PINID='A';
NODE_NAME     C252 1
 '@S9S_MB_2U_LIB.S9S_MB_2U(SCH_1):PAGE77_I82@PURE_QUANTA.Q_CAP(CHIPS)':
 'A': CDS_PINID='A';
NODE_NAME     C256 1
 '@S9S_MB_2U_LIB.S9S_MB_2U(SCH_1):PAGE77_I85@PURE_QUANTA.Q_CAP(CHIPS)':
 'A': CDS_PINID='A';
NODE_NAME     C273 1
 '@S9S_MB_2U_LIB.S9S_MB_2U(SCH_1):PAGE77_I91@PURE_QUANTA.Q_CAP(CHIPS)':
 'A': CDS_PINID='A';
NODE_NAME     C267 1
 '@S9S_MB_2U_LIB.S9S_MB_2U(SCH_1):PAGE77_I94@PURE_QUANTA.Q_CAP(CHIPS)':
 'A': CDS_PINID='A';
NODE_NAME     C266 1
 '@S9S_MB_2U_LIB.S9S_MB_2U(SCH_1):PAGE77_I97@PURE_QUANTA.Q_CAP(CHIPS)':
 'A': CDS_PINID='A';
NODE_NAME     C287 1
 '@S9S_MB_2U_LIB.S9S_MB_2U(SCH_1):PAGE77_I124@PURE_QUANTA.Q_CAP(CHIPS)':
 'A': CDS_PINID='A';
NODE_NAME     C292 1
 '@S9S_MB_2U_LIB.S9S_MB_2U(SCH_1):PAGE77_I127@PURE_QUANTA.Q_CAP(CHIPS)':
 'A': CDS_PINID='A';
NODE_NAME     C291 1
 '@S9S_MB_2U_LIB.S9S_MB_2U(SCH_1):PAGE77_I128@PURE_QUANTA.Q_CAP(CHIPS)':
 'A': CDS_PINID='A';
NODE_NAME     C303 1
 '@S9S_MB_2U_LIB.S9S_MB_2U(SCH_1):PAGE77_I139@PURE_QUANTA.Q_CAP(CHIPS)':
 'A': CDS_PINID='A';
NODE_NAME     C307 1
 '@S9S_MB_2U_LIB.S9S_MB_2U(SCH_1):PAGE77_I142@PURE_QUANTA.Q_CAP(CHIPS)':
 'A': CDS_PINID='A';
NODE_NAME     C312 1
 '@S9S_MB_2U_LIB.S9S_MB_2U(SCH_1):PAGE78_I14@PURE_QUANTA.Q_CAP(CHIPS)':
 'A': CDS_PINID='A';
NODE_NAME     C311 1
 '@S9S_MB_2U_LIB.S9S_MB_2U(SCH_1):PAGE78_I16@PURE_QUANTA.Q_CAP(CHIPS)':
 'A': CDS_PINID='A';
NODE_NAME     C315 1
 '@S9S_MB_2U_LIB.S9S_MB_2U(SCH_1):PAGE78_I26@PURE_QUANTA.Q_CAP(CHIPS)':
 'A': CDS_PINID='A';
NODE_NAME     C321 1
 '@S9S_MB_2U_LIB.S9S_MB_2U(SCH_1):PAGE78_I30@PURE_QUANTA.Q_CAP(CHIPS)':
 'A': CDS_PINID='A';
NODE_NAME     C324 1
 '@S9S_MB_2U_LIB.S9S_MB_2U(SCH_1):PAGE78_I31@PURE_QUANTA.Q_CAP(CHIPS)':
 'A': CDS_PINID='A';
NODE_NAME     C330 1
 '@S9S_MB_2U_LIB.S9S_MB_2U(SCH_1):PAGE78_I33@PURE_QUANTA.Q_CAP(CHIPS)':
 'A': CDS_PINID='A';
NODE_NAME     C333 1
 '@S9S_MB_2U_LIB.S9S_MB_2U(SCH_1):PAGE78_I34@PURE_QUANTA.Q_CAP(CHIPS)':
 'A': CDS_PINID='A';
NODE_NAME     C339 1
 '@S9S_MB_2U_LIB.S9S_MB_2U(SCH_1):PAGE78_I36@PURE_QUANTA.Q_CAP(CHIPS)':
 'A': CDS_PINID='A';
NODE_NAME     C317 1
 '@S9S_MB_2U_LIB.S9S_MB_2U(SCH_1):PAGE78_I38@PURE_QUANTA.Q_CAP(CHIPS)':
 'A': CDS_PINID='A';
NODE_NAME     C329 1
 '@S9S_MB_2U_LIB.S9S_MB_2U(SCH_1):PAGE78_I42@PURE_QUANTA.Q_CAP(CHIPS)':
 'A': CDS_PINID='A';
NODE_NAME     C332 1
 '@S9S_MB_2U_LIB.S9S_MB_2U(SCH_1):PAGE78_I43@PURE_QUANTA.Q_CAP(CHIPS)':
 'A': CDS_PINID='A';
NODE_NAME     C335 1
 '@S9S_MB_2U_LIB.S9S_MB_2U(SCH_1):PAGE78_I44@PURE_QUANTA.Q_CAP(CHIPS)':
 'A': CDS_PINID='A';
NODE_NAME     C338 1
 '@S9S_MB_2U_LIB.S9S_MB_2U(SCH_1):PAGE78_I45@PURE_QUANTA.Q_CAP(CHIPS)':
 'A': CDS_PINID='A';
NODE_NAME     C349 1
 '@S9S_MB_2U_LIB.S9S_MB_2U(SCH_1):PAGE78_I63@PURE_QUANTA.Q_CAP(CHIPS)':
 'A': CDS_PINID='A';
NODE_NAME     C351 1
 '@S9S_MB_2U_LIB.S9S_MB_2U(SCH_1):PAGE78_I64@PURE_QUANTA.Q_CAP(CHIPS)':
 'A': CDS_PINID='A';
NODE_NAME     C342 1
 '@S9S_MB_2U_LIB.S9S_MB_2U(SCH_1):PAGE79_I23@PURE_QUANTA.Q_CAP(CHIPS)':
 'A': CDS_PINID='A';
NODE_NAME     C344 1
 '@S9S_MB_2U_LIB.S9S_MB_2U(SCH_1):PAGE79_I24@PURE_QUANTA.Q_CAP(CHIPS)':
 'A': CDS_PINID='A';
NODE_NAME     C346 1
 '@S9S_MB_2U_LIB.S9S_MB_2U(SCH_1):PAGE79_I25@PURE_QUANTA.Q_CAP(CHIPS)':
 'A': CDS_PINID='A';
NODE_NAME     C348 1
 '@S9S_MB_2U_LIB.S9S_MB_2U(SCH_1):PAGE79_I32@PURE_QUANTA.Q_CAP(CHIPS)':
 'A': CDS_PINID='A';
NODE_NAME     C350 1
 '@S9S_MB_2U_LIB.S9S_MB_2U(SCH_1):PAGE79_I33@PURE_QUANTA.Q_CAP(CHIPS)':
 'A': CDS_PINID='A';
NODE_NAME     C352 1
 '@S9S_MB_2U_LIB.S9S_MB_2U(SCH_1):PAGE79_I34@PURE_QUANTA.Q_CAP(CHIPS)':
 'A': CDS_PINID='A';
NODE_NAME     C354 1
 '@S9S_MB_2U_LIB.S9S_MB_2U(SCH_1):PAGE79_I35@PURE_QUANTA.Q_CAP(CHIPS)':
 'A': CDS_PINID='A';
NODE_NAME     C322 1
 '@S9S_MB_2U_LIB.S9S_MB_2U(SCH_1):PAGE79_I46@PURE_QUANTA.Q_CAP(CHIPS)':
 'A': CDS_PINID='A';
NODE_NAME     C325 1
 '@S9S_MB_2U_LIB.S9S_MB_2U(SCH_1):PAGE79_I47@PURE_QUANTA.Q_CAP(CHIPS)':
 'A': CDS_PINID='A';
NODE_NAME     C328 1
 '@S9S_MB_2U_LIB.S9S_MB_2U(SCH_1):PAGE79_I50@PURE_QUANTA.Q_CAP(CHIPS)':
 'A': CDS_PINID='A';
NODE_NAME     C341 1
 '@S9S_MB_2U_LIB.S9S_MB_2U(SCH_1):PAGE79_I51@PURE_QUANTA.Q_CAP(CHIPS)':
 'A': CDS_PINID='A';
NODE_NAME     C343 1
 '@S9S_MB_2U_LIB.S9S_MB_2U(SCH_1):PAGE79_I52@PURE_QUANTA.Q_CAP(CHIPS)':
 'A': CDS_PINID='A';
NODE_NAME     C345 1
 '@S9S_MB_2U_LIB.S9S_MB_2U(SCH_1):PAGE79_I53@PURE_QUANTA.Q_CAP(CHIPS)':
 'A': CDS_PINID='A';
NODE_NAME     C347 1
 '@S9S_MB_2U_LIB.S9S_MB_2U(SCH_1):PAGE79_I55@PURE_QUANTA.Q_CAP(CHIPS)':
 'A': CDS_PINID='A';
NODE_NAME     PC575_P1_2 1
 '@S9S_MB_2U_LIB.S9S_MB_2U(SCH_1):PAGE271_I57@PURE_QUANTA.Q_CAP(CHIPS)':
 'A': CDS_PINID='A';
NODE_NAME     PC577_P1_2 1
 '@S9S_MB_2U_LIB.S9S_MB_2U(SCH_1):PAGE271_I58@PURE_QUANTA.Q_CAP(CHIPS)':
 'A': CDS_PINID='A';
NODE_NAME     PR4240 1
 '@S9S_MB_2U_LIB.S9S_MB_2U(SCH_1):PAGE271_I59@PURE_QUANTA.Q_RES(CHIPS)':
 'A': CDS_PINID='A';
NODE_NAME     PC580 1
 '@S9S_MB_2U_LIB.S9S_MB_2U(SCH_1):PAGE271_I63@PURE_QUANTA.Q_CAPP(CHIPS)':
 'A': CDS_PINID='A';
NODE_NAME     PC589 1
 '@S9S_MB_2U_LIB.S9S_MB_2U(SCH_1):PAGE271_I72@PURE_QUANTA.Q_CAPP(CHIPS)':
 'A': CDS_PINID='A';
NODE_NAME     PC574_P1_1 1
 '@S9S_MB_2U_LIB.S9S_MB_2U(SCH_1):PAGE271_I85@PURE_QUANTA.Q_CAP(CHIPS)':
 'A': CDS_PINID='A';
NODE_NAME     PL28 4
 '@S9S_MB_2U_LIB.S9S_MB_2U(SCH_1):PAGE272_I37@PURE_QUANTA.Q_INDUCTOR4P_14(CHIPS)':
 '4': CDS_PINID='\4\';
NODE_NAME     PR301 2
 '@S9S_MB_2U_LIB.S9S_MB_2U(SCH_1):PAGE272_I38@PURE_QUANTA.Q_RES(CHIPS)':
 'B': CDS_PINID='B';
NODE_NAME     PR302 2
 '@S9S_MB_2U_LIB.S9S_MB_2U(SCH_1):PAGE272_I45@PURE_QUANTA.Q_RES(CHIPS)':
 'B': CDS_PINID='B';
NODE_NAME     PL29 4
 '@S9S_MB_2U_LIB.S9S_MB_2U(SCH_1):PAGE272_I51@PURE_QUANTA.Q_INDUCTOR4P_14(CHIPS)':
 '4': CDS_PINID='\4\';
NODE_NAME     PC541_P1_4 1
 '@S9S_MB_2U_LIB.S9S_MB_2U(SCH_1):PAGE272_I58@PURE_QUANTA.Q_CAP(CHIPS)':
 'A': CDS_PINID='A';
NODE_NAME     PC543_P1_4 1
 '@S9S_MB_2U_LIB.S9S_MB_2U(SCH_1):PAGE272_I59@PURE_QUANTA.Q_CAP(CHIPS)':
 'A': CDS_PINID='A';
NODE_NAME     PC542_P1_3 1
 '@S9S_MB_2U_LIB.S9S_MB_2U(SCH_1):PAGE272_I63@PURE_QUANTA.Q_CAP(CHIPS)':
 'A': CDS_PINID='A';
NODE_NAME     PC544_P1_3 1
 '@S9S_MB_2U_LIB.S9S_MB_2U(SCH_1):PAGE272_I64@PURE_QUANTA.Q_CAP(CHIPS)':
 'A': CDS_PINID='A';
NODE_NAME     PR295 2
 '@S9S_MB_2U_LIB.S9S_MB_2U(SCH_1):PAGE273_I27@PURE_QUANTA.Q_RES(CHIPS)':
 'B': CDS_PINID='B';
NODE_NAME     PC521_P1_6 1
 '@S9S_MB_2U_LIB.S9S_MB_2U(SCH_1):PAGE273_I57@PURE_QUANTA.Q_CAP(CHIPS)':
 'A': CDS_PINID='A';
NODE_NAME     PC520_P1_5 1
 '@S9S_MB_2U_LIB.S9S_MB_2U(SCH_1):PAGE273_I64@PURE_QUANTA.Q_CAP(CHIPS)':
 'A': CDS_PINID='A';
NODE_NAME     PC522_P1_5 1
 '@S9S_MB_2U_LIB.S9S_MB_2U(SCH_1):PAGE273_I65@PURE_QUANTA.Q_CAP(CHIPS)':
 'A': CDS_PINID='A';
NODE_NAME     PR290 2
 '@S9S_MB_2U_LIB.S9S_MB_2U(SCH_1):PAGE274_I50@PURE_QUANTA.Q_RES(CHIPS)':
 'B': CDS_PINID='B';
NODE_NAME     PL25 4
 '@S9S_MB_2U_LIB.S9S_MB_2U(SCH_1):PAGE274_I58@PURE_QUANTA.Q_INDUCTOR4P_14(CHIPS)':
 '4': CDS_PINID='\4\';
NODE_NAME     PC496_P1_7 1
 '@S9S_MB_2U_LIB.S9S_MB_2U(SCH_1):PAGE274_I64@PURE_QUANTA.Q_CAP(CHIPS)':
 'A': CDS_PINID='A';
NODE_NAME     PC498_P1_7 1
 '@S9S_MB_2U_LIB.S9S_MB_2U(SCH_1):PAGE274_I65@PURE_QUANTA.Q_CAP(CHIPS)':
 'A': CDS_PINID='A';
NODE_NAME     PC500_P1_7 1
 '@S9S_MB_2U_LIB.S9S_MB_2U(SCH_1):PAGE274_I66@PURE_QUANTA.Q_CAP(CHIPS)':
 'A': CDS_PINID='A';
NODE_NAME     PC83 1
 '@S9S_MB_2U_LIB.S9S_MB_2U(SCH_1):PAGE271_I56@PURE_QUANTA.Q_CAPP(CHIPS)':
 'A': CDS_PINID='A';
NODE_NAME     PC189 1
 '@S9S_MB_2U_LIB.S9S_MB_2U(SCH_1):PAGE271_I62@PURE_QUANTA.Q_CAPP(CHIPS)':
 'A': CDS_PINID='A';
NODE_NAME     PR330 2
 '@S9S_MB_2U_LIB.S9S_MB_2U(SCH_1):PAGE271_I73@PURE_QUANTA.Q_RES(CHIPS)':
 'B': CDS_PINID='B';
NODE_NAME     PC576_P1_1 1
 '@S9S_MB_2U_LIB.S9S_MB_2U(SCH_1):PAGE271_I88@PURE_QUANTA.Q_CAP(CHIPS)':
 'A': CDS_PINID='A';
NODE_NAME     PC578_P1_1 1
 '@S9S_MB_2U_LIB.S9S_MB_2U(SCH_1):PAGE271_I91@PURE_QUANTA.Q_CAP(CHIPS)':
 'A': CDS_PINID='A';
NODE_NAME     PR578 2
 '@S9S_MB_2U_LIB.S9S_MB_2U(SCH_1):PAGE270_I49@PURE_QUANTA.Q_RES(CHIPS)':
 'B': CDS_PINID='B';
NODE_NAME     PL30 4
 '@S9S_MB_2U_LIB.S9S_MB_2U(SCH_1):PAGE271_I18@PURE_QUANTA.Q_INDUCTOR4P_14(CHIPS)':
 '4': CDS_PINID='\4\';
NODE_NAME     PR329 2
 '@S9S_MB_2U_LIB.S9S_MB_2U(SCH_1):PAGE271_I51@PURE_QUANTA.Q_RES(CHIPS)':
 'B': CDS_PINID='B';
NODE_NAME     PC583 1
 '@S9S_MB_2U_LIB.S9S_MB_2U(SCH_1):PAGE271_I64@PURE_QUANTA.Q_CAPP(CHIPS)':
 'A': CDS_PINID='A';
NODE_NAME     PC590 1
 '@S9S_MB_2U_LIB.S9S_MB_2U(SCH_1):PAGE271_I68@PURE_QUANTA.Q_CAPP(CHIPS)':
 'A': CDS_PINID='A';
NET_NAME
'PVCCIN_CPU1_ADDR'
 '@S9S_MB_2U_LIB.S9S_MB_2U(SCH_1):PVCCIN_CPU1_ADDR':
 C_SIGNAL='@s9s_mb_2u_lib.s9s_mb_2u(sch_1):pvccin_cpu1_addr';
NODE_NAME     PR306 2
 '@S9S_MB_2U_LIB.S9S_MB_2U(SCH_1):PAGE270_I4@PURE_QUANTA.Q_RES(CHIPS)':
 'B': CDS_PINID='B';
NODE_NAME     PR318 1
 '@S9S_MB_2U_LIB.S9S_MB_2U(SCH_1):PAGE270_I6@PURE_QUANTA.Q_RES(CHIPS)':
 'A': CDS_PINID='A';
NODE_NAME     PU29 42
 '@S9S_MB_2U_LIB.S9S_MB_2U(SCH_1):PAGE270_I33@PURE_QUANTA.RAA229126GNPHA0(CHIPS)':
 'ADDR_CFG': CDS_PINID='ADDR_CFG';
NET_NAME
'PVCCIN_CPU1_ATSEN'
 '@S9S_MB_2U_LIB.S9S_MB_2U(SCH_1):PVCCIN_CPU1_ATSEN':
 C_SIGNAL='@s9s_mb_2u_lib.s9s_mb_2u(sch_1):pvccin_cpu1_atsen';
NODE_NAME     PU26_P1_5 36
 '@S9S_MB_2U_LIB.S9S_MB_2U(SCH_1):PAGE273_I23@PURE_QUANTA.ISL99390FRZTR5935(CHIPS)':
 'TOUT_FLT': CDS_PINID='TOUT_FLT';
NODE_NAME     PR637 1
 '@S9S_MB_2U_LIB.S9S_MB_2U(SCH_1):PAGE270_I74@PURE_QUANTA.Q_RES(CHIPS)':
 'A': CDS_PINID='A';
NODE_NAME     PU27_P1_4 36
 '@S9S_MB_2U_LIB.S9S_MB_2U(SCH_1):PAGE272_I10@PURE_QUANTA.ISL99390FRZTR5935(CHIPS)':
 'TOUT_FLT': CDS_PINID='TOUT_FLT';
NODE_NAME     PU28_P1_3 36
 '@S9S_MB_2U_LIB.S9S_MB_2U(SCH_1):PAGE272_I66@PURE_QUANTA.ISL99390FRZTR5935(CHIPS)':
 'TOUT_FLT': CDS_PINID='TOUT_FLT';
NODE_NAME     PU25_P1_6 36
 '@S9S_MB_2U_LIB.S9S_MB_2U(SCH_1):PAGE273_I16@PURE_QUANTA.ISL99390FRZTR5935(CHIPS)':
 'TOUT_FLT': CDS_PINID='TOUT_FLT';
NODE_NAME     PU23_P1_8 36
 '@S9S_MB_2U_LIB.S9S_MB_2U(SCH_1):PAGE274_I11@PURE_QUANTA.ISL99390FRZTR5935(CHIPS)':
 'TOUT_FLT': CDS_PINID='TOUT_FLT';
NODE_NAME     PU24_P1_7 36
 '@S9S_MB_2U_LIB.S9S_MB_2U(SCH_1):PAGE274_I20@PURE_QUANTA.ISL99390FRZTR5935(CHIPS)':
 'TOUT_FLT': CDS_PINID='TOUT_FLT';
NODE_NAME     PU31_P1_1 36
 '@S9S_MB_2U_LIB.S9S_MB_2U(SCH_1):PAGE271_I40@PURE_QUANTA.ISL99390FRZTR5935(CHIPS)':
 'TOUT_FLT': CDS_PINID='TOUT_FLT';
NODE_NAME     PU30_P1_2 36
 '@S9S_MB_2U_LIB.S9S_MB_2U(SCH_1):PAGE271_I7@PURE_QUANTA.ISL99390FRZTR5935(CHIPS)':
 'TOUT_FLT': CDS_PINID='TOUT_FLT';
NODE_NAME     PU29 43
 '@S9S_MB_2U_LIB.S9S_MB_2U(SCH_1):PAGE270_I33@PURE_QUANTA.RAA229126GNPHA0(CHIPS)':
 'TEMP0': CDS_PINID='TEMP0';
NODE_NAME     PC554 1
 '@S9S_MB_2U_LIB.S9S_MB_2U(SCH_1):PAGE270_I72@PURE_QUANTA.Q_CAP(CHIPS)':
 'A': CDS_PINID='A';
NET_NAME
'PVCCIN_CPU1_CSPIN'
 '@S9S_MB_2U_LIB.S9S_MB_2U(SCH_1):PVCCIN_CPU1_CSPIN':
 C_SIGNAL='@s9s_mb_2u_lib.s9s_mb_2u(sch_1):pvccin_cpu1_cspin';
NODE_NAME     PC547 1
 '@S9S_MB_2U_LIB.S9S_MB_2U(SCH_1):PAGE270_I28@PURE_QUANTA.Q_CAP(CHIPS)':
 'A': CDS_PINID='A';
NODE_NAME     PR304 2
 '@S9S_MB_2U_LIB.S9S_MB_2U(SCH_1):PAGE270_I9@PURE_QUANTA.Q_RES(CHIPS)':
 'B': CDS_PINID='B';
NODE_NAME     PR305 1
 '@S9S_MB_2U_LIB.S9S_MB_2U(SCH_1):PAGE270_I27@PURE_QUANTA.Q_RES(CHIPS)':
 'A': CDS_PINID='A';
NODE_NAME     PU29 45
 '@S9S_MB_2U_LIB.S9S_MB_2U(SCH_1):PAGE270_I33@PURE_QUANTA.RAA229126GNPHA0(CHIPS)':
 'VMON||IINSEN||VSYS||ISYS': CDS_PINID='\vmon||iinsen||vsys||isys\';
NET_NAME
'PVCCIN_CPU1_EN_R'
 '@S9S_MB_2U_LIB.S9S_MB_2U(SCH_1):PVCCIN_CPU1_EN_R':
 C_SIGNAL='@s9s_mb_2u_lib.s9s_mb_2u(sch_1):pvccin_cpu1_en_r';
NODE_NAME     C2860 1
 '@S9S_MB_2U_LIB.S9S_MB_2U(SCH_1):PAGE270_I67@PURE_QUANTA.Q_CAP(CHIPS)':
 'A': CDS_PINID='A';
NODE_NAME     R309 2
 '@S9S_MB_2U_LIB.S9S_MB_2U(SCH_1):PAGE270_I59@PURE_QUANTA.Q_RES(CHIPS)':
 'B': CDS_PINID='B';
NODE_NAME     PU29 17
 '@S9S_MB_2U_LIB.S9S_MB_2U(SCH_1):PAGE270_I33@PURE_QUANTA.RAA229126GNPHA0(CHIPS)':
 'EN0': CDS_PINID='EN0';
NET_NAME
'PVCCIN_CPU1_IMON1'
 '@S9S_MB_2U_LIB.S9S_MB_2U(SCH_1):PVCCIN_CPU1_IMON1':
 C_SIGNAL='@s9s_mb_2u_lib.s9s_mb_2u(sch_1):pvccin_cpu1_imon1';
NODE_NAME     PU31_P1_1 38
 '@S9S_MB_2U_LIB.S9S_MB_2U(SCH_1):PAGE271_I40@PURE_QUANTA.ISL99390FRZTR5935(CHIPS)':
 'IOUT': CDS_PINID='IOUT';
NODE_NAME     PU29 27
 '@S9S_MB_2U_LIB.S9S_MB_2U(SCH_1):PAGE270_I33@PURE_QUANTA.RAA229126GNPHA0(CHIPS)':
 'CS11': CDS_PINID='CS11';
NET_NAME
'PVCCIN_CPU1_IMON2'
 '@S9S_MB_2U_LIB.S9S_MB_2U(SCH_1):PVCCIN_CPU1_IMON2':
 C_SIGNAL='@s9s_mb_2u_lib.s9s_mb_2u(sch_1):pvccin_cpu1_imon2';
NODE_NAME     PU30_P1_2 38
 '@S9S_MB_2U_LIB.S9S_MB_2U(SCH_1):PAGE271_I7@PURE_QUANTA.ISL99390FRZTR5935(CHIPS)':
 'IOUT': CDS_PINID='IOUT';
NODE_NAME     PU29 28
 '@S9S_MB_2U_LIB.S9S_MB_2U(SCH_1):PAGE270_I33@PURE_QUANTA.RAA229126GNPHA0(CHIPS)':
 'CS10': CDS_PINID='CS10';
NET_NAME
'PVCCIN_CPU1_IMON3'
 '@S9S_MB_2U_LIB.S9S_MB_2U(SCH_1):PVCCIN_CPU1_IMON3':
 C_SIGNAL='@s9s_mb_2u_lib.s9s_mb_2u(sch_1):pvccin_cpu1_imon3';
NODE_NAME     PU28_P1_3 38
 '@S9S_MB_2U_LIB.S9S_MB_2U(SCH_1):PAGE272_I66@PURE_QUANTA.ISL99390FRZTR5935(CHIPS)':
 'IOUT': CDS_PINID='IOUT';
NODE_NAME     PU29 29
 '@S9S_MB_2U_LIB.S9S_MB_2U(SCH_1):PAGE270_I33@PURE_QUANTA.RAA229126GNPHA0(CHIPS)':
 'CS9': CDS_PINID='CS9';
NET_NAME
'PVCCIN_CPU1_IMON4'
 '@S9S_MB_2U_LIB.S9S_MB_2U(SCH_1):PVCCIN_CPU1_IMON4':
 C_SIGNAL='@s9s_mb_2u_lib.s9s_mb_2u(sch_1):pvccin_cpu1_imon4';
NODE_NAME     PU27_P1_4 38
 '@S9S_MB_2U_LIB.S9S_MB_2U(SCH_1):PAGE272_I10@PURE_QUANTA.ISL99390FRZTR5935(CHIPS)':
 'IOUT': CDS_PINID='IOUT';
NODE_NAME     PU29 30
 '@S9S_MB_2U_LIB.S9S_MB_2U(SCH_1):PAGE270_I33@PURE_QUANTA.RAA229126GNPHA0(CHIPS)':
 'CS8': CDS_PINID='CS8';
NET_NAME
'PVCCIN_CPU1_IMON5'
 '@S9S_MB_2U_LIB.S9S_MB_2U(SCH_1):PVCCIN_CPU1_IMON5':
 C_SIGNAL='@s9s_mb_2u_lib.s9s_mb_2u(sch_1):pvccin_cpu1_imon5';
NODE_NAME     PU26_P1_5 38
 '@S9S_MB_2U_LIB.S9S_MB_2U(SCH_1):PAGE273_I23@PURE_QUANTA.ISL99390FRZTR5935(CHIPS)':
 'IOUT': CDS_PINID='IOUT';
NODE_NAME     PU29 31
 '@S9S_MB_2U_LIB.S9S_MB_2U(SCH_1):PAGE270_I33@PURE_QUANTA.RAA229126GNPHA0(CHIPS)':
 'CS7': CDS_PINID='CS7';
NET_NAME
'PVCCIN_CPU1_IMON6'
 '@S9S_MB_2U_LIB.S9S_MB_2U(SCH_1):PVCCIN_CPU1_IMON6':
 C_SIGNAL='@s9s_mb_2u_lib.s9s_mb_2u(sch_1):pvccin_cpu1_imon6';
NODE_NAME     PU25_P1_6 38
 '@S9S_MB_2U_LIB.S9S_MB_2U(SCH_1):PAGE273_I16@PURE_QUANTA.ISL99390FRZTR5935(CHIPS)':
 'IOUT': CDS_PINID='IOUT';
NODE_NAME     PU29 32
 '@S9S_MB_2U_LIB.S9S_MB_2U(SCH_1):PAGE270_I33@PURE_QUANTA.RAA229126GNPHA0(CHIPS)':
 'CS6': CDS_PINID='CS6';
NET_NAME
'PVCCIN_CPU1_IMON7'
 '@S9S_MB_2U_LIB.S9S_MB_2U(SCH_1):PVCCIN_CPU1_IMON7':
 C_SIGNAL='@s9s_mb_2u_lib.s9s_mb_2u(sch_1):pvccin_cpu1_imon7';
NODE_NAME     PU24_P1_7 38
 '@S9S_MB_2U_LIB.S9S_MB_2U(SCH_1):PAGE274_I20@PURE_QUANTA.ISL99390FRZTR5935(CHIPS)':
 'IOUT': CDS_PINID='IOUT';
NODE_NAME     PU29 33
 '@S9S_MB_2U_LIB.S9S_MB_2U(SCH_1):PAGE270_I33@PURE_QUANTA.RAA229126GNPHA0(CHIPS)':
 'CS5': CDS_PINID='CS5';
NET_NAME
'PVCCIN_CPU1_IMON8'
 '@S9S_MB_2U_LIB.S9S_MB_2U(SCH_1):PVCCIN_CPU1_IMON8':
 C_SIGNAL='@s9s_mb_2u_lib.s9s_mb_2u(sch_1):pvccin_cpu1_imon8';
NODE_NAME     PU23_P1_8 38
 '@S9S_MB_2U_LIB.S9S_MB_2U(SCH_1):PAGE274_I11@PURE_QUANTA.ISL99390FRZTR5935(CHIPS)':
 'IOUT': CDS_PINID='IOUT';
NODE_NAME     PU29 34
 '@S9S_MB_2U_LIB.S9S_MB_2U(SCH_1):PAGE270_I33@PURE_QUANTA.RAA229126GNPHA0(CHIPS)':
 'CS4': CDS_PINID='CS4';
NET_NAME
'PVCCIN_CPU1_LSET1'
 '@S9S_MB_2U_LIB.S9S_MB_2U(SCH_1):PVCCIN_CPU1_LSET1':
 C_SIGNAL='@s9s_mb_2u_lib.s9s_mb_2u(sch_1):pvccin_cpu1_lset1';
NODE_NAME     PR326 1
 '@S9S_MB_2U_LIB.S9S_MB_2U(SCH_1):PAGE271_I29@PURE_QUANTA.Q_RES(CHIPS)':
 'A': CDS_PINID='A';
NODE_NAME     PU31_P1_1 37
 '@S9S_MB_2U_LIB.S9S_MB_2U(SCH_1):PAGE271_I40@PURE_QUANTA.ISL99390FRZTR5935(CHIPS)':
 'LSET': CDS_PINID='LSET';
NET_NAME
'PVCCIN_CPU1_LSET2'
 '@S9S_MB_2U_LIB.S9S_MB_2U(SCH_1):PVCCIN_CPU1_LSET2':
 C_SIGNAL='@s9s_mb_2u_lib.s9s_mb_2u(sch_1):pvccin_cpu1_lset2';
NODE_NAME     PR325 1
 '@S9S_MB_2U_LIB.S9S_MB_2U(SCH_1):PAGE271_I3@PURE_QUANTA.Q_RES(CHIPS)':
 'A': CDS_PINID='A';
NODE_NAME     PU30_P1_2 37
 '@S9S_MB_2U_LIB.S9S_MB_2U(SCH_1):PAGE271_I7@PURE_QUANTA.ISL99390FRZTR5935(CHIPS)':
 'LSET': CDS_PINID='LSET';
NET_NAME
'PVCCIN_CPU1_LSET3'
 '@S9S_MB_2U_LIB.S9S_MB_2U(SCH_1):PVCCIN_CPU1_LSET3':
 C_SIGNAL='@s9s_mb_2u_lib.s9s_mb_2u(sch_1):pvccin_cpu1_lset3';
NODE_NAME     PR298 1
 '@S9S_MB_2U_LIB.S9S_MB_2U(SCH_1):PAGE272_I15@PURE_QUANTA.Q_RES(CHIPS)':
 'A': CDS_PINID='A';
NODE_NAME     PU28_P1_3 37
 '@S9S_MB_2U_LIB.S9S_MB_2U(SCH_1):PAGE272_I66@PURE_QUANTA.ISL99390FRZTR5935(CHIPS)':
 'LSET': CDS_PINID='LSET';
NET_NAME
'PVCCIN_CPU1_LSET4'
 '@S9S_MB_2U_LIB.S9S_MB_2U(SCH_1):PVCCIN_CPU1_LSET4':
 C_SIGNAL='@s9s_mb_2u_lib.s9s_mb_2u(sch_1):pvccin_cpu1_lset4';
NODE_NAME     PR297 1
 '@S9S_MB_2U_LIB.S9S_MB_2U(SCH_1):PAGE272_I3@PURE_QUANTA.Q_RES(CHIPS)':
 'A': CDS_PINID='A';
NODE_NAME     PU27_P1_4 37
 '@S9S_MB_2U_LIB.S9S_MB_2U(SCH_1):PAGE272_I10@PURE_QUANTA.ISL99390FRZTR5935(CHIPS)':
 'LSET': CDS_PINID='LSET';
NET_NAME
'PVCCIN_CPU1_LSET5'
 '@S9S_MB_2U_LIB.S9S_MB_2U(SCH_1):PVCCIN_CPU1_LSET5':
 C_SIGNAL='@s9s_mb_2u_lib.s9s_mb_2u(sch_1):pvccin_cpu1_lset5';
NODE_NAME     PU26_P1_5 37
 '@S9S_MB_2U_LIB.S9S_MB_2U(SCH_1):PAGE273_I23@PURE_QUANTA.ISL99390FRZTR5935(CHIPS)':
 'LSET': CDS_PINID='LSET';
NODE_NAME     PR292 1
 '@S9S_MB_2U_LIB.S9S_MB_2U(SCH_1):PAGE273_I7@PURE_QUANTA.Q_RES(CHIPS)':
 'A': CDS_PINID='A';
NET_NAME
'PVCCIN_CPU1_LSET6'
 '@S9S_MB_2U_LIB.S9S_MB_2U(SCH_1):PVCCIN_CPU1_LSET6':
 C_SIGNAL='@s9s_mb_2u_lib.s9s_mb_2u(sch_1):pvccin_cpu1_lset6';
NODE_NAME     PR291 1
 '@S9S_MB_2U_LIB.S9S_MB_2U(SCH_1):PAGE273_I2@PURE_QUANTA.Q_RES(CHIPS)':
 'A': CDS_PINID='A';
NODE_NAME     PU25_P1_6 37
 '@S9S_MB_2U_LIB.S9S_MB_2U(SCH_1):PAGE273_I16@PURE_QUANTA.ISL99390FRZTR5935(CHIPS)':
 'LSET': CDS_PINID='LSET';
NET_NAME
'PVCCIN_CPU1_LSET7'
 '@S9S_MB_2U_LIB.S9S_MB_2U(SCH_1):PVCCIN_CPU1_LSET7':
 C_SIGNAL='@s9s_mb_2u_lib.s9s_mb_2u(sch_1):pvccin_cpu1_lset7';
NODE_NAME     PR286 1
 '@S9S_MB_2U_LIB.S9S_MB_2U(SCH_1):PAGE274_I15@PURE_QUANTA.Q_RES(CHIPS)':
 'A': CDS_PINID='A';
NODE_NAME     PU24_P1_7 37
 '@S9S_MB_2U_LIB.S9S_MB_2U(SCH_1):PAGE274_I20@PURE_QUANTA.ISL99390FRZTR5935(CHIPS)':
 'LSET': CDS_PINID='LSET';
NET_NAME
'PVCCIN_CPU1_LSET8'
 '@S9S_MB_2U_LIB.S9S_MB_2U(SCH_1):PVCCIN_CPU1_LSET8':
 C_SIGNAL='@s9s_mb_2u_lib.s9s_mb_2u(sch_1):pvccin_cpu1_lset8';
NODE_NAME     PR285 1
 '@S9S_MB_2U_LIB.S9S_MB_2U(SCH_1):PAGE274_I3@PURE_QUANTA.Q_RES(CHIPS)':
 'A': CDS_PINID='A';
NODE_NAME     PU23_P1_8 37
 '@S9S_MB_2U_LIB.S9S_MB_2U(SCH_1):PAGE274_I11@PURE_QUANTA.ISL99390FRZTR5935(CHIPS)':
 'LSET': CDS_PINID='LSET';
NET_NAME
'PVCCIN_CPU1_PIN_ALERT'
 '@S9S_MB_2U_LIB.S9S_MB_2U(SCH_1):PVCCIN_CPU1_PIN_ALERT':
 C_SIGNAL='@s9s_mb_2u_lib.s9s_mb_2u(sch_1):pvccin_cpu1_pin_alert';
NODE_NAME     R2525 2
 '@S9S_MB_2U_LIB.S9S_MB_2U(SCH_1):PAGE270_I18@PURE_QUANTA.Q_RES(CHIPS)':
 'B': CDS_PINID='B';
NODE_NAME     PU29 19
 '@S9S_MB_2U_LIB.S9S_MB_2U(SCH_1):PAGE270_I33@PURE_QUANTA.RAA229126GNPHA0(CHIPS)':
 'NPINALERT||NPSYS_CRIT': CDS_PINID='\npinalert||npsys_crit\';
NET_NAME
'PVCCIN_CPU1_PVCC'
 '@S9S_MB_2U_LIB.S9S_MB_2U(SCH_1):PVCCIN_CPU1_PVCC':
 C_SIGNAL='@s9s_mb_2u_lib.s9s_mb_2u(sch_1):pvccin_cpu1_pvcc',
 CDS_GLOBAL_NET='TRUE';
NODE_NAME     PR299 1
 '@S9S_MB_2U_LIB.S9S_MB_2U(SCH_1):PAGE272_I12@PURE_QUANTA.Q_RES(CHIPS)':
 'A': CDS_PINID='A';
NODE_NAME     PC503_P1_6 1
 '@S9S_MB_2U_LIB.S9S_MB_2U(SCH_1):PAGE273_I21@PURE_QUANTA.Q_CAP(CHIPS)':
 'A': CDS_PINID='A';
NODE_NAME     PU26_P1_5 4
 '@S9S_MB_2U_LIB.S9S_MB_2U(SCH_1):PAGE273_I23@PURE_QUANTA.ISL99390FRZTR5935(CHIPS)':
 'PVCC': CDS_PINID='PVCC';
NODE_NAME     PR294 1
 '@S9S_MB_2U_LIB.S9S_MB_2U(SCH_1):PAGE273_I39@PURE_QUANTA.Q_RES(CHIPS)':
 'A': CDS_PINID='A';
NODE_NAME     PC504_P1_5 1
 '@S9S_MB_2U_LIB.S9S_MB_2U(SCH_1):PAGE273_I41@PURE_QUANTA.Q_CAP(CHIPS)':
 'A': CDS_PINID='A';
NODE_NAME     PC481_P1_8 1
 '@S9S_MB_2U_LIB.S9S_MB_2U(SCH_1):PAGE274_I18@PURE_QUANTA.Q_CAP(CHIPS)':
 'A': CDS_PINID='A';
NODE_NAME     PU27_P1_4 4
 '@S9S_MB_2U_LIB.S9S_MB_2U(SCH_1):PAGE272_I10@PURE_QUANTA.ISL99390FRZTR5935(CHIPS)':
 'PVCC': CDS_PINID='PVCC';
NODE_NAME     PC525_P1_4 1
 '@S9S_MB_2U_LIB.S9S_MB_2U(SCH_1):PAGE272_I19@PURE_QUANTA.Q_CAP(CHIPS)':
 'A': CDS_PINID='A';
NODE_NAME     PR300 1
 '@S9S_MB_2U_LIB.S9S_MB_2U(SCH_1):PAGE272_I25@PURE_QUANTA.Q_RES(CHIPS)':
 'A': CDS_PINID='A';
NODE_NAME     PC526_P1_3 1
 '@S9S_MB_2U_LIB.S9S_MB_2U(SCH_1):PAGE272_I29@PURE_QUANTA.Q_CAP(CHIPS)':
 'A': CDS_PINID='A';
NODE_NAME     PU28_P1_3 4
 '@S9S_MB_2U_LIB.S9S_MB_2U(SCH_1):PAGE272_I66@PURE_QUANTA.ISL99390FRZTR5935(CHIPS)':
 'PVCC': CDS_PINID='PVCC';
NODE_NAME     PU25_P1_6 4
 '@S9S_MB_2U_LIB.S9S_MB_2U(SCH_1):PAGE273_I16@PURE_QUANTA.ISL99390FRZTR5935(CHIPS)':
 'PVCC': CDS_PINID='PVCC';
NODE_NAME     PR293 1
 '@S9S_MB_2U_LIB.S9S_MB_2U(SCH_1):PAGE273_I19@PURE_QUANTA.Q_RES(CHIPS)':
 'A': CDS_PINID='A';
NODE_NAME     PU23_P1_8 4
 '@S9S_MB_2U_LIB.S9S_MB_2U(SCH_1):PAGE274_I11@PURE_QUANTA.ISL99390FRZTR5935(CHIPS)':
 'PVCC': CDS_PINID='PVCC';
NODE_NAME     PR287 1
 '@S9S_MB_2U_LIB.S9S_MB_2U(SCH_1):PAGE274_I12@PURE_QUANTA.Q_RES(CHIPS)':
 'A': CDS_PINID='A';
NODE_NAME     PU24_P1_7 4
 '@S9S_MB_2U_LIB.S9S_MB_2U(SCH_1):PAGE274_I20@PURE_QUANTA.ISL99390FRZTR5935(CHIPS)':
 'PVCC': CDS_PINID='PVCC';
NODE_NAME     PR288 1
 '@S9S_MB_2U_LIB.S9S_MB_2U(SCH_1):PAGE274_I68@PURE_QUANTA.Q_RES(CHIPS)':
 'A': CDS_PINID='A';
NODE_NAME     PC482_P1_7 1
 '@S9S_MB_2U_LIB.S9S_MB_2U(SCH_1):PAGE274_I69@PURE_QUANTA.Q_CAP(CHIPS)':
 'A': CDS_PINID='A';
NODE_NAME     PC558_P1_2 1
 '@S9S_MB_2U_LIB.S9S_MB_2U(SCH_1):PAGE271_I15@PURE_QUANTA.Q_CAP(CHIPS)':
 'A': CDS_PINID='A';
NODE_NAME     PR328 1
 '@S9S_MB_2U_LIB.S9S_MB_2U(SCH_1):PAGE271_I37@PURE_QUANTA.Q_RES(CHIPS)':
 'A': CDS_PINID='A';
NODE_NAME     PC559_P1_1 1
 '@S9S_MB_2U_LIB.S9S_MB_2U(SCH_1):PAGE271_I39@PURE_QUANTA.Q_CAP(CHIPS)':
 'A': CDS_PINID='A';
NODE_NAME     PU31_P1_1 4
 '@S9S_MB_2U_LIB.S9S_MB_2U(SCH_1):PAGE271_I40@PURE_QUANTA.ISL99390FRZTR5935(CHIPS)':
 'PVCC': CDS_PINID='PVCC';
NODE_NAME     PU30_P1_2 4
 '@S9S_MB_2U_LIB.S9S_MB_2U(SCH_1):PAGE271_I7@PURE_QUANTA.ISL99390FRZTR5935(CHIPS)':
 'PVCC': CDS_PINID='PVCC';
NODE_NAME     PR327 1
 '@S9S_MB_2U_LIB.S9S_MB_2U(SCH_1):PAGE271_I13@PURE_QUANTA.Q_RES(CHIPS)':
 'A': CDS_PINID='A';
NODE_NAME     PR639 2
 '@S9S_MB_2U_LIB.S9S_MB_2U(SCH_1):PAGE271_I26@PURE_QUANTA.Q_RES(CHIPS)':
 'B': CDS_PINID='B';
NODE_NAME     PR640 2
 '@S9S_MB_2U_LIB.S9S_MB_2U(SCH_1):PAGE271_I41@PURE_QUANTA.Q_RES(CHIPS)':
 'B': CDS_PINID='B';
NET_NAME
'PVCCIN_CPU1_PWM1'
 '@S9S_MB_2U_LIB.S9S_MB_2U(SCH_1):PVCCIN_CPU1_PWM1':
 C_SIGNAL='@s9s_mb_2u_lib.s9s_mb_2u(sch_1):pvccin_cpu1_pwm1';
NODE_NAME     PU31_P1_1 34
 '@S9S_MB_2U_LIB.S9S_MB_2U(SCH_1):PAGE271_I40@PURE_QUANTA.ISL99390FRZTR5935(CHIPS)':
 'PWM': CDS_PINID='PWM';
NODE_NAME     PU29 12
 '@S9S_MB_2U_LIB.S9S_MB_2U(SCH_1):PAGE270_I33@PURE_QUANTA.RAA229126GNPHA0(CHIPS)':
 'PWM11': CDS_PINID='PWM11';
NET_NAME
'PVCCIN_CPU1_PWM2'
 '@S9S_MB_2U_LIB.S9S_MB_2U(SCH_1):PVCCIN_CPU1_PWM2':
 C_SIGNAL='@s9s_mb_2u_lib.s9s_mb_2u(sch_1):pvccin_cpu1_pwm2';
NODE_NAME     PU30_P1_2 34
 '@S9S_MB_2U_LIB.S9S_MB_2U(SCH_1):PAGE271_I7@PURE_QUANTA.ISL99390FRZTR5935(CHIPS)':
 'PWM': CDS_PINID='PWM';
NODE_NAME     PU29 11
 '@S9S_MB_2U_LIB.S9S_MB_2U(SCH_1):PAGE270_I33@PURE_QUANTA.RAA229126GNPHA0(CHIPS)':
 'PWM10': CDS_PINID='PWM10';
NET_NAME
'PVCCIN_CPU1_PWM3'
 '@S9S_MB_2U_LIB.S9S_MB_2U(SCH_1):PVCCIN_CPU1_PWM3':
 C_SIGNAL='@s9s_mb_2u_lib.s9s_mb_2u(sch_1):pvccin_cpu1_pwm3';
NODE_NAME     PU28_P1_3 34
 '@S9S_MB_2U_LIB.S9S_MB_2U(SCH_1):PAGE272_I66@PURE_QUANTA.ISL99390FRZTR5935(CHIPS)':
 'PWM': CDS_PINID='PWM';
NODE_NAME     PU29 10
 '@S9S_MB_2U_LIB.S9S_MB_2U(SCH_1):PAGE270_I33@PURE_QUANTA.RAA229126GNPHA0(CHIPS)':
 'PWM9': CDS_PINID='PWM9';
NET_NAME
'PVCCIN_CPU1_PWM4'
 '@S9S_MB_2U_LIB.S9S_MB_2U(SCH_1):PVCCIN_CPU1_PWM4':
 C_SIGNAL='@s9s_mb_2u_lib.s9s_mb_2u(sch_1):pvccin_cpu1_pwm4';
NODE_NAME     PU27_P1_4 34
 '@S9S_MB_2U_LIB.S9S_MB_2U(SCH_1):PAGE272_I10@PURE_QUANTA.ISL99390FRZTR5935(CHIPS)':
 'PWM': CDS_PINID='PWM';
NODE_NAME     PU29 9
 '@S9S_MB_2U_LIB.S9S_MB_2U(SCH_1):PAGE270_I33@PURE_QUANTA.RAA229126GNPHA0(CHIPS)':
 'PWM8': CDS_PINID='PWM8';
NET_NAME
'PVCCIN_CPU1_PWM5'
 '@S9S_MB_2U_LIB.S9S_MB_2U(SCH_1):PVCCIN_CPU1_PWM5':
 C_SIGNAL='@s9s_mb_2u_lib.s9s_mb_2u(sch_1):pvccin_cpu1_pwm5';
NODE_NAME     PU26_P1_5 34
 '@S9S_MB_2U_LIB.S9S_MB_2U(SCH_1):PAGE273_I23@PURE_QUANTA.ISL99390FRZTR5935(CHIPS)':
 'PWM': CDS_PINID='PWM';
NODE_NAME     PU29 8
 '@S9S_MB_2U_LIB.S9S_MB_2U(SCH_1):PAGE270_I33@PURE_QUANTA.RAA229126GNPHA0(CHIPS)':
 'PWM7': CDS_PINID='PWM7';
NET_NAME
'PVCCIN_CPU1_PWM6'
 '@S9S_MB_2U_LIB.S9S_MB_2U(SCH_1):PVCCIN_CPU1_PWM6':
 C_SIGNAL='@s9s_mb_2u_lib.s9s_mb_2u(sch_1):pvccin_cpu1_pwm6';
NODE_NAME     PU25_P1_6 34
 '@S9S_MB_2U_LIB.S9S_MB_2U(SCH_1):PAGE273_I16@PURE_QUANTA.ISL99390FRZTR5935(CHIPS)':
 'PWM': CDS_PINID='PWM';
NODE_NAME     PU29 7
 '@S9S_MB_2U_LIB.S9S_MB_2U(SCH_1):PAGE270_I33@PURE_QUANTA.RAA229126GNPHA0(CHIPS)':
 'PWM6': CDS_PINID='PWM6';
NET_NAME
'PVCCIN_CPU1_PWM7'
 '@S9S_MB_2U_LIB.S9S_MB_2U(SCH_1):PVCCIN_CPU1_PWM7':
 C_SIGNAL='@s9s_mb_2u_lib.s9s_mb_2u(sch_1):pvccin_cpu1_pwm7';
NODE_NAME     PU24_P1_7 34
 '@S9S_MB_2U_LIB.S9S_MB_2U(SCH_1):PAGE274_I20@PURE_QUANTA.ISL99390FRZTR5935(CHIPS)':
 'PWM': CDS_PINID='PWM';
NODE_NAME     PU29 6
 '@S9S_MB_2U_LIB.S9S_MB_2U(SCH_1):PAGE270_I33@PURE_QUANTA.RAA229126GNPHA0(CHIPS)':
 'PWM5': CDS_PINID='PWM5';
NET_NAME
'PVCCIN_CPU1_PWM8'
 '@S9S_MB_2U_LIB.S9S_MB_2U(SCH_1):PVCCIN_CPU1_PWM8':
 C_SIGNAL='@s9s_mb_2u_lib.s9s_mb_2u(sch_1):pvccin_cpu1_pwm8';
NODE_NAME     PU23_P1_8 34
 '@S9S_MB_2U_LIB.S9S_MB_2U(SCH_1):PAGE274_I11@PURE_QUANTA.ISL99390FRZTR5935(CHIPS)':
 'PWM': CDS_PINID='PWM';
NODE_NAME     PU29 5
 '@S9S_MB_2U_LIB.S9S_MB_2U(SCH_1):PAGE270_I33@PURE_QUANTA.RAA229126GNPHA0(CHIPS)':
 'PWM4': CDS_PINID='PWM4';
NET_NAME
'PVCCIN_CPU1_VCC'
 '@S9S_MB_2U_LIB.S9S_MB_2U(SCH_1):PVCCIN_CPU1_VCC':
 C_SIGNAL='@s9s_mb_2u_lib.s9s_mb_2u(sch_1):pvccin_cpu1_vcc';
NODE_NAME     PC552 1
 '@S9S_MB_2U_LIB.S9S_MB_2U(SCH_1):PAGE270_I120@PURE_QUANTA.Q_CAP(CHIPS)':
 'A': CDS_PINID='A';
NODE_NAME     PC555 1
 '@S9S_MB_2U_LIB.S9S_MB_2U(SCH_1):PAGE270_I122@PURE_QUANTA.Q_CAP(CHIPS)':
 'A': CDS_PINID='A';
NODE_NAME     PR323 1
 '@S9S_MB_2U_LIB.S9S_MB_2U(SCH_1):PAGE270_I126@PURE_QUANTA.Q_RES(CHIPS)':
 'A': CDS_PINID='A';
NODE_NAME     PU29 47
 '@S9S_MB_2U_LIB.S9S_MB_2U(SCH_1):PAGE270_I33@PURE_QUANTA.RAA229126GNPHA0(CHIPS)':
 'VCC': CDS_PINID='VCC';
NODE_NAME     PC2366 1
 '@S9S_MB_2U_LIB.S9S_MB_2U(SCH_1):PAGE270_I128@PURE_QUANTA.Q_CAP(CHIPS)':
 'A': CDS_PINID='A';
NET_NAME
'PVCCIN_CPU1_VDD1'
 '@S9S_MB_2U_LIB.S9S_MB_2U(SCH_1):PVCCIN_CPU1_VDD1':
 C_SIGNAL='@s9s_mb_2u_lib.s9s_mb_2u(sch_1):pvccin_cpu1_vdd1';
NODE_NAME     PR328 2
 '@S9S_MB_2U_LIB.S9S_MB_2U(SCH_1):PAGE271_I37@PURE_QUANTA.Q_RES(CHIPS)':
 'B': CDS_PINID='B';
NODE_NAME     PU31_P1_1 35
 '@S9S_MB_2U_LIB.S9S_MB_2U(SCH_1):PAGE271_I40@PURE_QUANTA.ISL99390FRZTR5935(CHIPS)':
 'EN': CDS_PINID='EN';
NODE_NAME     PU31_P1_1 3
 '@S9S_MB_2U_LIB.S9S_MB_2U(SCH_1):PAGE271_I40@PURE_QUANTA.ISL99390FRZTR5935(CHIPS)':
 'VCC': CDS_PINID='VCC';
NODE_NAME     PC557 1
 '@S9S_MB_2U_LIB.S9S_MB_2U(SCH_1):PAGE271_I36@PURE_QUANTA.Q_CAP(CHIPS)':
 'A': CDS_PINID='A';
NET_NAME
'PVCCIN_CPU1_VDD2'
 '@S9S_MB_2U_LIB.S9S_MB_2U(SCH_1):PVCCIN_CPU1_VDD2':
 C_SIGNAL='@s9s_mb_2u_lib.s9s_mb_2u(sch_1):pvccin_cpu1_vdd2';
NODE_NAME     PC556 1
 '@S9S_MB_2U_LIB.S9S_MB_2U(SCH_1):PAGE271_I11@PURE_QUANTA.Q_CAP(CHIPS)':
 'A': CDS_PINID='A';
NODE_NAME     PU30_P1_2 35
 '@S9S_MB_2U_LIB.S9S_MB_2U(SCH_1):PAGE271_I7@PURE_QUANTA.ISL99390FRZTR5935(CHIPS)':
 'EN': CDS_PINID='EN';
NODE_NAME     PU30_P1_2 3
 '@S9S_MB_2U_LIB.S9S_MB_2U(SCH_1):PAGE271_I7@PURE_QUANTA.ISL99390FRZTR5935(CHIPS)':
 'VCC': CDS_PINID='VCC';
NODE_NAME     PR327 2
 '@S9S_MB_2U_LIB.S9S_MB_2U(SCH_1):PAGE271_I13@PURE_QUANTA.Q_RES(CHIPS)':
 'B': CDS_PINID='B';
NET_NAME
'PVCCIN_CPU1_VDD3'
 '@S9S_MB_2U_LIB.S9S_MB_2U(SCH_1):PVCCIN_CPU1_VDD3':
 C_SIGNAL='@s9s_mb_2u_lib.s9s_mb_2u(sch_1):pvccin_cpu1_vdd3';
NODE_NAME     PC524 1
 '@S9S_MB_2U_LIB.S9S_MB_2U(SCH_1):PAGE272_I24@PURE_QUANTA.Q_CAP(CHIPS)':
 'A': CDS_PINID='A';
NODE_NAME     PR300 2
 '@S9S_MB_2U_LIB.S9S_MB_2U(SCH_1):PAGE272_I25@PURE_QUANTA.Q_RES(CHIPS)':
 'B': CDS_PINID='B';
NODE_NAME     PU28_P1_3 35
 '@S9S_MB_2U_LIB.S9S_MB_2U(SCH_1):PAGE272_I66@PURE_QUANTA.ISL99390FRZTR5935(CHIPS)':
 'EN': CDS_PINID='EN';
NODE_NAME     PU28_P1_3 3
 '@S9S_MB_2U_LIB.S9S_MB_2U(SCH_1):PAGE272_I66@PURE_QUANTA.ISL99390FRZTR5935(CHIPS)':
 'VCC': CDS_PINID='VCC';
NET_NAME
'PVCCIN_CPU1_VDD4'
 '@S9S_MB_2U_LIB.S9S_MB_2U(SCH_1):PVCCIN_CPU1_VDD4':
 C_SIGNAL='@s9s_mb_2u_lib.s9s_mb_2u(sch_1):pvccin_cpu1_vdd4';
NODE_NAME     PC523 1
 '@S9S_MB_2U_LIB.S9S_MB_2U(SCH_1):PAGE272_I11@PURE_QUANTA.Q_CAP(CHIPS)':
 'A': CDS_PINID='A';
NODE_NAME     PR299 2
 '@S9S_MB_2U_LIB.S9S_MB_2U(SCH_1):PAGE272_I12@PURE_QUANTA.Q_RES(CHIPS)':
 'B': CDS_PINID='B';
NODE_NAME     PU27_P1_4 35
 '@S9S_MB_2U_LIB.S9S_MB_2U(SCH_1):PAGE272_I10@PURE_QUANTA.ISL99390FRZTR5935(CHIPS)':
 'EN': CDS_PINID='EN';
NODE_NAME     PU27_P1_4 3
 '@S9S_MB_2U_LIB.S9S_MB_2U(SCH_1):PAGE272_I10@PURE_QUANTA.ISL99390FRZTR5935(CHIPS)':
 'VCC': CDS_PINID='VCC';
NET_NAME
'PVCCIN_CPU1_VDD5'
 '@S9S_MB_2U_LIB.S9S_MB_2U(SCH_1):PVCCIN_CPU1_VDD5':
 C_SIGNAL='@s9s_mb_2u_lib.s9s_mb_2u(sch_1):pvccin_cpu1_vdd5';
NODE_NAME     PU26_P1_5 35
 '@S9S_MB_2U_LIB.S9S_MB_2U(SCH_1):PAGE273_I23@PURE_QUANTA.ISL99390FRZTR5935(CHIPS)':
 'EN': CDS_PINID='EN';
NODE_NAME     PU26_P1_5 3
 '@S9S_MB_2U_LIB.S9S_MB_2U(SCH_1):PAGE273_I23@PURE_QUANTA.ISL99390FRZTR5935(CHIPS)':
 'VCC': CDS_PINID='VCC';
NODE_NAME     PC502 1
 '@S9S_MB_2U_LIB.S9S_MB_2U(SCH_1):PAGE273_I37@PURE_QUANTA.Q_CAP(CHIPS)':
 'A': CDS_PINID='A';
NODE_NAME     PR294 2
 '@S9S_MB_2U_LIB.S9S_MB_2U(SCH_1):PAGE273_I39@PURE_QUANTA.Q_RES(CHIPS)':
 'B': CDS_PINID='B';
NET_NAME
'PVCCIN_CPU1_VDD6'
 '@S9S_MB_2U_LIB.S9S_MB_2U(SCH_1):PVCCIN_CPU1_VDD6':
 C_SIGNAL='@s9s_mb_2u_lib.s9s_mb_2u(sch_1):pvccin_cpu1_vdd6';
NODE_NAME     PU25_P1_6 35
 '@S9S_MB_2U_LIB.S9S_MB_2U(SCH_1):PAGE273_I16@PURE_QUANTA.ISL99390FRZTR5935(CHIPS)':
 'EN': CDS_PINID='EN';
NODE_NAME     PU25_P1_6 3
 '@S9S_MB_2U_LIB.S9S_MB_2U(SCH_1):PAGE273_I16@PURE_QUANTA.ISL99390FRZTR5935(CHIPS)':
 'VCC': CDS_PINID='VCC';
NODE_NAME     PC501 1
 '@S9S_MB_2U_LIB.S9S_MB_2U(SCH_1):PAGE273_I17@PURE_QUANTA.Q_CAP(CHIPS)':
 'A': CDS_PINID='A';
NODE_NAME     PR293 2
 '@S9S_MB_2U_LIB.S9S_MB_2U(SCH_1):PAGE273_I19@PURE_QUANTA.Q_RES(CHIPS)':
 'B': CDS_PINID='B';
NET_NAME
'PVCCIN_CPU1_VDD7'
 '@S9S_MB_2U_LIB.S9S_MB_2U(SCH_1):PVCCIN_CPU1_VDD7':
 C_SIGNAL='@s9s_mb_2u_lib.s9s_mb_2u(sch_1):pvccin_cpu1_vdd7';
NODE_NAME     PC480 1
 '@S9S_MB_2U_LIB.S9S_MB_2U(SCH_1):PAGE274_I34@PURE_QUANTA.Q_CAP(CHIPS)':
 'A': CDS_PINID='A';
NODE_NAME     PU24_P1_7 35
 '@S9S_MB_2U_LIB.S9S_MB_2U(SCH_1):PAGE274_I20@PURE_QUANTA.ISL99390FRZTR5935(CHIPS)':
 'EN': CDS_PINID='EN';
NODE_NAME     PU24_P1_7 3
 '@S9S_MB_2U_LIB.S9S_MB_2U(SCH_1):PAGE274_I20@PURE_QUANTA.ISL99390FRZTR5935(CHIPS)':
 'VCC': CDS_PINID='VCC';
NODE_NAME     PR288 2
 '@S9S_MB_2U_LIB.S9S_MB_2U(SCH_1):PAGE274_I68@PURE_QUANTA.Q_RES(CHIPS)':
 'B': CDS_PINID='B';
NET_NAME
'PVCCIN_CPU1_VDD8'
 '@S9S_MB_2U_LIB.S9S_MB_2U(SCH_1):PVCCIN_CPU1_VDD8':
 C_SIGNAL='@s9s_mb_2u_lib.s9s_mb_2u(sch_1):pvccin_cpu1_vdd8';
NODE_NAME     PC479 1
 '@S9S_MB_2U_LIB.S9S_MB_2U(SCH_1):PAGE274_I9@PURE_QUANTA.Q_CAP(CHIPS)':
 'A': CDS_PINID='A';
NODE_NAME     PU23_P1_8 35
 '@S9S_MB_2U_LIB.S9S_MB_2U(SCH_1):PAGE274_I11@PURE_QUANTA.ISL99390FRZTR5935(CHIPS)':
 'EN': CDS_PINID='EN';
NODE_NAME     PU23_P1_8 3
 '@S9S_MB_2U_LIB.S9S_MB_2U(SCH_1):PAGE274_I11@PURE_QUANTA.ISL99390FRZTR5935(CHIPS)':
 'VCC': CDS_PINID='VCC';
NODE_NAME     PR287 2
 '@S9S_MB_2U_LIB.S9S_MB_2U(SCH_1):PAGE274_I12@PURE_QUANTA.Q_RES(CHIPS)':
 'B': CDS_PINID='B';
NET_NAME
'PVCCIN_CPU1_VIN_CSNIN'
 '@S9S_MB_2U_LIB.S9S_MB_2U(SCH_1):PVCCIN_CPU1_VIN_CSNIN':
 C_SIGNAL='@s9s_mb_2u_lib.s9s_mb_2u(sch_1):pvccin_cpu1_vin_csnin';
NODE_NAME     PR313 1
 '@S9S_MB_2U_LIB.S9S_MB_2U(SCH_1):PAGE270_I29@PURE_QUANTA.Q_RES(CHIPS)':
 'A': CDS_PINID='A';
NODE_NAME     PC548 1
 '@S9S_MB_2U_LIB.S9S_MB_2U(SCH_1):PAGE270_I31@PURE_QUANTA.Q_CAP(CHIPS)':
 'A': CDS_PINID='A';
NODE_NAME     PR303 2
 '@S9S_MB_2U_LIB.S9S_MB_2U(SCH_1):PAGE270_I7@PURE_QUANTA.Q_RES(CHIPS)':
 'B': CDS_PINID='B';
NODE_NAME     PU29 46
 '@S9S_MB_2U_LIB.S9S_MB_2U(SCH_1):PAGE270_I33@PURE_QUANTA.RAA229126GNPHA0(CHIPS)':
 'VINSEN||VSYS': CDS_PINID='\vinsen||vsys\';
NET_NAME
'PVCCIN_CPU1_VOS1'
 '@S9S_MB_2U_LIB.S9S_MB_2U(SCH_1):PVCCIN_CPU1_VOS1':
 C_SIGNAL='@s9s_mb_2u_lib.s9s_mb_2u(sch_1):pvccin_cpu1_vos1';
NODE_NAME     PU31_P1_1 1
 '@S9S_MB_2U_LIB.S9S_MB_2U(SCH_1):PAGE271_I40@PURE_QUANTA.ISL99390FRZTR5935(CHIPS)':
 'VOS': CDS_PINID='VOS';
NODE_NAME     PR330 1
 '@S9S_MB_2U_LIB.S9S_MB_2U(SCH_1):PAGE271_I73@PURE_QUANTA.Q_RES(CHIPS)':
 'A': CDS_PINID='A';
NET_NAME
'PVCCIN_CPU1_VOS2'
 '@S9S_MB_2U_LIB.S9S_MB_2U(SCH_1):PVCCIN_CPU1_VOS2':
 C_SIGNAL='@s9s_mb_2u_lib.s9s_mb_2u(sch_1):pvccin_cpu1_vos2';
NODE_NAME     PU30_P1_2 1
 '@S9S_MB_2U_LIB.S9S_MB_2U(SCH_1):PAGE271_I7@PURE_QUANTA.ISL99390FRZTR5935(CHIPS)':
 'VOS': CDS_PINID='VOS';
NODE_NAME     PR329 1
 '@S9S_MB_2U_LIB.S9S_MB_2U(SCH_1):PAGE271_I51@PURE_QUANTA.Q_RES(CHIPS)':
 'A': CDS_PINID='A';
NET_NAME
'PVCCIN_CPU1_VOS3'
 '@S9S_MB_2U_LIB.S9S_MB_2U(SCH_1):PVCCIN_CPU1_VOS3':
 C_SIGNAL='@s9s_mb_2u_lib.s9s_mb_2u(sch_1):pvccin_cpu1_vos3';
NODE_NAME     PR302 1
 '@S9S_MB_2U_LIB.S9S_MB_2U(SCH_1):PAGE272_I45@PURE_QUANTA.Q_RES(CHIPS)':
 'A': CDS_PINID='A';
NODE_NAME     PU28_P1_3 1
 '@S9S_MB_2U_LIB.S9S_MB_2U(SCH_1):PAGE272_I66@PURE_QUANTA.ISL99390FRZTR5935(CHIPS)':
 'VOS': CDS_PINID='VOS';
NET_NAME
'PVCCIN_CPU1_VOS4'
 '@S9S_MB_2U_LIB.S9S_MB_2U(SCH_1):PVCCIN_CPU1_VOS4':
 C_SIGNAL='@s9s_mb_2u_lib.s9s_mb_2u(sch_1):pvccin_cpu1_vos4';
NODE_NAME     PU27_P1_4 1
 '@S9S_MB_2U_LIB.S9S_MB_2U(SCH_1):PAGE272_I10@PURE_QUANTA.ISL99390FRZTR5935(CHIPS)':
 'VOS': CDS_PINID='VOS';
NODE_NAME     PR301 1
 '@S9S_MB_2U_LIB.S9S_MB_2U(SCH_1):PAGE272_I38@PURE_QUANTA.Q_RES(CHIPS)':
 'A': CDS_PINID='A';
NET_NAME
'PVCCIN_CPU1_VOS5'
 '@S9S_MB_2U_LIB.S9S_MB_2U(SCH_1):PVCCIN_CPU1_VOS5':
 C_SIGNAL='@s9s_mb_2u_lib.s9s_mb_2u(sch_1):pvccin_cpu1_vos5';
NODE_NAME     PU26_P1_5 1
 '@S9S_MB_2U_LIB.S9S_MB_2U(SCH_1):PAGE273_I23@PURE_QUANTA.ISL99390FRZTR5935(CHIPS)':
 'VOS': CDS_PINID='VOS';
NODE_NAME     PR296 1
 '@S9S_MB_2U_LIB.S9S_MB_2U(SCH_1):PAGE273_I49@PURE_QUANTA.Q_RES(CHIPS)':
 'A': CDS_PINID='A';
NET_NAME
'PVCCIN_CPU1_VOS6'
 '@S9S_MB_2U_LIB.S9S_MB_2U(SCH_1):PVCCIN_CPU1_VOS6':
 C_SIGNAL='@s9s_mb_2u_lib.s9s_mb_2u(sch_1):pvccin_cpu1_vos6';
NODE_NAME     PU25_P1_6 1
 '@S9S_MB_2U_LIB.S9S_MB_2U(SCH_1):PAGE273_I16@PURE_QUANTA.ISL99390FRZTR5935(CHIPS)':
 'VOS': CDS_PINID='VOS';
NODE_NAME     PR295 1
 '@S9S_MB_2U_LIB.S9S_MB_2U(SCH_1):PAGE273_I27@PURE_QUANTA.Q_RES(CHIPS)':
 'A': CDS_PINID='A';
NET_NAME
'PVCCIN_CPU1_VOS7'
 '@S9S_MB_2U_LIB.S9S_MB_2U(SCH_1):PVCCIN_CPU1_VOS7':
 C_SIGNAL='@s9s_mb_2u_lib.s9s_mb_2u(sch_1):pvccin_cpu1_vos7';
NODE_NAME     PU24_P1_7 1
 '@S9S_MB_2U_LIB.S9S_MB_2U(SCH_1):PAGE274_I20@PURE_QUANTA.ISL99390FRZTR5935(CHIPS)':
 'VOS': CDS_PINID='VOS';
NODE_NAME     PR290 1
 '@S9S_MB_2U_LIB.S9S_MB_2U(SCH_1):PAGE274_I50@PURE_QUANTA.Q_RES(CHIPS)':
 'A': CDS_PINID='A';
NET_NAME
'PVCCIN_CPU1_VOS8'
 '@S9S_MB_2U_LIB.S9S_MB_2U(SCH_1):PVCCIN_CPU1_VOS8':
 C_SIGNAL='@s9s_mb_2u_lib.s9s_mb_2u(sch_1):pvccin_cpu1_vos8';
NODE_NAME     PR289 1
 '@S9S_MB_2U_LIB.S9S_MB_2U(SCH_1):PAGE274_I44@PURE_QUANTA.Q_RES(CHIPS)':
 'A': CDS_PINID='A';
NODE_NAME     PU23_P1_8 1
 '@S9S_MB_2U_LIB.S9S_MB_2U(SCH_1):PAGE274_I11@PURE_QUANTA.ISL99390FRZTR5935(CHIPS)':
 'VOS': CDS_PINID='VOS';
NET_NAME
'PVCCIN_CPU1_VREF'
 '@S9S_MB_2U_LIB.S9S_MB_2U(SCH_1):PVCCIN_CPU1_VREF':
 C_SIGNAL='@s9s_mb_2u_lib.s9s_mb_2u(sch_1):pvccin_cpu1_vref';
NODE_NAME     PC1359 2
 '@S9S_MB_2U_LIB.S9S_MB_2U(SCH_1):PAGE272_I27@PURE_QUANTA.Q_CAP(CHIPS)':
 'B': CDS_PINID='B';
NODE_NAME     PU26_P1_5 39
 '@S9S_MB_2U_LIB.S9S_MB_2U(SCH_1):PAGE273_I23@PURE_QUANTA.ISL99390FRZTR5935(CHIPS)':
 'REFIN': CDS_PINID='REFIN';
NODE_NAME     PC1361 2
 '@S9S_MB_2U_LIB.S9S_MB_2U(SCH_1):PAGE273_I36@PURE_QUANTA.Q_CAP(CHIPS)':
 'B': CDS_PINID='B';
NODE_NAME     PC1363 2
 '@S9S_MB_2U_LIB.S9S_MB_2U(SCH_1):PAGE274_I32@PURE_QUANTA.Q_CAP(CHIPS)':
 'B': CDS_PINID='B';
NODE_NAME     PU76_P1_2 39
 '@S9S_MB_2U_LIB.S9S_MB_2U(SCH_1):PAGE275_I9@PURE_QUANTA.ISL99390FRZTR5935(CHIPS)':
 'REFIN': CDS_PINID='REFIN';
NODE_NAME     PR306 1
 '@S9S_MB_2U_LIB.S9S_MB_2U(SCH_1):PAGE270_I4@PURE_QUANTA.Q_RES(CHIPS)':
 'A': CDS_PINID='A';
NODE_NAME     PC1194 1
 '@S9S_MB_2U_LIB.S9S_MB_2U(SCH_1):PAGE270_I121@PURE_QUANTA.Q_CAP(CHIPS)':
 'A': CDS_PINID='A';
NODE_NAME     PC1338 2
 '@S9S_MB_2U_LIB.S9S_MB_2U(SCH_1):PAGE271_I6@PURE_QUANTA.Q_CAP(CHIPS)':
 'B': CDS_PINID='B';
NODE_NAME     PC1358 2
 '@S9S_MB_2U_LIB.S9S_MB_2U(SCH_1):PAGE272_I6@PURE_QUANTA.Q_CAP(CHIPS)':
 'B': CDS_PINID='B';
NODE_NAME     PU27_P1_4 39
 '@S9S_MB_2U_LIB.S9S_MB_2U(SCH_1):PAGE272_I10@PURE_QUANTA.ISL99390FRZTR5935(CHIPS)':
 'REFIN': CDS_PINID='REFIN';
NODE_NAME     PU28_P1_3 39
 '@S9S_MB_2U_LIB.S9S_MB_2U(SCH_1):PAGE272_I66@PURE_QUANTA.ISL99390FRZTR5935(CHIPS)':
 'REFIN': CDS_PINID='REFIN';
NODE_NAME     PC1360 2
 '@S9S_MB_2U_LIB.S9S_MB_2U(SCH_1):PAGE273_I15@PURE_QUANTA.Q_CAP(CHIPS)':
 'B': CDS_PINID='B';
NODE_NAME     PU25_P1_6 39
 '@S9S_MB_2U_LIB.S9S_MB_2U(SCH_1):PAGE273_I16@PURE_QUANTA.ISL99390FRZTR5935(CHIPS)':
 'REFIN': CDS_PINID='REFIN';
NODE_NAME     PC1362 2
 '@S9S_MB_2U_LIB.S9S_MB_2U(SCH_1):PAGE274_I7@PURE_QUANTA.Q_CAP(CHIPS)':
 'B': CDS_PINID='B';
NODE_NAME     PU23_P1_8 39
 '@S9S_MB_2U_LIB.S9S_MB_2U(SCH_1):PAGE274_I11@PURE_QUANTA.ISL99390FRZTR5935(CHIPS)':
 'REFIN': CDS_PINID='REFIN';
NODE_NAME     PU24_P1_7 39
 '@S9S_MB_2U_LIB.S9S_MB_2U(SCH_1):PAGE274_I20@PURE_QUANTA.ISL99390FRZTR5935(CHIPS)':
 'REFIN': CDS_PINID='REFIN';
NODE_NAME     PC1367 2
 '@S9S_MB_2U_LIB.S9S_MB_2U(SCH_1):PAGE275_I29@PURE_QUANTA.Q_CAP(CHIPS)':
 'B': CDS_PINID='B';
NODE_NAME     PU78_P1_4 39
 '@S9S_MB_2U_LIB.S9S_MB_2U(SCH_1):PAGE276_I15@PURE_QUANTA.ISL99390FRZTR5935(CHIPS)':
 'REFIN': CDS_PINID='REFIN';
NODE_NAME     PU31_P1_1 39
 '@S9S_MB_2U_LIB.S9S_MB_2U(SCH_1):PAGE271_I40@PURE_QUANTA.ISL99390FRZTR5935(CHIPS)':
 'REFIN': CDS_PINID='REFIN';
NODE_NAME     PC1369 2
 '@S9S_MB_2U_LIB.S9S_MB_2U(SCH_1):PAGE276_I23@PURE_QUANTA.Q_CAP(CHIPS)':
 'B': CDS_PINID='B';
NODE_NAME     PU77_P1_3 39
 '@S9S_MB_2U_LIB.S9S_MB_2U(SCH_1):PAGE276_I24@PURE_QUANTA.ISL99390FRZTR5935(CHIPS)':
 'REFIN': CDS_PINID='REFIN';
NODE_NAME     PC1368 2
 '@S9S_MB_2U_LIB.S9S_MB_2U(SCH_1):PAGE275_I8@PURE_QUANTA.Q_CAP(CHIPS)':
 'B': CDS_PINID='B';
NODE_NAME     PU75_P1_1 39
 '@S9S_MB_2U_LIB.S9S_MB_2U(SCH_1):PAGE275_I89@PURE_QUANTA.ISL99390FRZTR5935(CHIPS)':
 'REFIN': CDS_PINID='REFIN';
NODE_NAME     PU30_P1_2 39
 '@S9S_MB_2U_LIB.S9S_MB_2U(SCH_1):PAGE271_I7@PURE_QUANTA.ISL99390FRZTR5935(CHIPS)':
 'REFIN': CDS_PINID='REFIN';
NODE_NAME     PC1339 2
 '@S9S_MB_2U_LIB.S9S_MB_2U(SCH_1):PAGE271_I34@PURE_QUANTA.Q_CAP(CHIPS)':
 'B': CDS_PINID='B';
NODE_NAME     PC1370 2
 '@S9S_MB_2U_LIB.S9S_MB_2U(SCH_1):PAGE276_I13@PURE_QUANTA.Q_CAP(CHIPS)':
 'B': CDS_PINID='B';
NODE_NAME     PU29 48
 '@S9S_MB_2U_LIB.S9S_MB_2U(SCH_1):PAGE270_I33@PURE_QUANTA.RAA229126GNPHA0(CHIPS)':
 'VCCS': CDS_PINID='VCCS';
NODE_NAME     PC553 1
 '@S9S_MB_2U_LIB.S9S_MB_2U(SCH_1):PAGE270_I119@PURE_QUANTA.Q_CAP(CHIPS)':
 'A': CDS_PINID='A';
NET_NAME
'PVCCIN_CPU1_VR_FAULT'
 '@S9S_MB_2U_LIB.S9S_MB_2U(SCH_1):PVCCIN_CPU1_VR_FAULT':
 C_SIGNAL='@s9s_mb_2u_lib.s9s_mb_2u(sch_1):pvccin_cpu1_vr_fault';
NODE_NAME     R2524 2
 '@S9S_MB_2U_LIB.S9S_MB_2U(SCH_1):PAGE270_I17@PURE_QUANTA.Q_RES(CHIPS)':
 'B': CDS_PINID='B';
NODE_NAME     PU29 41
 '@S9S_MB_2U_LIB.S9S_MB_2U(SCH_1):PAGE270_I33@PURE_QUANTA.RAA229126GNPHA0(CHIPS)':
 'CFP': CDS_PINID='CFP';
NET_NAME
'PVCCIO_PECI_BMC'
 '@S9S_MB_2U_LIB.S9S_MB_2U(SCH_1):PVCCIO_PECI_BMC':
 C_SIGNAL='@s9s_mb_2u_lib.s9s_mb_2u(sch_1):pvccio_peci_bmc';
NODE_NAME     R142 2
 '@S9S_MB_2U_LIB.S9S_MB_2U(SCH_1):PAGE227_I84@PURE_QUANTA.Q_RES(CHIPS)':
 'B': CDS_PINID='B';
NODE_NAME     J41 B28
 '@S9S_MB_2U_LIB.S9S_MB_2U(SCH_1):PAGE227_I173@PURE_QUANTA.SCONN168_ME1016810202011(CHIPS)':
 'GND_B28': CDS_PINID='GND_B28';
NET_NAME
'PVNN_MAIN_CPU0'
 '@S9S_MB_2U_LIB.S9S_MB_2U(SCH_1):PVNN_MAIN_CPU0':
 C_SIGNAL='@s9s_mb_2u_lib.s9s_mb_2u(sch_1):pvnn_main_cpu0',
 CDS_GLOBAL_NET='TRUE';
NODE_NAME     U2 BA19
 '@S9S_MB_2U_LIB.S9S_MB_2U(SCH_1):PAGE37_I8@PURE_QUANTA.SOCKET4677_AZIF0045P001C01CS(CHIPS)':
 'VCCVNN0': CDS_PINID='VCCVNN0';
NODE_NAME     U2 BE19
 '@S9S_MB_2U_LIB.S9S_MB_2U(SCH_1):PAGE37_I8@PURE_QUANTA.SOCKET4677_AZIF0045P001C01CS(CHIPS)':
 'VCCVNN1': CDS_PINID='VCCVNN1';
NODE_NAME     U2 BJ19
 '@S9S_MB_2U_LIB.S9S_MB_2U(SCH_1):PAGE37_I8@PURE_QUANTA.SOCKET4677_AZIF0045P001C01CS(CHIPS)':
 'VCCVNN2': CDS_PINID='VCCVNN2';
NODE_NAME     U2 BN19
 '@S9S_MB_2U_LIB.S9S_MB_2U(SCH_1):PAGE37_I8@PURE_QUANTA.SOCKET4677_AZIF0045P001C01CS(CHIPS)':
 'VCCVNN3': CDS_PINID='VCCVNN3';
NODE_NAME     C590 1
 '@S9S_MB_2U_LIB.S9S_MB_2U(SCH_1):PAGE74_I102@PURE_QUANTA.Q_CAP(CHIPS)':
 'A': CDS_PINID='A';
NODE_NAME     C1399 1
 '@S9S_MB_2U_LIB.S9S_MB_2U(SCH_1):PAGE76_I13@PURE_QUANTA.Q_CAP(CHIPS)':
 'A': CDS_PINID='A';
NODE_NAME     C1364 1
 '@S9S_MB_2U_LIB.S9S_MB_2U(SCH_1):PAGE80_I9@PURE_QUANTA.Q_CAP(CHIPS)':
 'A': CDS_PINID='A';
NODE_NAME     C395 1
 '@S9S_MB_2U_LIB.S9S_MB_2U(SCH_1):PAGE75_I46@PURE_QUANTA.Q_CAP(CHIPS)':
 'A': CDS_PINID='A';
NODE_NAME     C1405 1
 '@S9S_MB_2U_LIB.S9S_MB_2U(SCH_1):PAGE75_I47@PURE_QUANTA.Q_CAP(CHIPS)':
 'A': CDS_PINID='A';
NODE_NAME     C1406 1
 '@S9S_MB_2U_LIB.S9S_MB_2U(SCH_1):PAGE75_I61@PURE_QUANTA.Q_CAP(CHIPS)':
 'A': CDS_PINID='A';
NODE_NAME     C1407 1
 '@S9S_MB_2U_LIB.S9S_MB_2U(SCH_1):PAGE75_I62@PURE_QUANTA.Q_CAP(CHIPS)':
 'A': CDS_PINID='A';
NODE_NAME     C1400 1
 '@S9S_MB_2U_LIB.S9S_MB_2U(SCH_1):PAGE76_I14@PURE_QUANTA.Q_CAP(CHIPS)':
 'A': CDS_PINID='A';
NODE_NAME     C1362 1
 '@S9S_MB_2U_LIB.S9S_MB_2U(SCH_1):PAGE76_I16@PURE_QUANTA.Q_CAP(CHIPS)':
 'A': CDS_PINID='A';
NODE_NAME     C1363 1
 '@S9S_MB_2U_LIB.S9S_MB_2U(SCH_1):PAGE80_I5@PURE_QUANTA.Q_CAP(CHIPS)':
 'A': CDS_PINID='A';
NODE_NAME     R324 1
 '@S9S_MB_2U_LIB.S9S_MB_2U(SCH_1):PAGE80_I12@PURE_QUANTA.Q_RES(CHIPS)':
 'A': CDS_PINID='A';
NODE_NAME     PR4698 2
 '@S9S_MB_2U_LIB.S9S_MB_2U(SCH_1):PAGE268_I40@PURE_QUANTA.Q_RES(CHIPS)':
 'B': CDS_PINID='B';
NODE_NAME     PC1278 1
 '@S9S_MB_2U_LIB.S9S_MB_2U(SCH_1):PAGE268_I42@PURE_QUANTA.Q_CAP(CHIPS)':
 'A': CDS_PINID='A';
NODE_NAME     PR4683 2
 '@S9S_MB_2U_LIB.S9S_MB_2U(SCH_1):PAGE268_I41@PURE_QUANTA.Q_RES(CHIPS)':
 'B': CDS_PINID='B';
NODE_NAME     PC1279 1
 '@S9S_MB_2U_LIB.S9S_MB_2U(SCH_1):PAGE268_I43@PURE_QUANTA.Q_CAP(CHIPS)':
 'A': CDS_PINID='A';
NODE_NAME     PL120 2
 '@S9S_MB_2U_LIB.S9S_MB_2U(SCH_1):PAGE268_I29@PURE_QUANTA.Q_INDUCTOR(CHIPS)':
 '2': CDS_PINID='\2\';
NODE_NAME     PC1276 1
 '@S9S_MB_2U_LIB.S9S_MB_2U(SCH_1):PAGE268_I37@PURE_QUANTA.Q_CAP(CHIPS)':
 'A': CDS_PINID='A';
NODE_NAME     PC1277 1
 '@S9S_MB_2U_LIB.S9S_MB_2U(SCH_1):PAGE268_I38@PURE_QUANTA.Q_CAP(CHIPS)':
 'A': CDS_PINID='A';
NODE_NAME     PC1206 1
 '@S9S_MB_2U_LIB.S9S_MB_2U(SCH_1):PAGE268_I47@PURE_QUANTA.Q_CAP(CHIPS)':
 'A': CDS_PINID='A';
NET_NAME
'PVNN_MAIN_CPU0_CS'
 '@S9S_MB_2U_LIB.S9S_MB_2U(SCH_1):PVNN_MAIN_CPU0_CS':
 C_SIGNAL='@s9s_mb_2u_lib.s9s_mb_2u(sch_1):pvnn_main_cpu0_cs';
NODE_NAME     PR1303 1
 '@S9S_MB_2U_LIB.S9S_MB_2U(SCH_1):PAGE268_I21@PURE_QUANTA.Q_RES(CHIPS)':
 'A': CDS_PINID='A';
NODE_NAME     PU81 4
 '@S9S_MB_2U_LIB.S9S_MB_2U(SCH_1):PAGE268_I22@PURE_QUANTA.RS53317LR(CHIPS)':
 'CS': CDS_PINID='CS';
NET_NAME
'PVNN_MAIN_CPU0_FB'
 '@S9S_MB_2U_LIB.S9S_MB_2U(SCH_1):PVNN_MAIN_CPU0_FB':
 C_SIGNAL='@s9s_mb_2u_lib.s9s_mb_2u(sch_1):pvnn_main_cpu0_fb';
NODE_NAME     PR501 1
 '@S9S_MB_2U_LIB.S9S_MB_2U(SCH_1):PAGE268_I36@PURE_QUANTA.Q_RES(CHIPS)':
 'A': CDS_PINID='A';
NODE_NAME     PC237 1
 '@S9S_MB_2U_LIB.S9S_MB_2U(SCH_1):PAGE268_I35@PURE_QUANTA.Q_CAP(CHIPS)':
 'A': CDS_PINID='A';
NODE_NAME     PR50 1
 '@S9S_MB_2U_LIB.S9S_MB_2U(SCH_1):PAGE268_I28@PURE_QUANTA.Q_RES(CHIPS)':
 'A': CDS_PINID='A';
NODE_NAME     PU81 6
 '@S9S_MB_2U_LIB.S9S_MB_2U(SCH_1):PAGE268_I22@PURE_QUANTA.RS53317LR(CHIPS)':
 'FB': CDS_PINID='FB';
NET_NAME
'PVNN_MAIN_CPU0_FB_RC'
 '@S9S_MB_2U_LIB.S9S_MB_2U(SCH_1):PVNN_MAIN_CPU0_FB_RC':
 C_SIGNAL='@s9s_mb_2u_lib.s9s_mb_2u(sch_1):pvnn_main_cpu0_fb_rc';
NODE_NAME     PR501 2
 '@S9S_MB_2U_LIB.S9S_MB_2U(SCH_1):PAGE268_I36@PURE_QUANTA.Q_RES(CHIPS)':
 'B': CDS_PINID='B';
NODE_NAME     PR4698 1
 '@S9S_MB_2U_LIB.S9S_MB_2U(SCH_1):PAGE268_I40@PURE_QUANTA.Q_RES(CHIPS)':
 'A': CDS_PINID='A';
NODE_NAME     PC237 2
 '@S9S_MB_2U_LIB.S9S_MB_2U(SCH_1):PAGE268_I35@PURE_QUANTA.Q_CAP(CHIPS)':
 'B': CDS_PINID='B';
NODE_NAME     PC1420 1
 '@S9S_MB_2U_LIB.S9S_MB_2U(SCH_1):PAGE268_I39@PURE_QUANTA.Q_CAP(CHIPS)':
 'A': CDS_PINID='A';
NODE_NAME     PR4683 1
 '@S9S_MB_2U_LIB.S9S_MB_2U(SCH_1):PAGE268_I41@PURE_QUANTA.Q_RES(CHIPS)':
 'A': CDS_PINID='A';
NET_NAME
'PVNN_MAIN_CPU0_MODE'
 '@S9S_MB_2U_LIB.S9S_MB_2U(SCH_1):PVNN_MAIN_CPU0_MODE':
 C_SIGNAL='@s9s_mb_2u_lib.s9s_mb_2u(sch_1):pvnn_main_cpu0_mode';
NODE_NAME     PR1301 1
 '@S9S_MB_2U_LIB.S9S_MB_2U(SCH_1):PAGE268_I9@PURE_QUANTA.Q_RES(CHIPS)':
 'A': CDS_PINID='A';
NODE_NAME     PU81 12
 '@S9S_MB_2U_LIB.S9S_MB_2U(SCH_1):PAGE268_I22@PURE_QUANTA.RS53317LR(CHIPS)':
 'MODE': CDS_PINID='MODE';
NET_NAME
'PVNN_MAIN_CPU0_REF'
 '@S9S_MB_2U_LIB.S9S_MB_2U(SCH_1):PVNN_MAIN_CPU0_REF':
 C_SIGNAL='@s9s_mb_2u_lib.s9s_mb_2u(sch_1):pvnn_main_cpu0_ref';
NODE_NAME     PC27 1
 '@S9S_MB_2U_LIB.S9S_MB_2U(SCH_1):PAGE268_I25@PURE_QUANTA.Q_CAP(CHIPS)':
 'A': CDS_PINID='A';
NODE_NAME     PU81 8
 '@S9S_MB_2U_LIB.S9S_MB_2U(SCH_1):PAGE268_I22@PURE_QUANTA.RS53317LR(CHIPS)':
 'REF': CDS_PINID='REF';
NET_NAME
'PVNN_MAIN_CPU0_VCC'
 '@S9S_MB_2U_LIB.S9S_MB_2U(SCH_1):PVNN_MAIN_CPU0_VCC':
 C_SIGNAL='@s9s_mb_2u_lib.s9s_mb_2u(sch_1):pvnn_main_cpu0_vcc';
NODE_NAME     PR3339 2
 '@S9S_MB_2U_LIB.S9S_MB_2U(SCH_1):PAGE268_I10@PURE_QUANTA.Q_RES(CHIPS)':
 'B': CDS_PINID='B';
NODE_NAME     PC2221 1
 '@S9S_MB_2U_LIB.S9S_MB_2U(SCH_1):PAGE268_I7@PURE_QUANTA.Q_CAP(CHIPS)':
 'A': CDS_PINID='A';
NODE_NAME     PU81 13
 '@S9S_MB_2U_LIB.S9S_MB_2U(SCH_1):PAGE268_I22@PURE_QUANTA.RS53317LR(CHIPS)':
 'VCC': CDS_PINID='VCC';
NET_NAME
'PVNN_MAIN_CPU1'
 '@S9S_MB_2U_LIB.S9S_MB_2U(SCH_1):PVNN_MAIN_CPU1':
 C_SIGNAL='@s9s_mb_2u_lib.s9s_mb_2u(sch_1):pvnn_main_cpu1',
 CDS_GLOBAL_NET='TRUE';
NODE_NAME     U1 BA19
 '@S9S_MB_2U_LIB.S9S_MB_2U(SCH_1):PAGE68_I8@PURE_QUANTA.SOCKET4677_AZIF0045P001C01CS(CHIPS)':
 'VCCVNN0': CDS_PINID='VCCVNN0';
NODE_NAME     U1 BE19
 '@S9S_MB_2U_LIB.S9S_MB_2U(SCH_1):PAGE68_I8@PURE_QUANTA.SOCKET4677_AZIF0045P001C01CS(CHIPS)':
 'VCCVNN1': CDS_PINID='VCCVNN1';
NODE_NAME     U1 BJ19
 '@S9S_MB_2U_LIB.S9S_MB_2U(SCH_1):PAGE68_I8@PURE_QUANTA.SOCKET4677_AZIF0045P001C01CS(CHIPS)':
 'VCCVNN2': CDS_PINID='VCCVNN2';
NODE_NAME     U1 BN19
 '@S9S_MB_2U_LIB.S9S_MB_2U(SCH_1):PAGE68_I8@PURE_QUANTA.SOCKET4677_AZIF0045P001C01CS(CHIPS)':
 'VCCVNN3': CDS_PINID='VCCVNN3';
NODE_NAME     C1391 1
 '@S9S_MB_2U_LIB.S9S_MB_2U(SCH_1):PAGE78_I52@PURE_QUANTA.Q_CAP(CHIPS)':
 'A': CDS_PINID='A';
NODE_NAME     C1365 1
 '@S9S_MB_2U_LIB.S9S_MB_2U(SCH_1):PAGE80_I20@PURE_QUANTA.Q_CAP(CHIPS)':
 'A': CDS_PINID='A';
NODE_NAME     C1366 1
 '@S9S_MB_2U_LIB.S9S_MB_2U(SCH_1):PAGE80_I28@PURE_QUANTA.Q_CAP(CHIPS)':
 'A': CDS_PINID='A';
NODE_NAME     C310 1
 '@S9S_MB_2U_LIB.S9S_MB_2U(SCH_1):PAGE77_I70@PURE_QUANTA.Q_CAP(CHIPS)':
 'A': CDS_PINID='A';
NODE_NAME     C1387 1
 '@S9S_MB_2U_LIB.S9S_MB_2U(SCH_1):PAGE78_I49@PURE_QUANTA.Q_CAP(CHIPS)':
 'A': CDS_PINID='A';
NODE_NAME     C1389 1
 '@S9S_MB_2U_LIB.S9S_MB_2U(SCH_1):PAGE78_I51@PURE_QUANTA.Q_CAP(CHIPS)':
 'A': CDS_PINID='A';
NODE_NAME     C1393 1
 '@S9S_MB_2U_LIB.S9S_MB_2U(SCH_1):PAGE78_I57@PURE_QUANTA.Q_CAP(CHIPS)':
 'A': CDS_PINID='A';
NODE_NAME     C1403 1
 '@S9S_MB_2U_LIB.S9S_MB_2U(SCH_1):PAGE79_I43@PURE_QUANTA.Q_CAP(CHIPS)':
 'A': CDS_PINID='A';
NODE_NAME     C1404 1
 '@S9S_MB_2U_LIB.S9S_MB_2U(SCH_1):PAGE79_I44@PURE_QUANTA.Q_CAP(CHIPS)':
 'A': CDS_PINID='A';
NODE_NAME     C1353 1
 '@S9S_MB_2U_LIB.S9S_MB_2U(SCH_1):PAGE79_I49@PURE_QUANTA.Q_CAP(CHIPS)':
 'A': CDS_PINID='A';
NODE_NAME     R330 1
 '@S9S_MB_2U_LIB.S9S_MB_2U(SCH_1):PAGE80_I34@PURE_QUANTA.Q_RES(CHIPS)':
 'A': CDS_PINID='A';
NODE_NAME     PL121 2
 '@S9S_MB_2U_LIB.S9S_MB_2U(SCH_1):PAGE286_I27@PURE_QUANTA.Q_INDUCTOR(CHIPS)':
 '2': CDS_PINID='\2\';
NODE_NAME     PR4700 2
 '@S9S_MB_2U_LIB.S9S_MB_2U(SCH_1):PAGE286_I42@PURE_QUANTA.Q_RES(CHIPS)':
 'B': CDS_PINID='B';
NODE_NAME     PC1287 1
 '@S9S_MB_2U_LIB.S9S_MB_2U(SCH_1):PAGE286_I44@PURE_QUANTA.Q_CAP(CHIPS)':
 'A': CDS_PINID='A';
NODE_NAME     PC1285 1
 '@S9S_MB_2U_LIB.S9S_MB_2U(SCH_1):PAGE286_I36@PURE_QUANTA.Q_CAP(CHIPS)':
 'A': CDS_PINID='A';
NODE_NAME     PC1286 1
 '@S9S_MB_2U_LIB.S9S_MB_2U(SCH_1):PAGE286_I38@PURE_QUANTA.Q_CAP(CHIPS)':
 'A': CDS_PINID='A';
NODE_NAME     PR4699 2
 '@S9S_MB_2U_LIB.S9S_MB_2U(SCH_1):PAGE286_I43@PURE_QUANTA.Q_RES(CHIPS)':
 'B': CDS_PINID='B';
NODE_NAME     PC1284 1
 '@S9S_MB_2U_LIB.S9S_MB_2U(SCH_1):PAGE286_I28@PURE_QUANTA.Q_CAP(CHIPS)':
 'A': CDS_PINID='A';
NODE_NAME     PC1207 1
 '@S9S_MB_2U_LIB.S9S_MB_2U(SCH_1):PAGE286_I45@PURE_QUANTA.Q_CAP(CHIPS)':
 'A': CDS_PINID='A';
NET_NAME
'PVNN_MAIN_CPU1_CS'
 '@S9S_MB_2U_LIB.S9S_MB_2U(SCH_1):PVNN_MAIN_CPU1_CS':
 C_SIGNAL='@s9s_mb_2u_lib.s9s_mb_2u(sch_1):pvnn_main_cpu1_cs';
NODE_NAME     PU82 4
 '@S9S_MB_2U_LIB.S9S_MB_2U(SCH_1):PAGE286_I20@PURE_QUANTA.RS53317LR(CHIPS)':
 'CS': CDS_PINID='CS';
NODE_NAME     PR2222 1
 '@S9S_MB_2U_LIB.S9S_MB_2U(SCH_1):PAGE286_I19@PURE_QUANTA.Q_RES(CHIPS)':
 'A': CDS_PINID='A';
NET_NAME
'PVNN_MAIN_CPU1_FB'
 '@S9S_MB_2U_LIB.S9S_MB_2U(SCH_1):PVNN_MAIN_CPU1_FB':
 C_SIGNAL='@s9s_mb_2u_lib.s9s_mb_2u(sch_1):pvnn_main_cpu1_fb';
NODE_NAME     PR51 1
 '@S9S_MB_2U_LIB.S9S_MB_2U(SCH_1):PAGE286_I26@PURE_QUANTA.Q_RES(CHIPS)':
 'A': CDS_PINID='A';
NODE_NAME     PU82 6
 '@S9S_MB_2U_LIB.S9S_MB_2U(SCH_1):PAGE286_I20@PURE_QUANTA.RS53317LR(CHIPS)':
 'FB': CDS_PINID='FB';
NODE_NAME     PR502 1
 '@S9S_MB_2U_LIB.S9S_MB_2U(SCH_1):PAGE286_I34@PURE_QUANTA.Q_RES(CHIPS)':
 'A': CDS_PINID='A';
NODE_NAME     PC238 1
 '@S9S_MB_2U_LIB.S9S_MB_2U(SCH_1):PAGE286_I33@PURE_QUANTA.Q_CAP(CHIPS)':
 'A': CDS_PINID='A';
NET_NAME
'PVNN_MAIN_CPU1_FB_RC'
 '@S9S_MB_2U_LIB.S9S_MB_2U(SCH_1):PVNN_MAIN_CPU1_FB_RC':
 C_SIGNAL='@s9s_mb_2u_lib.s9s_mb_2u(sch_1):pvnn_main_cpu1_fb_rc';
NODE_NAME     PR4700 1
 '@S9S_MB_2U_LIB.S9S_MB_2U(SCH_1):PAGE286_I42@PURE_QUANTA.Q_RES(CHIPS)':
 'A': CDS_PINID='A';
NODE_NAME     PR502 2
 '@S9S_MB_2U_LIB.S9S_MB_2U(SCH_1):PAGE286_I34@PURE_QUANTA.Q_RES(CHIPS)':
 'B': CDS_PINID='B';
NODE_NAME     PC238 2
 '@S9S_MB_2U_LIB.S9S_MB_2U(SCH_1):PAGE286_I33@PURE_QUANTA.Q_CAP(CHIPS)':
 'B': CDS_PINID='B';
NODE_NAME     PR4699 1
 '@S9S_MB_2U_LIB.S9S_MB_2U(SCH_1):PAGE286_I43@PURE_QUANTA.Q_RES(CHIPS)':
 'A': CDS_PINID='A';
NODE_NAME     PC2277 1
 '@S9S_MB_2U_LIB.S9S_MB_2U(SCH_1):PAGE286_I40@PURE_QUANTA.Q_CAP(CHIPS)':
 'A': CDS_PINID='A';
NET_NAME
'PVNN_MAIN_CPU1_MODE'
 '@S9S_MB_2U_LIB.S9S_MB_2U(SCH_1):PVNN_MAIN_CPU1_MODE':
 C_SIGNAL='@s9s_mb_2u_lib.s9s_mb_2u(sch_1):pvnn_main_cpu1_mode';
NODE_NAME     PU82 12
 '@S9S_MB_2U_LIB.S9S_MB_2U(SCH_1):PAGE286_I20@PURE_QUANTA.RS53317LR(CHIPS)':
 'MODE': CDS_PINID='MODE';
NODE_NAME     PR2220 1
 '@S9S_MB_2U_LIB.S9S_MB_2U(SCH_1):PAGE286_I12@PURE_QUANTA.Q_RES(CHIPS)':
 'A': CDS_PINID='A';
NET_NAME
'PVNN_MAIN_CPU1_REF'
 '@S9S_MB_2U_LIB.S9S_MB_2U(SCH_1):PVNN_MAIN_CPU1_REF':
 C_SIGNAL='@s9s_mb_2u_lib.s9s_mb_2u(sch_1):pvnn_main_cpu1_ref';
NODE_NAME     PC28 1
 '@S9S_MB_2U_LIB.S9S_MB_2U(SCH_1):PAGE286_I23@PURE_QUANTA.Q_CAP(CHIPS)':
 'A': CDS_PINID='A';
NODE_NAME     PU82 8
 '@S9S_MB_2U_LIB.S9S_MB_2U(SCH_1):PAGE286_I20@PURE_QUANTA.RS53317LR(CHIPS)':
 'REF': CDS_PINID='REF';
NET_NAME
'PVNN_MAIN_CPU1_VCC'
 '@S9S_MB_2U_LIB.S9S_MB_2U(SCH_1):PVNN_MAIN_CPU1_VCC':
 C_SIGNAL='@s9s_mb_2u_lib.s9s_mb_2u(sch_1):pvnn_main_cpu1_vcc';
NODE_NAME     PR3338 2
 '@S9S_MB_2U_LIB.S9S_MB_2U(SCH_1):PAGE286_I13@PURE_QUANTA.Q_RES(CHIPS)':
 'B': CDS_PINID='B';
NODE_NAME     PU82 13
 '@S9S_MB_2U_LIB.S9S_MB_2U(SCH_1):PAGE286_I20@PURE_QUANTA.RS53317LR(CHIPS)':
 'VCC': CDS_PINID='VCC';
NODE_NAME     PC2222 1
 '@S9S_MB_2U_LIB.S9S_MB_2U(SCH_1):PAGE286_I10@PURE_QUANTA.Q_CAP(CHIPS)':
 'A': CDS_PINID='A';
NET_NAME
'PVNN_TERM_CPU0'
 '@S9S_MB_2U_LIB.S9S_MB_2U(SCH_1):PVNN_TERM_CPU0':
 C_SIGNAL='@s9s_mb_2u_lib.s9s_mb_2u(sch_1):pvnn_term_cpu0',
 CDS_GLOBAL_NET='TRUE';
NODE_NAME     R328 2
 '@S9S_MB_2U_LIB.S9S_MB_2U(SCH_1):PAGE14_I93@PURE_QUANTA.Q_RES(CHIPS)':
 'B': CDS_PINID='B';
NODE_NAME     R548 2
 '@S9S_MB_2U_LIB.S9S_MB_2U(SCH_1):PAGE14_I94@PURE_QUANTA.Q_RES(CHIPS)':
 'B': CDS_PINID='B';
NODE_NAME     R555 2
 '@S9S_MB_2U_LIB.S9S_MB_2U(SCH_1):PAGE14_I98@PURE_QUANTA.Q_RES(CHIPS)':
 'B': CDS_PINID='B';
NODE_NAME     R556 2
 '@S9S_MB_2U_LIB.S9S_MB_2U(SCH_1):PAGE14_I100@PURE_QUANTA.Q_RES(CHIPS)':
 'B': CDS_PINID='B';
NODE_NAME     R18 1
 '@S9S_MB_2U_LIB.S9S_MB_2U(SCH_1):PAGE16_I35@PURE_QUANTA.Q_RES(CHIPS)':
 'A': CDS_PINID='A';
NODE_NAME     R19 1
 '@S9S_MB_2U_LIB.S9S_MB_2U(SCH_1):PAGE16_I36@PURE_QUANTA.Q_RES(CHIPS)':
 'A': CDS_PINID='A';
NODE_NAME     R1242 1
 '@S9S_MB_2U_LIB.S9S_MB_2U(SCH_1):PAGE117_I13@PURE_QUANTA.Q_RES(CHIPS)':
 'A': CDS_PINID='A';
NODE_NAME     R296 1
 '@S9S_MB_2U_LIB.S9S_MB_2U(SCH_1):PAGE118_I65@PURE_QUANTA.Q_RES(CHIPS)':
 'A': CDS_PINID='A';
NODE_NAME     R301 1
 '@S9S_MB_2U_LIB.S9S_MB_2U(SCH_1):PAGE118_I73@PURE_QUANTA.Q_RES(CHIPS)':
 'A': CDS_PINID='A';
NODE_NAME     R282 1
 '@S9S_MB_2U_LIB.S9S_MB_2U(SCH_1):PAGE119_I53@PURE_QUANTA.Q_RES(CHIPS)':
 'A': CDS_PINID='A';
NODE_NAME     R279 1
 '@S9S_MB_2U_LIB.S9S_MB_2U(SCH_1):PAGE119_I54@PURE_QUANTA.Q_RES(CHIPS)':
 'A': CDS_PINID='A';
NODE_NAME     R280 1
 '@S9S_MB_2U_LIB.S9S_MB_2U(SCH_1):PAGE119_I57@PURE_QUANTA.Q_RES(CHIPS)':
 'A': CDS_PINID='A';
NODE_NAME     R281 1
 '@S9S_MB_2U_LIB.S9S_MB_2U(SCH_1):PAGE119_I58@PURE_QUANTA.Q_RES(CHIPS)':
 'A': CDS_PINID='A';
NODE_NAME     R278 1
 '@S9S_MB_2U_LIB.S9S_MB_2U(SCH_1):PAGE119_I61@PURE_QUANTA.Q_RES(CHIPS)':
 'A': CDS_PINID='A';
NODE_NAME     R277 1
 '@S9S_MB_2U_LIB.S9S_MB_2U(SCH_1):PAGE119_I62@PURE_QUANTA.Q_RES(CHIPS)':
 'A': CDS_PINID='A';
NODE_NAME     R276 1
 '@S9S_MB_2U_LIB.S9S_MB_2U(SCH_1):PAGE119_I66@PURE_QUANTA.Q_RES(CHIPS)':
 'A': CDS_PINID='A';
NODE_NAME     R275 1
 '@S9S_MB_2U_LIB.S9S_MB_2U(SCH_1):PAGE119_I68@PURE_QUANTA.Q_RES(CHIPS)':
 'A': CDS_PINID='A';
NODE_NAME     R1009 1
 '@S9S_MB_2U_LIB.S9S_MB_2U(SCH_1):PAGE119_I136@PURE_QUANTA.Q_RES(CHIPS)':
 'A': CDS_PINID='A';
NODE_NAME     R1232 1
 '@S9S_MB_2U_LIB.S9S_MB_2U(SCH_1):PAGE119_I156@PURE_QUANTA.Q_RES(CHIPS)':
 'A': CDS_PINID='A';
NODE_NAME     R1233 1
 '@S9S_MB_2U_LIB.S9S_MB_2U(SCH_1):PAGE119_I158@PURE_QUANTA.Q_RES(CHIPS)':
 'A': CDS_PINID='A';
NODE_NAME     R292 1
 '@S9S_MB_2U_LIB.S9S_MB_2U(SCH_1):PAGE119_I196@PURE_QUANTA.Q_RES(CHIPS)':
 'A': CDS_PINID='A';
NODE_NAME     R249 1
 '@S9S_MB_2U_LIB.S9S_MB_2U(SCH_1):PAGE120_I27@PURE_QUANTA.Q_RES(CHIPS)':
 'A': CDS_PINID='A';
NODE_NAME     R251 1
 '@S9S_MB_2U_LIB.S9S_MB_2U(SCH_1):PAGE120_I28@PURE_QUANTA.Q_RES(CHIPS)':
 'A': CDS_PINID='A';
NODE_NAME     R250 1
 '@S9S_MB_2U_LIB.S9S_MB_2U(SCH_1):PAGE120_I29@PURE_QUANTA.Q_RES(CHIPS)':
 'A': CDS_PINID='A';
NODE_NAME     R252 1
 '@S9S_MB_2U_LIB.S9S_MB_2U(SCH_1):PAGE120_I30@PURE_QUANTA.Q_RES(CHIPS)':
 'A': CDS_PINID='A';
NODE_NAME     R253 1
 '@S9S_MB_2U_LIB.S9S_MB_2U(SCH_1):PAGE120_I31@PURE_QUANTA.Q_RES(CHIPS)':
 'A': CDS_PINID='A';
NODE_NAME     R254 1
 '@S9S_MB_2U_LIB.S9S_MB_2U(SCH_1):PAGE120_I32@PURE_QUANTA.Q_RES(CHIPS)':
 'A': CDS_PINID='A';
NODE_NAME     R185 2
 '@S9S_MB_2U_LIB.S9S_MB_2U(SCH_1):PAGE124_I60@PURE_QUANTA.Q_RES(CHIPS)':
 'B': CDS_PINID='B';
NODE_NAME     R183 2
 '@S9S_MB_2U_LIB.S9S_MB_2U(SCH_1):PAGE124_I62@PURE_QUANTA.Q_RES(CHIPS)':
 'B': CDS_PINID='B';
NODE_NAME     R96 1
 '@S9S_MB_2U_LIB.S9S_MB_2U(SCH_1):PAGE126_I22@PURE_QUANTA.Q_RES(CHIPS)':
 'A': CDS_PINID='A';
NODE_NAME     R95 1
 '@S9S_MB_2U_LIB.S9S_MB_2U(SCH_1):PAGE126_I23@PURE_QUANTA.Q_RES(CHIPS)':
 'A': CDS_PINID='A';
NODE_NAME     R94 1
 '@S9S_MB_2U_LIB.S9S_MB_2U(SCH_1):PAGE126_I25@PURE_QUANTA.Q_RES(CHIPS)':
 'A': CDS_PINID='A';
NODE_NAME     R97 1
 '@S9S_MB_2U_LIB.S9S_MB_2U(SCH_1):PAGE126_I114@PURE_QUANTA.Q_RES(CHIPS)':
 'A': CDS_PINID='A';
NODE_NAME     R779 1
 '@S9S_MB_2U_LIB.S9S_MB_2U(SCH_1):PAGE133_I95@PURE_QUANTA.Q_RES(CHIPS)':
 'A': CDS_PINID='A';
NODE_NAME     R757 1
 '@S9S_MB_2U_LIB.S9S_MB_2U(SCH_1):PAGE134_I166@PURE_QUANTA.Q_RES(CHIPS)':
 'A': CDS_PINID='A';
NODE_NAME     R758 1
 '@S9S_MB_2U_LIB.S9S_MB_2U(SCH_1):PAGE134_I168@PURE_QUANTA.Q_RES(CHIPS)':
 'A': CDS_PINID='A';
NODE_NAME     R759 1
 '@S9S_MB_2U_LIB.S9S_MB_2U(SCH_1):PAGE134_I169@PURE_QUANTA.Q_RES(CHIPS)':
 'A': CDS_PINID='A';
NODE_NAME     R760 1
 '@S9S_MB_2U_LIB.S9S_MB_2U(SCH_1):PAGE134_I174@PURE_QUANTA.Q_RES(CHIPS)':
 'A': CDS_PINID='A';
NODE_NAME     R761 1
 '@S9S_MB_2U_LIB.S9S_MB_2U(SCH_1):PAGE134_I175@PURE_QUANTA.Q_RES(CHIPS)':
 'A': CDS_PINID='A';
NODE_NAME     R741 1
 '@S9S_MB_2U_LIB.S9S_MB_2U(SCH_1):PAGE135_I66@PURE_QUANTA.Q_RES(CHIPS)':
 'A': CDS_PINID='A';
NODE_NAME     R744 1
 '@S9S_MB_2U_LIB.S9S_MB_2U(SCH_1):PAGE135_I77@PURE_QUANTA.Q_RES(CHIPS)':
 'A': CDS_PINID='A';
NODE_NAME     R1486 1
 '@S9S_MB_2U_LIB.S9S_MB_2U(SCH_1):PAGE174_I74@PURE_QUANTA.Q_RES(CHIPS)':
 'A': CDS_PINID='A';
NODE_NAME     R1485 1
 '@S9S_MB_2U_LIB.S9S_MB_2U(SCH_1):PAGE174_I75@PURE_QUANTA.Q_RES(CHIPS)':
 'A': CDS_PINID='A';
NODE_NAME     R145 1
 '@S9S_MB_2U_LIB.S9S_MB_2U(SCH_1):PAGE185_I26@PURE_QUANTA.Q_RES(CHIPS)':
 'A': CDS_PINID='A';
NODE_NAME     R146 1
 '@S9S_MB_2U_LIB.S9S_MB_2U(SCH_1):PAGE185_I30@PURE_QUANTA.Q_RES(CHIPS)':
 'A': CDS_PINID='A';
NODE_NAME     R679 1
 '@S9S_MB_2U_LIB.S9S_MB_2U(SCH_1):PAGE217_I29@PURE_QUANTA.Q_RES(CHIPS)':
 'A': CDS_PINID='A';
NODE_NAME     R1006 1
 '@S9S_MB_2U_LIB.S9S_MB_2U(SCH_1):PAGE223_I8@PURE_QUANTA.Q_RES(CHIPS)':
 'A': CDS_PINID='A';
NODE_NAME     C559 1
 '@S9S_MB_2U_LIB.S9S_MB_2U(SCH_1):PAGE223_I20@PURE_QUANTA.Q_CAP(CHIPS)':
 'A': CDS_PINID='A';
NODE_NAME     R911 1
 '@S9S_MB_2U_LIB.S9S_MB_2U(SCH_1):PAGE223_I22@PURE_QUANTA.Q_RES(CHIPS)':
 'A': CDS_PINID='A';
NODE_NAME     R910 1
 '@S9S_MB_2U_LIB.S9S_MB_2U(SCH_1):PAGE223_I24@PURE_QUANTA.Q_RES(CHIPS)':
 'A': CDS_PINID='A';
NODE_NAME     U28 1
 '@S9S_MB_2U_LIB.S9S_MB_2U(SCH_1):PAGE223_I39@PURE_QUANTA.PCA9617ADP(CHIPS)':
 'VCCA': CDS_PINID='VCCA';
NODE_NAME     C567 1
 '@S9S_MB_2U_LIB.S9S_MB_2U(SCH_1):PAGE224_I25@PURE_QUANTA.Q_CAP(CHIPS)':
 'A': CDS_PINID='A';
NODE_NAME     U30 1
 '@S9S_MB_2U_LIB.S9S_MB_2U(SCH_1):PAGE224_I28@PURE_QUANTA.PCA9517AD(CHIPS)':
 'VCCA': CDS_PINID='VCCA';
NODE_NAME     R971 1
 '@S9S_MB_2U_LIB.S9S_MB_2U(SCH_1):PAGE224_I42@PURE_QUANTA.Q_RES(CHIPS)':
 'A': CDS_PINID='A';
NODE_NAME     R969 1
 '@S9S_MB_2U_LIB.S9S_MB_2U(SCH_1):PAGE224_I43@PURE_QUANTA.Q_RES(CHIPS)':
 'A': CDS_PINID='A';
NODE_NAME     R2386 1
 '@S9S_MB_2U_LIB.S9S_MB_2U(SCH_1):PAGE260_I37@PURE_QUANTA.Q_RES(CHIPS)':
 'A': CDS_PINID='A';
NODE_NAME     R324 2
 '@S9S_MB_2U_LIB.S9S_MB_2U(SCH_1):PAGE80_I12@PURE_QUANTA.Q_RES(CHIPS)':
 'B': CDS_PINID='B';
NODE_NAME     R323 2
 '@S9S_MB_2U_LIB.S9S_MB_2U(SCH_1):PAGE80_I13@PURE_QUANTA.Q_RES(CHIPS)':
 'B': CDS_PINID='B';
NODE_NAME     R2322 1
 '@S9S_MB_2U_LIB.S9S_MB_2U(SCH_1):PAGE260_I36@PURE_QUANTA.Q_RES(CHIPS)':
 'A': CDS_PINID='A';
NODE_NAME     R1717 1
 '@S9S_MB_2U_LIB.S9S_MB_2U(SCH_1):PAGE264_I25@PURE_QUANTA.Q_RES(CHIPS)':
 'A': CDS_PINID='A';
NODE_NAME     R4262 1
 '@S9S_MB_2U_LIB.S9S_MB_2U(SCH_1):PAGE119_I215@PURE_QUANTA.Q_RES(CHIPS)':
 'A': CDS_PINID='A';
NODE_NAME     R4260 1
 '@S9S_MB_2U_LIB.S9S_MB_2U(SCH_1):PAGE119_I219@PURE_QUANTA.Q_RES(CHIPS)':
 'A': CDS_PINID='A';
NODE_NAME     R288 1
 '@S9S_MB_2U_LIB.S9S_MB_2U(SCH_1):PAGE119_I224@PURE_QUANTA.Q_RES(CHIPS)':
 'A': CDS_PINID='A';
NODE_NAME     R4390 1
 '@S9S_MB_2U_LIB.S9S_MB_2U(SCH_1):PAGE322_I169@PURE_QUANTA.Q_RES(CHIPS)':
 'A': CDS_PINID='A';
NODE_NAME     R4388 1
 '@S9S_MB_2U_LIB.S9S_MB_2U(SCH_1):PAGE322_I174@PURE_QUANTA.Q_RES(CHIPS)':
 'A': CDS_PINID='A';
NODE_NAME     R4389 1
 '@S9S_MB_2U_LIB.S9S_MB_2U(SCH_1):PAGE322_I177@PURE_QUANTA.Q_RES(CHIPS)':
 'A': CDS_PINID='A';
NODE_NAME     R2382 2
 '@S9S_MB_2U_LIB.S9S_MB_2U(SCH_1):PAGE252_I123@PURE_QUANTA.Q_RES(CHIPS)':
 'B': CDS_PINID='B';
NODE_NAME     C2443 1
 '@S9S_MB_2U_LIB.S9S_MB_2U(SCH_1):PAGE264_I18@PURE_QUANTA.Q_CAP(CHIPS)':
 'A': CDS_PINID='A';
NODE_NAME     C2444 1
 '@S9S_MB_2U_LIB.S9S_MB_2U(SCH_1):PAGE264_I19@PURE_QUANTA.Q_CAP(CHIPS)':
 'A': CDS_PINID='A';
NODE_NAME     R1735 1
 '@S9S_MB_2U_LIB.S9S_MB_2U(SCH_1):PAGE264_I24@PURE_QUANTA.Q_RES(CHIPS)':
 'A': CDS_PINID='A';
NODE_NAME     R2590 2
 '@S9S_MB_2U_LIB.S9S_MB_2U(SCH_1):PAGE252_I124@PURE_QUANTA.Q_RES(CHIPS)':
 'B': CDS_PINID='B';
NODE_NAME     R2381 2
 '@S9S_MB_2U_LIB.S9S_MB_2U(SCH_1):PAGE252_I125@PURE_QUANTA.Q_RES(CHIPS)':
 'B': CDS_PINID='B';
NODE_NAME     C3270 1
 '@S9S_MB_2U_LIB.S9S_MB_2U(SCH_1):PAGE252_I127@PURE_QUANTA.Q_CAP(CHIPS)':
 'A': CDS_PINID='A';
NODE_NAME     C3271 1
 '@S9S_MB_2U_LIB.S9S_MB_2U(SCH_1):PAGE252_I128@PURE_QUANTA.Q_CAP(CHIPS)':
 'A': CDS_PINID='A';
NODE_NAME     R680 1
 '@S9S_MB_2U_LIB.S9S_MB_2U(SCH_1):PAGE217_I30@PURE_QUANTA.Q_RES(CHIPS)':
 'A': CDS_PINID='A';
NODE_NAME     R681 1
 '@S9S_MB_2U_LIB.S9S_MB_2U(SCH_1):PAGE217_I32@PURE_QUANTA.Q_RES(CHIPS)':
 'A': CDS_PINID='A';
NODE_NAME     R686 1
 '@S9S_MB_2U_LIB.S9S_MB_2U(SCH_1):PAGE217_I33@PURE_QUANTA.Q_RES(CHIPS)':
 'A': CDS_PINID='A';
NODE_NAME     R4395 1
 '@S9S_MB_2U_LIB.S9S_MB_2U(SCH_1):PAGE121_I13@PURE_QUANTA.Q_RES(CHIPS)':
 'A': CDS_PINID='A';
NODE_NAME     Q138 4
 '@S9S_MB_2U_LIB.S9S_MB_2U(SCH_1):PAGE121_I17@PURE_QUANTA.BC847BPN(CHIPS)':
 'E2': CDS_PINID='E2';
NODE_NAME     R243 1
 '@S9S_MB_2U_LIB.S9S_MB_2U(SCH_1):PAGE121_I23@PURE_QUANTA.Q_RES(CHIPS)':
 'A': CDS_PINID='A';
NODE_NAME     R4401 1
 '@S9S_MB_2U_LIB.S9S_MB_2U(SCH_1):PAGE122_I8@PURE_QUANTA.Q_RES(CHIPS)':
 'A': CDS_PINID='A';
NODE_NAME     Q143 4
 '@S9S_MB_2U_LIB.S9S_MB_2U(SCH_1):PAGE122_I12@PURE_QUANTA.BC847BPN(CHIPS)':
 'E2': CDS_PINID='E2';
NODE_NAME     R219 1
 '@S9S_MB_2U_LIB.S9S_MB_2U(SCH_1):PAGE122_I37@PURE_QUANTA.Q_RES(CHIPS)':
 'A': CDS_PINID='A';
NODE_NAME     Q141 4
 '@S9S_MB_2U_LIB.S9S_MB_2U(SCH_1):PAGE123_I12@PURE_QUANTA.BC847BPN(CHIPS)':
 'E2': CDS_PINID='E2';
NODE_NAME     R200 1
 '@S9S_MB_2U_LIB.S9S_MB_2U(SCH_1):PAGE123_I19@PURE_QUANTA.Q_RES(CHIPS)':
 'A': CDS_PINID='A';
NODE_NAME     R197 1
 '@S9S_MB_2U_LIB.S9S_MB_2U(SCH_1):PAGE123_I27@PURE_QUANTA.Q_RES(CHIPS)':
 'A': CDS_PINID='A';
NODE_NAME     C1302 1
 '@S9S_MB_2U_LIB.S9S_MB_2U(SCH_1):PAGE227_I82@PURE_QUANTA.Q_CAP(CHIPS)':
 'A': CDS_PINID='A';
NODE_NAME     R142 1
 '@S9S_MB_2U_LIB.S9S_MB_2U(SCH_1):PAGE227_I84@PURE_QUANTA.Q_RES(CHIPS)':
 'A': CDS_PINID='A';
NET_NAME
'PVNN_TERM_CPU1'
 '@S9S_MB_2U_LIB.S9S_MB_2U(SCH_1):PVNN_TERM_CPU1':
 C_SIGNAL='@s9s_mb_2u_lib.s9s_mb_2u(sch_1):pvnn_term_cpu1',
 CDS_GLOBAL_NET='TRUE';
NODE_NAME     R559 2
 '@S9S_MB_2U_LIB.S9S_MB_2U(SCH_1):PAGE45_I69@PURE_QUANTA.Q_RES(CHIPS)':
 'B': CDS_PINID='B';
NODE_NAME     R560 2
 '@S9S_MB_2U_LIB.S9S_MB_2U(SCH_1):PAGE45_I70@PURE_QUANTA.Q_RES(CHIPS)':
 'B': CDS_PINID='B';
NODE_NAME     R558 2
 '@S9S_MB_2U_LIB.S9S_MB_2U(SCH_1):PAGE45_I73@PURE_QUANTA.Q_RES(CHIPS)':
 'B': CDS_PINID='B';
NODE_NAME     R557 2
 '@S9S_MB_2U_LIB.S9S_MB_2U(SCH_1):PAGE45_I74@PURE_QUANTA.Q_RES(CHIPS)':
 'B': CDS_PINID='B';
NODE_NAME     R49 1
 '@S9S_MB_2U_LIB.S9S_MB_2U(SCH_1):PAGE47_I34@PURE_QUANTA.Q_RES(CHIPS)':
 'A': CDS_PINID='A';
NODE_NAME     R50 1
 '@S9S_MB_2U_LIB.S9S_MB_2U(SCH_1):PAGE47_I35@PURE_QUANTA.Q_RES(CHIPS)':
 'A': CDS_PINID='A';
NODE_NAME     R1244 1
 '@S9S_MB_2U_LIB.S9S_MB_2U(SCH_1):PAGE117_I16@PURE_QUANTA.Q_RES(CHIPS)':
 'A': CDS_PINID='A';
NODE_NAME     R298 1
 '@S9S_MB_2U_LIB.S9S_MB_2U(SCH_1):PAGE118_I67@PURE_QUANTA.Q_RES(CHIPS)':
 'A': CDS_PINID='A';
NODE_NAME     R303 1
 '@S9S_MB_2U_LIB.S9S_MB_2U(SCH_1):PAGE118_I76@PURE_QUANTA.Q_RES(CHIPS)':
 'A': CDS_PINID='A';
NODE_NAME     R268 1
 '@S9S_MB_2U_LIB.S9S_MB_2U(SCH_1):PAGE119_I94@PURE_QUANTA.Q_RES(CHIPS)':
 'A': CDS_PINID='A';
NODE_NAME     R267 1
 '@S9S_MB_2U_LIB.S9S_MB_2U(SCH_1):PAGE119_I95@PURE_QUANTA.Q_RES(CHIPS)':
 'A': CDS_PINID='A';
NODE_NAME     R266 1
 '@S9S_MB_2U_LIB.S9S_MB_2U(SCH_1):PAGE119_I96@PURE_QUANTA.Q_RES(CHIPS)':
 'A': CDS_PINID='A';
NODE_NAME     R265 1
 '@S9S_MB_2U_LIB.S9S_MB_2U(SCH_1):PAGE119_I97@PURE_QUANTA.Q_RES(CHIPS)':
 'A': CDS_PINID='A';
NODE_NAME     R264 1
 '@S9S_MB_2U_LIB.S9S_MB_2U(SCH_1):PAGE119_I98@PURE_QUANTA.Q_RES(CHIPS)':
 'A': CDS_PINID='A';
NODE_NAME     R262 1
 '@S9S_MB_2U_LIB.S9S_MB_2U(SCH_1):PAGE119_I100@PURE_QUANTA.Q_RES(CHIPS)':
 'A': CDS_PINID='A';
NODE_NAME     R261 1
 '@S9S_MB_2U_LIB.S9S_MB_2U(SCH_1):PAGE119_I101@PURE_QUANTA.Q_RES(CHIPS)':
 'A': CDS_PINID='A';
NODE_NAME     R263 1
 '@S9S_MB_2U_LIB.S9S_MB_2U(SCH_1):PAGE119_I125@PURE_QUANTA.Q_RES(CHIPS)':
 'A': CDS_PINID='A';
NODE_NAME     R1008 1
 '@S9S_MB_2U_LIB.S9S_MB_2U(SCH_1):PAGE119_I139@PURE_QUANTA.Q_RES(CHIPS)':
 'A': CDS_PINID='A';
NODE_NAME     R1229 1
 '@S9S_MB_2U_LIB.S9S_MB_2U(SCH_1):PAGE119_I169@PURE_QUANTA.Q_RES(CHIPS)':
 'A': CDS_PINID='A';
NODE_NAME     R1230 1
 '@S9S_MB_2U_LIB.S9S_MB_2U(SCH_1):PAGE119_I170@PURE_QUANTA.Q_RES(CHIPS)':
 'A': CDS_PINID='A';
NODE_NAME     R255 1
 '@S9S_MB_2U_LIB.S9S_MB_2U(SCH_1):PAGE120_I42@PURE_QUANTA.Q_RES(CHIPS)':
 'A': CDS_PINID='A';
NODE_NAME     R257 1
 '@S9S_MB_2U_LIB.S9S_MB_2U(SCH_1):PAGE120_I43@PURE_QUANTA.Q_RES(CHIPS)':
 'A': CDS_PINID='A';
NODE_NAME     R258 1
 '@S9S_MB_2U_LIB.S9S_MB_2U(SCH_1):PAGE120_I44@PURE_QUANTA.Q_RES(CHIPS)':
 'A': CDS_PINID='A';
NODE_NAME     R259 1
 '@S9S_MB_2U_LIB.S9S_MB_2U(SCH_1):PAGE120_I45@PURE_QUANTA.Q_RES(CHIPS)':
 'A': CDS_PINID='A';
NODE_NAME     R260 1
 '@S9S_MB_2U_LIB.S9S_MB_2U(SCH_1):PAGE120_I46@PURE_QUANTA.Q_RES(CHIPS)':
 'A': CDS_PINID='A';
NODE_NAME     R256 1
 '@S9S_MB_2U_LIB.S9S_MB_2U(SCH_1):PAGE120_I48@PURE_QUANTA.Q_RES(CHIPS)':
 'A': CDS_PINID='A';
NODE_NAME     R157 2
 '@S9S_MB_2U_LIB.S9S_MB_2U(SCH_1):PAGE125_I24@PURE_QUANTA.Q_RES(CHIPS)':
 'B': CDS_PINID='B';
NODE_NAME     R155 2
 '@S9S_MB_2U_LIB.S9S_MB_2U(SCH_1):PAGE125_I26@PURE_QUANTA.Q_RES(CHIPS)':
 'B': CDS_PINID='B';
NODE_NAME     R90 1
 '@S9S_MB_2U_LIB.S9S_MB_2U(SCH_1):PAGE126_I135@PURE_QUANTA.Q_RES(CHIPS)':
 'A': CDS_PINID='A';
NODE_NAME     R91 1
 '@S9S_MB_2U_LIB.S9S_MB_2U(SCH_1):PAGE126_I136@PURE_QUANTA.Q_RES(CHIPS)':
 'A': CDS_PINID='A';
NODE_NAME     R92 1
 '@S9S_MB_2U_LIB.S9S_MB_2U(SCH_1):PAGE126_I140@PURE_QUANTA.Q_RES(CHIPS)':
 'A': CDS_PINID='A';
NODE_NAME     R93 1
 '@S9S_MB_2U_LIB.S9S_MB_2U(SCH_1):PAGE126_I141@PURE_QUANTA.Q_RES(CHIPS)':
 'A': CDS_PINID='A';
NODE_NAME     R743 1
 '@S9S_MB_2U_LIB.S9S_MB_2U(SCH_1):PAGE135_I65@PURE_QUANTA.Q_RES(CHIPS)':
 'A': CDS_PINID='A';
NODE_NAME     R742 1
 '@S9S_MB_2U_LIB.S9S_MB_2U(SCH_1):PAGE135_I78@PURE_QUANTA.Q_RES(CHIPS)':
 'A': CDS_PINID='A';
NODE_NAME     R663 1
 '@S9S_MB_2U_LIB.S9S_MB_2U(SCH_1):PAGE218_I18@PURE_QUANTA.Q_RES(CHIPS)':
 'A': CDS_PINID='A';
NODE_NAME     R664 1
 '@S9S_MB_2U_LIB.S9S_MB_2U(SCH_1):PAGE218_I28@PURE_QUANTA.Q_RES(CHIPS)':
 'A': CDS_PINID='A';
NODE_NAME     R1007 1
 '@S9S_MB_2U_LIB.S9S_MB_2U(SCH_1):PAGE223_I12@PURE_QUANTA.Q_RES(CHIPS)':
 'A': CDS_PINID='A';
NODE_NAME     C560 1
 '@S9S_MB_2U_LIB.S9S_MB_2U(SCH_1):PAGE223_I42@PURE_QUANTA.Q_CAP(CHIPS)':
 'A': CDS_PINID='A';
NODE_NAME     U29 1
 '@S9S_MB_2U_LIB.S9S_MB_2U(SCH_1):PAGE223_I43@PURE_QUANTA.PCA9617ADP(CHIPS)':
 'VCCA': CDS_PINID='VCCA';
NODE_NAME     R964 1
 '@S9S_MB_2U_LIB.S9S_MB_2U(SCH_1):PAGE223_I46@PURE_QUANTA.Q_RES(CHIPS)':
 'A': CDS_PINID='A';
NODE_NAME     R963 1
 '@S9S_MB_2U_LIB.S9S_MB_2U(SCH_1):PAGE223_I48@PURE_QUANTA.Q_RES(CHIPS)':
 'A': CDS_PINID='A';
NODE_NAME     C568 1
 '@S9S_MB_2U_LIB.S9S_MB_2U(SCH_1):PAGE224_I35@PURE_QUANTA.Q_CAP(CHIPS)':
 'A': CDS_PINID='A';
NODE_NAME     U31 1
 '@S9S_MB_2U_LIB.S9S_MB_2U(SCH_1):PAGE224_I37@PURE_QUANTA.PCA9517AD(CHIPS)':
 'VCCA': CDS_PINID='VCCA';
NODE_NAME     R972 1
 '@S9S_MB_2U_LIB.S9S_MB_2U(SCH_1):PAGE224_I49@PURE_QUANTA.Q_RES(CHIPS)':
 'A': CDS_PINID='A';
NODE_NAME     R970 1
 '@S9S_MB_2U_LIB.S9S_MB_2U(SCH_1):PAGE224_I50@PURE_QUANTA.Q_RES(CHIPS)':
 'A': CDS_PINID='A';
NODE_NAME     R330 2
 '@S9S_MB_2U_LIB.S9S_MB_2U(SCH_1):PAGE80_I34@PURE_QUANTA.Q_RES(CHIPS)':
 'B': CDS_PINID='B';
NODE_NAME     R329 2
 '@S9S_MB_2U_LIB.S9S_MB_2U(SCH_1):PAGE80_I35@PURE_QUANTA.Q_RES(CHIPS)':
 'B': CDS_PINID='B';
NODE_NAME     R2345 1
 '@S9S_MB_2U_LIB.S9S_MB_2U(SCH_1):PAGE278_I15@PURE_QUANTA.Q_RES(CHIPS)':
 'A': CDS_PINID='A';
NODE_NAME     R2593 1
 '@S9S_MB_2U_LIB.S9S_MB_2U(SCH_1):PAGE282_I29@PURE_QUANTA.Q_RES(CHIPS)':
 'A': CDS_PINID='A';
NODE_NAME     R1718 1
 '@S9S_MB_2U_LIB.S9S_MB_2U(SCH_1):PAGE282_I33@PURE_QUANTA.Q_RES(CHIPS)':
 'A': CDS_PINID='A';
NODE_NAME     R2555 2
 '@S9S_MB_2U_LIB.S9S_MB_2U(SCH_1):PAGE270_I101@PURE_QUANTA.Q_RES(CHIPS)':
 'B': CDS_PINID='B';
NODE_NAME     R2554 2
 '@S9S_MB_2U_LIB.S9S_MB_2U(SCH_1):PAGE270_I100@PURE_QUANTA.Q_RES(CHIPS)':
 'B': CDS_PINID='B';
NODE_NAME     C2449 1
 '@S9S_MB_2U_LIB.S9S_MB_2U(SCH_1):PAGE270_I104@PURE_QUANTA.Q_CAP(CHIPS)':
 'A': CDS_PINID='A';
NODE_NAME     R2354 1
 '@S9S_MB_2U_LIB.S9S_MB_2U(SCH_1):PAGE278_I14@PURE_QUANTA.Q_RES(CHIPS)':
 'A': CDS_PINID='A';
NODE_NAME     C1337 1
 '@S9S_MB_2U_LIB.S9S_MB_2U(SCH_1):PAGE282_I28@PURE_QUANTA.Q_CAP(CHIPS)':
 'A': CDS_PINID='A';
NODE_NAME     C1336 1
 '@S9S_MB_2U_LIB.S9S_MB_2U(SCH_1):PAGE282_I24@PURE_QUANTA.Q_CAP(CHIPS)':
 'A': CDS_PINID='A';
NODE_NAME     R2553 2
 '@S9S_MB_2U_LIB.S9S_MB_2U(SCH_1):PAGE270_I99@PURE_QUANTA.Q_RES(CHIPS)':
 'B': CDS_PINID='B';
NODE_NAME     C2448 1
 '@S9S_MB_2U_LIB.S9S_MB_2U(SCH_1):PAGE270_I103@PURE_QUANTA.Q_CAP(CHIPS)':
 'A': CDS_PINID='A';
NODE_NAME     R4396 1
 '@S9S_MB_2U_LIB.S9S_MB_2U(SCH_1):PAGE121_I4@PURE_QUANTA.Q_RES(CHIPS)':
 'A': CDS_PINID='A';
NODE_NAME     Q139 4
 '@S9S_MB_2U_LIB.S9S_MB_2U(SCH_1):PAGE121_I8@PURE_QUANTA.BC847BPN(CHIPS)':
 'E2': CDS_PINID='E2';
NODE_NAME     R244 1
 '@S9S_MB_2U_LIB.S9S_MB_2U(SCH_1):PAGE121_I19@PURE_QUANTA.Q_RES(CHIPS)':
 'A': CDS_PINID='A';
NODE_NAME     R4402 1
 '@S9S_MB_2U_LIB.S9S_MB_2U(SCH_1):PAGE122_I5@PURE_QUANTA.Q_RES(CHIPS)':
 'A': CDS_PINID='A';
NODE_NAME     Q142 4
 '@S9S_MB_2U_LIB.S9S_MB_2U(SCH_1):PAGE122_I10@PURE_QUANTA.BC847BPN(CHIPS)':
 'E2': CDS_PINID='E2';
NODE_NAME     R220 1
 '@S9S_MB_2U_LIB.S9S_MB_2U(SCH_1):PAGE122_I29@PURE_QUANTA.Q_RES(CHIPS)':
 'A': CDS_PINID='A';
NODE_NAME     R202 1
 '@S9S_MB_2U_LIB.S9S_MB_2U(SCH_1):PAGE123_I7@PURE_QUANTA.Q_RES(CHIPS)':
 'A': CDS_PINID='A';
NODE_NAME     Q140 4
 '@S9S_MB_2U_LIB.S9S_MB_2U(SCH_1):PAGE123_I11@PURE_QUANTA.BC847BPN(CHIPS)':
 'E2': CDS_PINID='E2';
NODE_NAME     R198 1
 '@S9S_MB_2U_LIB.S9S_MB_2U(SCH_1):PAGE123_I23@PURE_QUANTA.Q_RES(CHIPS)':
 'A': CDS_PINID='A';
NODE_NAME     R662 1
 '@S9S_MB_2U_LIB.S9S_MB_2U(SCH_1):PAGE218_I17@PURE_QUANTA.Q_RES(CHIPS)':
 'A': CDS_PINID='A';
NODE_NAME     R669 1
 '@S9S_MB_2U_LIB.S9S_MB_2U(SCH_1):PAGE218_I29@PURE_QUANTA.Q_RES(CHIPS)':
 'A': CDS_PINID='A';
NET_NAME
'PVPP_HBM_CPU0'
 '@S9S_MB_2U_LIB.S9S_MB_2U(SCH_1):PVPP_HBM_CPU0':
 C_SIGNAL='@s9s_mb_2u_lib.s9s_mb_2u(sch_1):pvpp_hbm_cpu0',
 CDS_GLOBAL_NET='TRUE';
NODE_NAME     U2 CF67
 '@S9S_MB_2U_LIB.S9S_MB_2U(SCH_1):PAGE37_I8@PURE_QUANTA.SOCKET4677_AZIF0045P001C01CS(CHIPS)':
 'VPP_HBM1': CDS_PINID='VPP_HBM1';
NODE_NAME     U2 CE68
 '@S9S_MB_2U_LIB.S9S_MB_2U(SCH_1):PAGE37_I8@PURE_QUANTA.SOCKET4677_AZIF0045P001C01CS(CHIPS)':
 'VPP_HBM2': CDS_PINID='VPP_HBM2';
NODE_NAME     U2 CD67
 '@S9S_MB_2U_LIB.S9S_MB_2U(SCH_1):PAGE37_I8@PURE_QUANTA.SOCKET4677_AZIF0045P001C01CS(CHIPS)':
 'VPP_HBM3': CDS_PINID='VPP_HBM3';
NODE_NAME     U2 CC68
 '@S9S_MB_2U_LIB.S9S_MB_2U(SCH_1):PAGE37_I8@PURE_QUANTA.SOCKET4677_AZIF0045P001C01CS(CHIPS)':
 'VPP_HBM4': CDS_PINID='VPP_HBM4';
NODE_NAME     U2 CG68
 '@S9S_MB_2U_LIB.S9S_MB_2U(SCH_1):PAGE37_I8@PURE_QUANTA.SOCKET4677_AZIF0045P001C01CS(CHIPS)':
 'VPP_HBM': CDS_PINID='VPP_HBM';
NODE_NAME     C1396 1
 '@S9S_MB_2U_LIB.S9S_MB_2U(SCH_1):PAGE75_I43@PURE_QUANTA.Q_CAP(CHIPS)':
 'A': CDS_PINID='A';
NODE_NAME     C1397 1
 '@S9S_MB_2U_LIB.S9S_MB_2U(SCH_1):PAGE75_I44@PURE_QUANTA.Q_CAP(CHIPS)':
 'A': CDS_PINID='A';
NODE_NAME     PC1254 1
 '@S9S_MB_2U_LIB.S9S_MB_2U(SCH_1):PAGE267_I38@PURE_QUANTA.Q_CAP(CHIPS)':
 'A': CDS_PINID='A';
NODE_NAME     PC1255 1
 '@S9S_MB_2U_LIB.S9S_MB_2U(SCH_1):PAGE267_I42@PURE_QUANTA.Q_CAP(CHIPS)':
 'A': CDS_PINID='A';
NODE_NAME     C1398 1
 '@S9S_MB_2U_LIB.S9S_MB_2U(SCH_1):PAGE75_I58@PURE_QUANTA.Q_CAP(CHIPS)':
 'A': CDS_PINID='A';
NODE_NAME     C1436 1
 '@S9S_MB_2U_LIB.S9S_MB_2U(SCH_1):PAGE75_I59@PURE_QUANTA.Q_CAP(CHIPS)':
 'A': CDS_PINID='A';
NODE_NAME     PL118 2
 '@S9S_MB_2U_LIB.S9S_MB_2U(SCH_1):PAGE267_I28@PURE_QUANTA.Q_INDUCTOR(CHIPS)':
 '2': CDS_PINID='\2\';
NODE_NAME     PC1258 1
 '@S9S_MB_2U_LIB.S9S_MB_2U(SCH_1):PAGE267_I49@PURE_QUANTA.Q_CAPP(CHIPS)':
 'A': CDS_PINID='A';
NODE_NAME     PC1256 1
 '@S9S_MB_2U_LIB.S9S_MB_2U(SCH_1):PAGE267_I43@PURE_QUANTA.Q_CAP(CHIPS)':
 'A': CDS_PINID='A';
NODE_NAME     PJ64 2
 '@S9S_MB_2U_LIB.S9S_MB_2U(SCH_1):PAGE267_I41@PURE_QUANTA.Q_SHORT(CHIPS)':
 '2': CDS_PINID='\2\';
NODE_NAME     PC1257 1
 '@S9S_MB_2U_LIB.S9S_MB_2U(SCH_1):PAGE267_I44@PURE_QUANTA.Q_CAP(CHIPS)':
 'A': CDS_PINID='A';
NET_NAME
'PVPP_HBM_CPU0_CS'
 '@S9S_MB_2U_LIB.S9S_MB_2U(SCH_1):PVPP_HBM_CPU0_CS':
 C_SIGNAL='@s9s_mb_2u_lib.s9s_mb_2u(sch_1):pvpp_hbm_cpu0_cs';
NODE_NAME     PR1336 1
 '@S9S_MB_2U_LIB.S9S_MB_2U(SCH_1):PAGE267_I15@PURE_QUANTA.Q_RES(CHIPS)':
 'A': CDS_PINID='A';
NODE_NAME     PU79 3
 '@S9S_MB_2U_LIB.S9S_MB_2U(SCH_1):PAGE267_I19@PURE_QUANTA.RS53318LR(CHIPS)':
 'CS': CDS_PINID='CS';
NET_NAME
'PVPP_HBM_CPU0_FB'
 '@S9S_MB_2U_LIB.S9S_MB_2U(SCH_1):PVPP_HBM_CPU0_FB':
 C_SIGNAL='@s9s_mb_2u_lib.s9s_mb_2u(sch_1):pvpp_hbm_cpu0_fb';
NODE_NAME     PR2336 1
 '@S9S_MB_2U_LIB.S9S_MB_2U(SCH_1):PAGE267_I34@PURE_QUANTA.Q_RES(CHIPS)':
 'A': CDS_PINID='A';
NODE_NAME     PR1310 1
 '@S9S_MB_2U_LIB.S9S_MB_2U(SCH_1):PAGE267_I26@PURE_QUANTA.Q_RES(CHIPS)':
 'A': CDS_PINID='A';
NODE_NAME     PR1337 1
 '@S9S_MB_2U_LIB.S9S_MB_2U(SCH_1):PAGE267_I36@PURE_QUANTA.Q_RES(CHIPS)':
 'A': CDS_PINID='A';
NODE_NAME     PC1253 1
 '@S9S_MB_2U_LIB.S9S_MB_2U(SCH_1):PAGE267_I35@PURE_QUANTA.Q_CAP(CHIPS)':
 'A': CDS_PINID='A';
NODE_NAME     PU79 7
 '@S9S_MB_2U_LIB.S9S_MB_2U(SCH_1):PAGE267_I19@PURE_QUANTA.RS53318LR(CHIPS)':
 'FB': CDS_PINID='FB';
NET_NAME
'PVPP_HBM_CPU0_MODE'
 '@S9S_MB_2U_LIB.S9S_MB_2U(SCH_1):PVPP_HBM_CPU0_MODE':
 C_SIGNAL='@s9s_mb_2u_lib.s9s_mb_2u(sch_1):pvpp_hbm_cpu0_mode';
NODE_NAME     PR3335 1
 '@S9S_MB_2U_LIB.S9S_MB_2U(SCH_1):PAGE267_I18@PURE_QUANTA.Q_RES(CHIPS)':
 'A': CDS_PINID='A';
NODE_NAME     PU79 4
 '@S9S_MB_2U_LIB.S9S_MB_2U(SCH_1):PAGE267_I19@PURE_QUANTA.RS53318LR(CHIPS)':
 'MODE': CDS_PINID='MODE';
NET_NAME
'PVPP_HBM_CPU0_REF'
 '@S9S_MB_2U_LIB.S9S_MB_2U(SCH_1):PVPP_HBM_CPU0_REF':
 C_SIGNAL='@s9s_mb_2u_lib.s9s_mb_2u(sch_1):pvpp_hbm_cpu0_ref';
NODE_NAME     PC2001 1
 '@S9S_MB_2U_LIB.S9S_MB_2U(SCH_1):PAGE267_I23@PURE_QUANTA.Q_CAP(CHIPS)':
 'A': CDS_PINID='A';
NODE_NAME     PU79 5
 '@S9S_MB_2U_LIB.S9S_MB_2U(SCH_1):PAGE267_I19@PURE_QUANTA.RS53318LR(CHIPS)':
 'REF': CDS_PINID='REF';
NODE_NAME     PC1251 1
 '@S9S_MB_2U_LIB.S9S_MB_2U(SCH_1):PAGE267_I25@PURE_QUANTA.Q_CAP(CHIPS)':
 'A': CDS_PINID='A';
NET_NAME
'PVPP_HBM_CPU0_VCC'
 '@S9S_MB_2U_LIB.S9S_MB_2U(SCH_1):PVPP_HBM_CPU0_VCC':
 C_SIGNAL='@s9s_mb_2u_lib.s9s_mb_2u(sch_1):pvpp_hbm_cpu0_vcc';
NODE_NAME     PC2643 1
 '@S9S_MB_2U_LIB.S9S_MB_2U(SCH_1):PAGE267_I4@PURE_QUANTA.Q_CAP(CHIPS)':
 'A': CDS_PINID='A';
NODE_NAME     PR1335 2
 '@S9S_MB_2U_LIB.S9S_MB_2U(SCH_1):PAGE267_I5@PURE_QUANTA.Q_RES(CHIPS)':
 'B': CDS_PINID='B';
NODE_NAME     PU79 19
 '@S9S_MB_2U_LIB.S9S_MB_2U(SCH_1):PAGE267_I19@PURE_QUANTA.RS53318LR(CHIPS)':
 'VCC': CDS_PINID='VCC';
NET_NAME
'PVPP_HBM_CPU1'
 '@S9S_MB_2U_LIB.S9S_MB_2U(SCH_1):PVPP_HBM_CPU1':
 C_SIGNAL='@s9s_mb_2u_lib.s9s_mb_2u(sch_1):pvpp_hbm_cpu1',
 CDS_GLOBAL_NET='TRUE';
NODE_NAME     U1 CF67
 '@S9S_MB_2U_LIB.S9S_MB_2U(SCH_1):PAGE68_I8@PURE_QUANTA.SOCKET4677_AZIF0045P001C01CS(CHIPS)':
 'VPP_HBM1': CDS_PINID='VPP_HBM1';
NODE_NAME     U1 CE68
 '@S9S_MB_2U_LIB.S9S_MB_2U(SCH_1):PAGE68_I8@PURE_QUANTA.SOCKET4677_AZIF0045P001C01CS(CHIPS)':
 'VPP_HBM2': CDS_PINID='VPP_HBM2';
NODE_NAME     U1 CD67
 '@S9S_MB_2U_LIB.S9S_MB_2U(SCH_1):PAGE68_I8@PURE_QUANTA.SOCKET4677_AZIF0045P001C01CS(CHIPS)':
 'VPP_HBM3': CDS_PINID='VPP_HBM3';
NODE_NAME     U1 CC68
 '@S9S_MB_2U_LIB.S9S_MB_2U(SCH_1):PAGE68_I8@PURE_QUANTA.SOCKET4677_AZIF0045P001C01CS(CHIPS)':
 'VPP_HBM4': CDS_PINID='VPP_HBM4';
NODE_NAME     U1 CG68
 '@S9S_MB_2U_LIB.S9S_MB_2U(SCH_1):PAGE68_I8@PURE_QUANTA.SOCKET4677_AZIF0045P001C01CS(CHIPS)':
 'VPP_HBM': CDS_PINID='VPP_HBM';
NODE_NAME     C1388 1
 '@S9S_MB_2U_LIB.S9S_MB_2U(SCH_1):PAGE78_I46@PURE_QUANTA.Q_CAP(CHIPS)':
 'A': CDS_PINID='A';
NODE_NAME     C1390 1
 '@S9S_MB_2U_LIB.S9S_MB_2U(SCH_1):PAGE78_I48@PURE_QUANTA.Q_CAP(CHIPS)':
 'A': CDS_PINID='A';
NODE_NAME     C1392 1
 '@S9S_MB_2U_LIB.S9S_MB_2U(SCH_1):PAGE78_I53@PURE_QUANTA.Q_CAP(CHIPS)':
 'A': CDS_PINID='A';
NODE_NAME     C1437 1
 '@S9S_MB_2U_LIB.S9S_MB_2U(SCH_1):PAGE78_I55@PURE_QUANTA.Q_CAP(CHIPS)':
 'A': CDS_PINID='A';
NODE_NAME     PL119 2
 '@S9S_MB_2U_LIB.S9S_MB_2U(SCH_1):PAGE285_I33@PURE_QUANTA.Q_INDUCTOR(CHIPS)':
 '2': CDS_PINID='\2\';
NODE_NAME     PC1269 1
 '@S9S_MB_2U_LIB.S9S_MB_2U(SCH_1):PAGE285_I41@PURE_QUANTA.Q_CAP(CHIPS)':
 'A': CDS_PINID='A';
NODE_NAME     PJ66 2
 '@S9S_MB_2U_LIB.S9S_MB_2U(SCH_1):PAGE285_I46@PURE_QUANTA.Q_SHORT(CHIPS)':
 '2': CDS_PINID='\2\';
NODE_NAME     PC1267 1
 '@S9S_MB_2U_LIB.S9S_MB_2U(SCH_1):PAGE285_I39@PURE_QUANTA.Q_CAP(CHIPS)':
 'A': CDS_PINID='A';
NODE_NAME     PC1268 1
 '@S9S_MB_2U_LIB.S9S_MB_2U(SCH_1):PAGE285_I40@PURE_QUANTA.Q_CAP(CHIPS)':
 'A': CDS_PINID='A';
NODE_NAME     PC1270 1
 '@S9S_MB_2U_LIB.S9S_MB_2U(SCH_1):PAGE285_I47@PURE_QUANTA.Q_CAP(CHIPS)':
 'A': CDS_PINID='A';
NODE_NAME     PC1771 1
 '@S9S_MB_2U_LIB.S9S_MB_2U(SCH_1):PAGE285_I49@PURE_QUANTA.Q_CAPP(CHIPS)':
 'A': CDS_PINID='A';
NET_NAME
'PVPP_HBM_CPU1_CS'
 '@S9S_MB_2U_LIB.S9S_MB_2U(SCH_1):PVPP_HBM_CPU1_CS':
 C_SIGNAL='@s9s_mb_2u_lib.s9s_mb_2u(sch_1):pvpp_hbm_cpu1_cs';
NODE_NAME     PU80 3
 '@S9S_MB_2U_LIB.S9S_MB_2U(SCH_1):PAGE285_I25@PURE_QUANTA.RS53318LR(CHIPS)':
 'CS': CDS_PINID='CS';
NODE_NAME     PR1339 1
 '@S9S_MB_2U_LIB.S9S_MB_2U(SCH_1):PAGE285_I10@PURE_QUANTA.Q_RES(CHIPS)':
 'A': CDS_PINID='A';
NET_NAME
'PVPP_HBM_CPU1_FB'
 '@S9S_MB_2U_LIB.S9S_MB_2U(SCH_1):PVPP_HBM_CPU1_FB':
 C_SIGNAL='@s9s_mb_2u_lib.s9s_mb_2u(sch_1):pvpp_hbm_cpu1_fb';
NODE_NAME     PR2381 1
 '@S9S_MB_2U_LIB.S9S_MB_2U(SCH_1):PAGE285_I30@PURE_QUANTA.Q_RES(CHIPS)':
 'A': CDS_PINID='A';
NODE_NAME     PR1314 1
 '@S9S_MB_2U_LIB.S9S_MB_2U(SCH_1):PAGE285_I28@PURE_QUANTA.Q_RES(CHIPS)':
 'A': CDS_PINID='A';
NODE_NAME     PR1340 1
 '@S9S_MB_2U_LIB.S9S_MB_2U(SCH_1):PAGE285_I34@PURE_QUANTA.Q_RES(CHIPS)':
 'A': CDS_PINID='A';
NODE_NAME     PU80 7
 '@S9S_MB_2U_LIB.S9S_MB_2U(SCH_1):PAGE285_I25@PURE_QUANTA.RS53318LR(CHIPS)':
 'FB': CDS_PINID='FB';
NODE_NAME     PC1266 1
 '@S9S_MB_2U_LIB.S9S_MB_2U(SCH_1):PAGE285_I35@PURE_QUANTA.Q_CAP(CHIPS)':
 'A': CDS_PINID='A';
NET_NAME
'PVPP_HBM_CPU1_MODE'
 '@S9S_MB_2U_LIB.S9S_MB_2U(SCH_1):PVPP_HBM_CPU1_MODE':
 C_SIGNAL='@s9s_mb_2u_lib.s9s_mb_2u(sch_1):pvpp_hbm_cpu1_mode';
NODE_NAME     PR3336 1
 '@S9S_MB_2U_LIB.S9S_MB_2U(SCH_1):PAGE285_I18@PURE_QUANTA.Q_RES(CHIPS)':
 'A': CDS_PINID='A';
NODE_NAME     PU80 4
 '@S9S_MB_2U_LIB.S9S_MB_2U(SCH_1):PAGE285_I25@PURE_QUANTA.RS53318LR(CHIPS)':
 'MODE': CDS_PINID='MODE';
NET_NAME
'PVPP_HBM_CPU1_REF'
 '@S9S_MB_2U_LIB.S9S_MB_2U(SCH_1):PVPP_HBM_CPU1_REF':
 C_SIGNAL='@s9s_mb_2u_lib.s9s_mb_2u(sch_1):pvpp_hbm_cpu1_ref';
NODE_NAME     PU80 5
 '@S9S_MB_2U_LIB.S9S_MB_2U(SCH_1):PAGE285_I25@PURE_QUANTA.RS53318LR(CHIPS)':
 'REF': CDS_PINID='REF';
NODE_NAME     PC1264 1
 '@S9S_MB_2U_LIB.S9S_MB_2U(SCH_1):PAGE285_I24@PURE_QUANTA.Q_CAP(CHIPS)':
 'A': CDS_PINID='A';
NODE_NAME     PC2002 1
 '@S9S_MB_2U_LIB.S9S_MB_2U(SCH_1):PAGE285_I23@PURE_QUANTA.Q_CAP(CHIPS)':
 'A': CDS_PINID='A';
NET_NAME
'PVPP_HBM_CPU1_VCC'
 '@S9S_MB_2U_LIB.S9S_MB_2U(SCH_1):PVPP_HBM_CPU1_VCC':
 C_SIGNAL='@s9s_mb_2u_lib.s9s_mb_2u(sch_1):pvpp_hbm_cpu1_vcc';
NODE_NAME     PU80 19
 '@S9S_MB_2U_LIB.S9S_MB_2U(SCH_1):PAGE285_I25@PURE_QUANTA.RS53318LR(CHIPS)':
 'VCC': CDS_PINID='VCC';
NODE_NAME     PR1338 2
 '@S9S_MB_2U_LIB.S9S_MB_2U(SCH_1):PAGE285_I3@PURE_QUANTA.Q_RES(CHIPS)':
 'B': CDS_PINID='B';
NODE_NAME     PC644 1
 '@S9S_MB_2U_LIB.S9S_MB_2U(SCH_1):PAGE285_I1@PURE_QUANTA.Q_CAP(CHIPS)':
 'A': CDS_PINID='A';
NET_NAME
'PWRGD_CHA_CPU0_DIMM1'
 '@S9S_MB_2U_LIB.S9S_MB_2U(SCH_1):PWRGD_CHA_CPU0_DIMM1':
 C_SIGNAL='@s9s_mb_2u_lib.s9s_mb_2u(sch_1):pwrgd_cha_cpu0_dimm1';
NODE_NAME     J1 147
 '@S9S_MB_2U_LIB.S9S_MB_2U(SCH_1):PAGE82_I198@PURE_QUANTA.SCONN288_ADR50017P130CC(CHIPS)':
 'PWR_GOOD||FAIL_N': CDS_PINID='\pwr_good||fail_n\';
NODE_NAME     R2726 1
 '@S9S_MB_2U_LIB.S9S_MB_2U(SCH_1):PAGE114_I32@PURE_QUANTA.Q_RES(CHIPS)':
 'A': CDS_PINID='A';
NET_NAME
'PWRGD_CHA_CPU0_DIMM2'
 '@S9S_MB_2U_LIB.S9S_MB_2U(SCH_1):PWRGD_CHA_CPU0_DIMM2':
 C_SIGNAL='@s9s_mb_2u_lib.s9s_mb_2u(sch_1):pwrgd_cha_cpu0_dimm2';
NODE_NAME     J2 147
 '@S9S_MB_2U_LIB.S9S_MB_2U(SCH_1):PAGE83_I177@PURE_QUANTA.SCONN288_ADR50017P087CC(CHIPS)':
 'PWR_GOOD||FAIL_N': CDS_PINID='\pwr_good||fail_n\';
NODE_NAME     R2727 1
 '@S9S_MB_2U_LIB.S9S_MB_2U(SCH_1):PAGE114_I31@PURE_QUANTA.Q_RES(CHIPS)':
 'A': CDS_PINID='A';
NET_NAME
'PWRGD_CHA_CPU1_DIMM1'
 '@S9S_MB_2U_LIB.S9S_MB_2U(SCH_1):PWRGD_CHA_CPU1_DIMM1':
 C_SIGNAL='@s9s_mb_2u_lib.s9s_mb_2u(sch_1):pwrgd_cha_cpu1_dimm1';
NODE_NAME     J17 147
 '@S9S_MB_2U_LIB.S9S_MB_2U(SCH_1):PAGE98_I12@PURE_QUANTA.SCONN288_ADR50017P130CC(CHIPS)':
 'PWR_GOOD||FAIL_N': CDS_PINID='\pwr_good||fail_n\';
NODE_NAME     R893 1
 '@S9S_MB_2U_LIB.S9S_MB_2U(SCH_1):PAGE114_I79@PURE_QUANTA.Q_RES(CHIPS)':
 'A': CDS_PINID='A';
NET_NAME
'PWRGD_CHA_CPU1_DIMM2'
 '@S9S_MB_2U_LIB.S9S_MB_2U(SCH_1):PWRGD_CHA_CPU1_DIMM2':
 C_SIGNAL='@s9s_mb_2u_lib.s9s_mb_2u(sch_1):pwrgd_cha_cpu1_dimm2';
NODE_NAME     J18 147
 '@S9S_MB_2U_LIB.S9S_MB_2U(SCH_1):PAGE99_I24@PURE_QUANTA.SCONN288_ADR50017P087CC(CHIPS)':
 'PWR_GOOD||FAIL_N': CDS_PINID='\pwr_good||fail_n\';
NODE_NAME     R894 1
 '@S9S_MB_2U_LIB.S9S_MB_2U(SCH_1):PAGE114_I78@PURE_QUANTA.Q_RES(CHIPS)':
 'A': CDS_PINID='A';
NET_NAME
'PWRGD_CHB_CPU0_DIMM1'
 '@S9S_MB_2U_LIB.S9S_MB_2U(SCH_1):PWRGD_CHB_CPU0_DIMM1':
 C_SIGNAL='@s9s_mb_2u_lib.s9s_mb_2u(sch_1):pwrgd_chb_cpu0_dimm1';
NODE_NAME     J3 147
 '@S9S_MB_2U_LIB.S9S_MB_2U(SCH_1):PAGE84_I180@PURE_QUANTA.SCONN288_ADR50017P130CC(CHIPS)':
 'PWR_GOOD||FAIL_N': CDS_PINID='\pwr_good||fail_n\';
NODE_NAME     R2728 1
 '@S9S_MB_2U_LIB.S9S_MB_2U(SCH_1):PAGE114_I30@PURE_QUANTA.Q_RES(CHIPS)':
 'A': CDS_PINID='A';
NET_NAME
'PWRGD_CHB_CPU0_DIMM2'
 '@S9S_MB_2U_LIB.S9S_MB_2U(SCH_1):PWRGD_CHB_CPU0_DIMM2':
 C_SIGNAL='@s9s_mb_2u_lib.s9s_mb_2u(sch_1):pwrgd_chb_cpu0_dimm2';
NODE_NAME     J4 147
 '@S9S_MB_2U_LIB.S9S_MB_2U(SCH_1):PAGE85_I23@PURE_QUANTA.SCONN288_ADR50017P087CC(CHIPS)':
 'PWR_GOOD||FAIL_N': CDS_PINID='\pwr_good||fail_n\';
NODE_NAME     R880 1
 '@S9S_MB_2U_LIB.S9S_MB_2U(SCH_1):PAGE114_I29@PURE_QUANTA.Q_RES(CHIPS)':
 'A': CDS_PINID='A';
NET_NAME
'PWRGD_CHB_CPU1_DIMM1'
 '@S9S_MB_2U_LIB.S9S_MB_2U(SCH_1):PWRGD_CHB_CPU1_DIMM1':
 C_SIGNAL='@s9s_mb_2u_lib.s9s_mb_2u(sch_1):pwrgd_chb_cpu1_dimm1';
NODE_NAME     J19 147
 '@S9S_MB_2U_LIB.S9S_MB_2U(SCH_1):PAGE100_I25@PURE_QUANTA.SCONN288_ADR50017P130CC(CHIPS)':
 'PWR_GOOD||FAIL_N': CDS_PINID='\pwr_good||fail_n\';
NODE_NAME     R895 1
 '@S9S_MB_2U_LIB.S9S_MB_2U(SCH_1):PAGE114_I77@PURE_QUANTA.Q_RES(CHIPS)':
 'A': CDS_PINID='A';
NET_NAME
'PWRGD_CHB_CPU1_DIMM2'
 '@S9S_MB_2U_LIB.S9S_MB_2U(SCH_1):PWRGD_CHB_CPU1_DIMM2':
 C_SIGNAL='@s9s_mb_2u_lib.s9s_mb_2u(sch_1):pwrgd_chb_cpu1_dimm2';
NODE_NAME     J20 147
 '@S9S_MB_2U_LIB.S9S_MB_2U(SCH_1):PAGE101_I47@PURE_QUANTA.SCONN288_ADR50017P087CC(CHIPS)':
 'PWR_GOOD||FAIL_N': CDS_PINID='\pwr_good||fail_n\';
NODE_NAME     R896 1
 '@S9S_MB_2U_LIB.S9S_MB_2U(SCH_1):PAGE114_I69@PURE_QUANTA.Q_RES(CHIPS)':
 'A': CDS_PINID='A';
NET_NAME
'PWRGD_CHC_CPU0_DIMM1'
 '@S9S_MB_2U_LIB.S9S_MB_2U(SCH_1):PWRGD_CHC_CPU0_DIMM1':
 C_SIGNAL='@s9s_mb_2u_lib.s9s_mb_2u(sch_1):pwrgd_chc_cpu0_dimm1';
NODE_NAME     J5 147
 '@S9S_MB_2U_LIB.S9S_MB_2U(SCH_1):PAGE86_I24@PURE_QUANTA.SCONN288_ADR50017P130CC(CHIPS)':
 'PWR_GOOD||FAIL_N': CDS_PINID='\pwr_good||fail_n\';
NODE_NAME     R2729 1
 '@S9S_MB_2U_LIB.S9S_MB_2U(SCH_1):PAGE114_I28@PURE_QUANTA.Q_RES(CHIPS)':
 'A': CDS_PINID='A';
NET_NAME
'PWRGD_CHC_CPU0_DIMM2'
 '@S9S_MB_2U_LIB.S9S_MB_2U(SCH_1):PWRGD_CHC_CPU0_DIMM2':
 C_SIGNAL='@s9s_mb_2u_lib.s9s_mb_2u(sch_1):pwrgd_chc_cpu0_dimm2';
NODE_NAME     J6 147
 '@S9S_MB_2U_LIB.S9S_MB_2U(SCH_1):PAGE87_I46@PURE_QUANTA.SCONN288_ADR50017P087CC(CHIPS)':
 'PWR_GOOD||FAIL_N': CDS_PINID='\pwr_good||fail_n\';
NODE_NAME     R2730 1
 '@S9S_MB_2U_LIB.S9S_MB_2U(SCH_1):PAGE114_I27@PURE_QUANTA.Q_RES(CHIPS)':
 'A': CDS_PINID='A';
NET_NAME
'PWRGD_CHC_CPU1_DIMM1'
 '@S9S_MB_2U_LIB.S9S_MB_2U(SCH_1):PWRGD_CHC_CPU1_DIMM1':
 C_SIGNAL='@s9s_mb_2u_lib.s9s_mb_2u(sch_1):pwrgd_chc_cpu1_dimm1';
NODE_NAME     J21 147
 '@S9S_MB_2U_LIB.S9S_MB_2U(SCH_1):PAGE102_I13@PURE_QUANTA.SCONN288_ADR50017P130CC(CHIPS)':
 'PWR_GOOD||FAIL_N': CDS_PINID='\pwr_good||fail_n\';
NODE_NAME     R897 1
 '@S9S_MB_2U_LIB.S9S_MB_2U(SCH_1):PAGE114_I67@PURE_QUANTA.Q_RES(CHIPS)':
 'A': CDS_PINID='A';
NET_NAME
'PWRGD_CHC_CPU1_DIMM2'
 '@S9S_MB_2U_LIB.S9S_MB_2U(SCH_1):PWRGD_CHC_CPU1_DIMM2':
 C_SIGNAL='@s9s_mb_2u_lib.s9s_mb_2u(sch_1):pwrgd_chc_cpu1_dimm2';
NODE_NAME     J22 147
 '@S9S_MB_2U_LIB.S9S_MB_2U(SCH_1):PAGE103_I51@PURE_QUANTA.SCONN288_ADR50017P087CC(CHIPS)':
 'PWR_GOOD||FAIL_N': CDS_PINID='\pwr_good||fail_n\';
NODE_NAME     R898 1
 '@S9S_MB_2U_LIB.S9S_MB_2U(SCH_1):PAGE114_I68@PURE_QUANTA.Q_RES(CHIPS)':
 'A': CDS_PINID='A';
NET_NAME
'PWRGD_CHD_CPU0_DIMM1'
 '@S9S_MB_2U_LIB.S9S_MB_2U(SCH_1):PWRGD_CHD_CPU0_DIMM1':
 C_SIGNAL='@s9s_mb_2u_lib.s9s_mb_2u(sch_1):pwrgd_chd_cpu0_dimm1';
NODE_NAME     J7 147
 '@S9S_MB_2U_LIB.S9S_MB_2U(SCH_1):PAGE88_I12@PURE_QUANTA.SCONN288_ADR50017P130CC(CHIPS)':
 'PWR_GOOD||FAIL_N': CDS_PINID='\pwr_good||fail_n\';
NODE_NAME     R2731 1
 '@S9S_MB_2U_LIB.S9S_MB_2U(SCH_1):PAGE114_I25@PURE_QUANTA.Q_RES(CHIPS)':
 'A': CDS_PINID='A';
NET_NAME
'PWRGD_CHD_CPU0_DIMM2'
 '@S9S_MB_2U_LIB.S9S_MB_2U(SCH_1):PWRGD_CHD_CPU0_DIMM2':
 C_SIGNAL='@s9s_mb_2u_lib.s9s_mb_2u(sch_1):pwrgd_chd_cpu0_dimm2';
NODE_NAME     J8 147
 '@S9S_MB_2U_LIB.S9S_MB_2U(SCH_1):PAGE89_I50@PURE_QUANTA.SCONN288_ADR50017P087CC(CHIPS)':
 'PWR_GOOD||FAIL_N': CDS_PINID='\pwr_good||fail_n\';
NODE_NAME     R884 1
 '@S9S_MB_2U_LIB.S9S_MB_2U(SCH_1):PAGE114_I26@PURE_QUANTA.Q_RES(CHIPS)':
 'A': CDS_PINID='A';
NET_NAME
'PWRGD_CHD_CPU1_DIMM1'
 '@S9S_MB_2U_LIB.S9S_MB_2U(SCH_1):PWRGD_CHD_CPU1_DIMM1':
 C_SIGNAL='@s9s_mb_2u_lib.s9s_mb_2u(sch_1):pwrgd_chd_cpu1_dimm1';
NODE_NAME     J23 147
 '@S9S_MB_2U_LIB.S9S_MB_2U(SCH_1):PAGE104_I25@PURE_QUANTA.SCONN288_ADR50017P130CC(CHIPS)':
 'PWR_GOOD||FAIL_N': CDS_PINID='\pwr_good||fail_n\';
NODE_NAME     R899 1
 '@S9S_MB_2U_LIB.S9S_MB_2U(SCH_1):PAGE114_I65@PURE_QUANTA.Q_RES(CHIPS)':
 'A': CDS_PINID='A';
NET_NAME
'PWRGD_CHD_CPU1_DIMM2'
 '@S9S_MB_2U_LIB.S9S_MB_2U(SCH_1):PWRGD_CHD_CPU1_DIMM2':
 C_SIGNAL='@s9s_mb_2u_lib.s9s_mb_2u(sch_1):pwrgd_chd_cpu1_dimm2';
NODE_NAME     J24 147
 '@S9S_MB_2U_LIB.S9S_MB_2U(SCH_1):PAGE105_I178@PURE_QUANTA.SCONN288_ADR50017P087CC(CHIPS)':
 'PWR_GOOD||FAIL_N': CDS_PINID='\pwr_good||fail_n\';
NODE_NAME     R900 1
 '@S9S_MB_2U_LIB.S9S_MB_2U(SCH_1):PAGE114_I66@PURE_QUANTA.Q_RES(CHIPS)':
 'A': CDS_PINID='A';
NET_NAME
'PWRGD_CHE_CPU0_DIMM1'
 '@S9S_MB_2U_LIB.S9S_MB_2U(SCH_1):PWRGD_CHE_CPU0_DIMM1':
 C_SIGNAL='@s9s_mb_2u_lib.s9s_mb_2u(sch_1):pwrgd_che_cpu0_dimm1';
NODE_NAME     J9 147
 '@S9S_MB_2U_LIB.S9S_MB_2U(SCH_1):PAGE90_I12@PURE_QUANTA.SCONN288_ADR50017P130CC(CHIPS)':
 'PWR_GOOD||FAIL_N': CDS_PINID='\pwr_good||fail_n\';
NODE_NAME     R885 1
 '@S9S_MB_2U_LIB.S9S_MB_2U(SCH_1):PAGE114_I24@PURE_QUANTA.Q_RES(CHIPS)':
 'A': CDS_PINID='A';
NET_NAME
'PWRGD_CHE_CPU0_DIMM2'
 '@S9S_MB_2U_LIB.S9S_MB_2U(SCH_1):PWRGD_CHE_CPU0_DIMM2':
 C_SIGNAL='@s9s_mb_2u_lib.s9s_mb_2u(sch_1):pwrgd_che_cpu0_dimm2';
NODE_NAME     J10 147
 '@S9S_MB_2U_LIB.S9S_MB_2U(SCH_1):PAGE91_I13@PURE_QUANTA.SCONN288_ADR50017P087CC(CHIPS)':
 'PWR_GOOD||FAIL_N': CDS_PINID='\pwr_good||fail_n\';
NODE_NAME     R886 1
 '@S9S_MB_2U_LIB.S9S_MB_2U(SCH_1):PAGE114_I23@PURE_QUANTA.Q_RES(CHIPS)':
 'A': CDS_PINID='A';
NET_NAME
'PWRGD_CHE_CPU1_DIMM1'
 '@S9S_MB_2U_LIB.S9S_MB_2U(SCH_1):PWRGD_CHE_CPU1_DIMM1':
 C_SIGNAL='@s9s_mb_2u_lib.s9s_mb_2u(sch_1):pwrgd_che_cpu1_dimm1';
NODE_NAME     J25 147
 '@S9S_MB_2U_LIB.S9S_MB_2U(SCH_1):PAGE106_I180@PURE_QUANTA.SCONN288_ADR50017P130CC(CHIPS)':
 'PWR_GOOD||FAIL_N': CDS_PINID='\pwr_good||fail_n\';
NODE_NAME     R901 1
 '@S9S_MB_2U_LIB.S9S_MB_2U(SCH_1):PAGE114_I64@PURE_QUANTA.Q_RES(CHIPS)':
 'A': CDS_PINID='A';
NET_NAME
'PWRGD_CHE_CPU1_DIMM2'
 '@S9S_MB_2U_LIB.S9S_MB_2U(SCH_1):PWRGD_CHE_CPU1_DIMM2':
 C_SIGNAL='@s9s_mb_2u_lib.s9s_mb_2u(sch_1):pwrgd_che_cpu1_dimm2';
NODE_NAME     J26 147
 '@S9S_MB_2U_LIB.S9S_MB_2U(SCH_1):PAGE107_I180@PURE_QUANTA.SCONN288_ADR50017P087CC(CHIPS)':
 'PWR_GOOD||FAIL_N': CDS_PINID='\pwr_good||fail_n\';
NODE_NAME     R902 1
 '@S9S_MB_2U_LIB.S9S_MB_2U(SCH_1):PAGE114_I63@PURE_QUANTA.Q_RES(CHIPS)':
 'A': CDS_PINID='A';
NET_NAME
'PWRGD_CHF_CPU0_DIMM1'
 '@S9S_MB_2U_LIB.S9S_MB_2U(SCH_1):PWRGD_CHF_CPU0_DIMM1':
 C_SIGNAL='@s9s_mb_2u_lib.s9s_mb_2u(sch_1):pwrgd_chf_cpu0_dimm1';
NODE_NAME     J11 147
 '@S9S_MB_2U_LIB.S9S_MB_2U(SCH_1):PAGE92_I25@PURE_QUANTA.SCONN288_ADR50017P130CC(CHIPS)':
 'PWR_GOOD||FAIL_N': CDS_PINID='\pwr_good||fail_n\';
NODE_NAME     R2732 1
 '@S9S_MB_2U_LIB.S9S_MB_2U(SCH_1):PAGE114_I22@PURE_QUANTA.Q_RES(CHIPS)':
 'A': CDS_PINID='A';
NET_NAME
'PWRGD_CHF_CPU0_DIMM2'
 '@S9S_MB_2U_LIB.S9S_MB_2U(SCH_1):PWRGD_CHF_CPU0_DIMM2':
 C_SIGNAL='@s9s_mb_2u_lib.s9s_mb_2u(sch_1):pwrgd_chf_cpu0_dimm2';
NODE_NAME     J12 147
 '@S9S_MB_2U_LIB.S9S_MB_2U(SCH_1):PAGE93_I24@PURE_QUANTA.SCONN288_ADR50017P087CC(CHIPS)':
 'PWR_GOOD||FAIL_N': CDS_PINID='\pwr_good||fail_n\';
NODE_NAME     R2733 1
 '@S9S_MB_2U_LIB.S9S_MB_2U(SCH_1):PAGE114_I21@PURE_QUANTA.Q_RES(CHIPS)':
 'A': CDS_PINID='A';
NET_NAME
'PWRGD_CHF_CPU1_DIMM1'
 '@S9S_MB_2U_LIB.S9S_MB_2U(SCH_1):PWRGD_CHF_CPU1_DIMM1':
 C_SIGNAL='@s9s_mb_2u_lib.s9s_mb_2u(sch_1):pwrgd_chf_cpu1_dimm1';
NODE_NAME     J27 147
 '@S9S_MB_2U_LIB.S9S_MB_2U(SCH_1):PAGE108_I179@PURE_QUANTA.SCONN288_ADR50017P130CC(CHIPS)':
 'PWR_GOOD||FAIL_N': CDS_PINID='\pwr_good||fail_n\';
NODE_NAME     R903 1
 '@S9S_MB_2U_LIB.S9S_MB_2U(SCH_1):PAGE114_I62@PURE_QUANTA.Q_RES(CHIPS)':
 'A': CDS_PINID='A';
NET_NAME
'PWRGD_CHF_CPU1_DIMM2'
 '@S9S_MB_2U_LIB.S9S_MB_2U(SCH_1):PWRGD_CHF_CPU1_DIMM2':
 C_SIGNAL='@s9s_mb_2u_lib.s9s_mb_2u(sch_1):pwrgd_chf_cpu1_dimm2';
NODE_NAME     J28 147
 '@S9S_MB_2U_LIB.S9S_MB_2U(SCH_1):PAGE109_I47@PURE_QUANTA.SCONN288_ADR50017P087CC(CHIPS)':
 'PWR_GOOD||FAIL_N': CDS_PINID='\pwr_good||fail_n\';
NODE_NAME     R2736 1
 '@S9S_MB_2U_LIB.S9S_MB_2U(SCH_1):PAGE114_I61@PURE_QUANTA.Q_RES(CHIPS)':
 'A': CDS_PINID='A';
NET_NAME
'PWRGD_CHG_CPU0_DIMM1'
 '@S9S_MB_2U_LIB.S9S_MB_2U(SCH_1):PWRGD_CHG_CPU0_DIMM1':
 C_SIGNAL='@s9s_mb_2u_lib.s9s_mb_2u(sch_1):pwrgd_chg_cpu0_dimm1';
NODE_NAME     J13 147
 '@S9S_MB_2U_LIB.S9S_MB_2U(SCH_1):PAGE94_I11@PURE_QUANTA.SCONN288_ADR50017P130CC(CHIPS)':
 'PWR_GOOD||FAIL_N': CDS_PINID='\pwr_good||fail_n\';
NODE_NAME     R889 1
 '@S9S_MB_2U_LIB.S9S_MB_2U(SCH_1):PAGE114_I20@PURE_QUANTA.Q_RES(CHIPS)':
 'A': CDS_PINID='A';
NET_NAME
'PWRGD_CHG_CPU0_DIMM2'
 '@S9S_MB_2U_LIB.S9S_MB_2U(SCH_1):PWRGD_CHG_CPU0_DIMM2':
 C_SIGNAL='@s9s_mb_2u_lib.s9s_mb_2u(sch_1):pwrgd_chg_cpu0_dimm2';
NODE_NAME     J14 147
 '@S9S_MB_2U_LIB.S9S_MB_2U(SCH_1):PAGE95_I47@PURE_QUANTA.SCONN288_ADR50017P087CC(CHIPS)':
 'PWR_GOOD||FAIL_N': CDS_PINID='\pwr_good||fail_n\';
NODE_NAME     R890 1
 '@S9S_MB_2U_LIB.S9S_MB_2U(SCH_1):PAGE114_I19@PURE_QUANTA.Q_RES(CHIPS)':
 'A': CDS_PINID='A';
NET_NAME
'PWRGD_CHG_CPU1_DIMM1'
 '@S9S_MB_2U_LIB.S9S_MB_2U(SCH_1):PWRGD_CHG_CPU1_DIMM1':
 C_SIGNAL='@s9s_mb_2u_lib.s9s_mb_2u(sch_1):pwrgd_chg_cpu1_dimm1';
NODE_NAME     J29 147
 '@S9S_MB_2U_LIB.S9S_MB_2U(SCH_1):PAGE110_I179@PURE_QUANTA.SCONN288_ADR50017P130CC(CHIPS)':
 'PWR_GOOD||FAIL_N': CDS_PINID='\pwr_good||fail_n\';
NODE_NAME     R905 1
 '@S9S_MB_2U_LIB.S9S_MB_2U(SCH_1):PAGE114_I60@PURE_QUANTA.Q_RES(CHIPS)':
 'A': CDS_PINID='A';
NET_NAME
'PWRGD_CHG_CPU1_DIMM2'
 '@S9S_MB_2U_LIB.S9S_MB_2U(SCH_1):PWRGD_CHG_CPU1_DIMM2':
 C_SIGNAL='@s9s_mb_2u_lib.s9s_mb_2u(sch_1):pwrgd_chg_cpu1_dimm2';
NODE_NAME     J30 147
 '@S9S_MB_2U_LIB.S9S_MB_2U(SCH_1):PAGE111_I179@PURE_QUANTA.SCONN288_ADR50017P087CC(CHIPS)':
 'PWR_GOOD||FAIL_N': CDS_PINID='\pwr_good||fail_n\';
NODE_NAME     R906 1
 '@S9S_MB_2U_LIB.S9S_MB_2U(SCH_1):PAGE114_I59@PURE_QUANTA.Q_RES(CHIPS)':
 'A': CDS_PINID='A';
NET_NAME
'PWRGD_CHH_CPU0_DIMM1'
 '@S9S_MB_2U_LIB.S9S_MB_2U(SCH_1):PWRGD_CHH_CPU0_DIMM1':
 C_SIGNAL='@s9s_mb_2u_lib.s9s_mb_2u(sch_1):pwrgd_chh_cpu0_dimm1';
NODE_NAME     J15 147
 '@S9S_MB_2U_LIB.S9S_MB_2U(SCH_1):PAGE96_I48@PURE_QUANTA.SCONN288_ADR50017P130CC(CHIPS)':
 'PWR_GOOD||FAIL_N': CDS_PINID='\pwr_good||fail_n\';
NODE_NAME     R2734 1
 '@S9S_MB_2U_LIB.S9S_MB_2U(SCH_1):PAGE114_I18@PURE_QUANTA.Q_RES(CHIPS)':
 'A': CDS_PINID='A';
NET_NAME
'PWRGD_CHH_CPU0_DIMM2'
 '@S9S_MB_2U_LIB.S9S_MB_2U(SCH_1):PWRGD_CHH_CPU0_DIMM2':
 C_SIGNAL='@s9s_mb_2u_lib.s9s_mb_2u(sch_1):pwrgd_chh_cpu0_dimm2';
NODE_NAME     J16 147
 '@S9S_MB_2U_LIB.S9S_MB_2U(SCH_1):PAGE97_I6@PURE_QUANTA.SCONN288_ADR50017P087CC(CHIPS)':
 'PWR_GOOD||FAIL_N': CDS_PINID='\pwr_good||fail_n\';
NODE_NAME     R2735 1
 '@S9S_MB_2U_LIB.S9S_MB_2U(SCH_1):PAGE114_I17@PURE_QUANTA.Q_RES(CHIPS)':
 'A': CDS_PINID='A';
NET_NAME
'PWRGD_CHH_CPU1_DIMM1'
 '@S9S_MB_2U_LIB.S9S_MB_2U(SCH_1):PWRGD_CHH_CPU1_DIMM1':
 C_SIGNAL='@s9s_mb_2u_lib.s9s_mb_2u(sch_1):pwrgd_chh_cpu1_dimm1';
NODE_NAME     J31 147
 '@S9S_MB_2U_LIB.S9S_MB_2U(SCH_1):PAGE112_I180@PURE_QUANTA.SCONN288_ADR50017P130CC(CHIPS)':
 'PWR_GOOD||FAIL_N': CDS_PINID='\pwr_good||fail_n\';
NODE_NAME     R907 1
 '@S9S_MB_2U_LIB.S9S_MB_2U(SCH_1):PAGE114_I58@PURE_QUANTA.Q_RES(CHIPS)':
 'A': CDS_PINID='A';
NET_NAME
'PWRGD_CHH_CPU1_DIMM2'
 '@S9S_MB_2U_LIB.S9S_MB_2U(SCH_1):PWRGD_CHH_CPU1_DIMM2':
 C_SIGNAL='@s9s_mb_2u_lib.s9s_mb_2u(sch_1):pwrgd_chh_cpu1_dimm2';
NODE_NAME     J32 147
 '@S9S_MB_2U_LIB.S9S_MB_2U(SCH_1):PAGE113_I179@PURE_QUANTA.SCONN288_ADR50017P087CC(CHIPS)':
 'PWR_GOOD||FAIL_N': CDS_PINID='\pwr_good||fail_n\';
NODE_NAME     R908 1
 '@S9S_MB_2U_LIB.S9S_MB_2U(SCH_1):PAGE114_I57@PURE_QUANTA.Q_RES(CHIPS)':
 'A': CDS_PINID='A';
NET_NAME
'PWRGD_CPU0_BUF_R'
 '@S9S_MB_2U_LIB.S9S_MB_2U(SCH_1):PWRGD_CPU0_BUF_R':
 C_SIGNAL='@s9s_mb_2u_lib.s9s_mb_2u(sch_1):pwrgd_cpu0_buf_r';
NODE_NAME     R168 2
 '@S9S_MB_2U_LIB.S9S_MB_2U(SCH_1):PAGE124_I43@PURE_QUANTA.Q_RES(CHIPS)':
 'B': CDS_PINID='B';
NODE_NAME     R183 1
 '@S9S_MB_2U_LIB.S9S_MB_2U(SCH_1):PAGE124_I62@PURE_QUANTA.Q_RES(CHIPS)':
 'A': CDS_PINID='A';
NODE_NAME     R184 1
 '@S9S_MB_2U_LIB.S9S_MB_2U(SCH_1):PAGE124_I77@PURE_QUANTA.Q_RES(CHIPS)':
 'A': CDS_PINID='A';
NET_NAME
'PWRGD_CPU0_LVC1'
 '@S9S_MB_2U_LIB.S9S_MB_2U(SCH_1):PWRGD_CPU0_LVC1':
 C_SIGNAL='@s9s_mb_2u_lib.s9s_mb_2u(sch_1):pwrgd_cpu0_lvc1';
NODE_NAME     U2 AV20
 '@S9S_MB_2U_LIB.S9S_MB_2U(SCH_1):PAGE14_I1@PURE_QUANTA.SOCKET4677_AZIF0045P001C01CS(CHIPS)':
 'PWRGOOD': CDS_PINID='PWRGOOD';
NODE_NAME     R184 2
 '@S9S_MB_2U_LIB.S9S_MB_2U(SCH_1):PAGE124_I77@PURE_QUANTA.Q_RES(CHIPS)':
 'B': CDS_PINID='B';
NET_NAME
'PWRGD_CPU0_LVC1_R'
 '@S9S_MB_2U_LIB.S9S_MB_2U(SCH_1):PWRGD_CPU0_LVC1_R':
 C_SIGNAL='@s9s_mb_2u_lib.s9s_mb_2u(sch_1):pwrgd_cpu0_lvc1_r';
NODE_NAME     R168 1
 '@S9S_MB_2U_LIB.S9S_MB_2U(SCH_1):PAGE124_I43@PURE_QUANTA.Q_RES(CHIPS)':
 'A': CDS_PINID='A';
NODE_NAME     R992 1
 '@S9S_MB_2U_LIB.S9S_MB_2U(SCH_1):PAGE208_I21@PURE_QUANTA.Q_RES(CHIPS)':
 'A': CDS_PINID='A';
NODE_NAME     U249 W2
 '@S9S_MB_2U_LIB.S9S_MB_2U(SCH_1):PAGE311_I33@PURE_QUANTA.LCMXO3LF9400C5BG484C(CHIPS)':
 'PL28B': CDS_PINID='PL28B';
NET_NAME
'PWRGD_CPU1_BUF_R'
 '@S9S_MB_2U_LIB.S9S_MB_2U(SCH_1):PWRGD_CPU1_BUF_R':
 C_SIGNAL='@s9s_mb_2u_lib.s9s_mb_2u(sch_1):pwrgd_cpu1_buf_r';
NODE_NAME     R130 2
 '@S9S_MB_2U_LIB.S9S_MB_2U(SCH_1):PAGE125_I5@PURE_QUANTA.Q_RES(CHIPS)':
 'B': CDS_PINID='B';
NODE_NAME     R155 1
 '@S9S_MB_2U_LIB.S9S_MB_2U(SCH_1):PAGE125_I26@PURE_QUANTA.Q_RES(CHIPS)':
 'A': CDS_PINID='A';
NODE_NAME     R156 1
 '@S9S_MB_2U_LIB.S9S_MB_2U(SCH_1):PAGE125_I64@PURE_QUANTA.Q_RES(CHIPS)':
 'A': CDS_PINID='A';
NET_NAME
'PWRGD_CPU1_LVC1'
 '@S9S_MB_2U_LIB.S9S_MB_2U(SCH_1):PWRGD_CPU1_LVC1':
 C_SIGNAL='@s9s_mb_2u_lib.s9s_mb_2u(sch_1):pwrgd_cpu1_lvc1';
NODE_NAME     U1 AV20
 '@S9S_MB_2U_LIB.S9S_MB_2U(SCH_1):PAGE45_I29@PURE_QUANTA.SOCKET4677_AZIF0045P001C01CS(CHIPS)':
 'PWRGOOD': CDS_PINID='PWRGOOD';
NODE_NAME     R156 2
 '@S9S_MB_2U_LIB.S9S_MB_2U(SCH_1):PAGE125_I64@PURE_QUANTA.Q_RES(CHIPS)':
 'B': CDS_PINID='B';
NET_NAME
'PWRGD_CPU1_LVC1_R'
 '@S9S_MB_2U_LIB.S9S_MB_2U(SCH_1):PWRGD_CPU1_LVC1_R':
 C_SIGNAL='@s9s_mb_2u_lib.s9s_mb_2u(sch_1):pwrgd_cpu1_lvc1_r';
NODE_NAME     R130 1
 '@S9S_MB_2U_LIB.S9S_MB_2U(SCH_1):PAGE125_I5@PURE_QUANTA.Q_RES(CHIPS)':
 'A': CDS_PINID='A';
NODE_NAME     R1398 1
 '@S9S_MB_2U_LIB.S9S_MB_2U(SCH_1):PAGE208_I22@PURE_QUANTA.Q_RES(CHIPS)':
 'A': CDS_PINID='A';
NODE_NAME     U249 W1
 '@S9S_MB_2U_LIB.S9S_MB_2U(SCH_1):PAGE311_I33@PURE_QUANTA.LCMXO3LF9400C5BG484C(CHIPS)':
 'PL28A': CDS_PINID='PL28A';
NET_NAME
'PWRGD_CPUPWRGD_GTL'
 '@S9S_MB_2U_LIB.S9S_MB_2U(SCH_1):PWRGD_CPUPWRGD_GTL':
 C_SIGNAL='@s9s_mb_2u_lib.s9s_mb_2u(sch_1):pwrgd_cpupwrgd_gtl';
NODE_NAME     R315 1
 '@S9S_MB_2U_LIB.S9S_MB_2U(SCH_1):PAGE118_I92@PURE_QUANTA.Q_RES(CHIPS)':
 'A': CDS_PINID='A';
NODE_NAME     U4 G10
 '@S9S_MB_2U_LIB.S9S_MB_2U(SCH_1):PAGE174_I36@PURE_QUANTA.EMMITSBURG_REV0P9(CHIPS)':
 'CPUPWRGD': CDS_PINID='CPUPWRGD';
NET_NAME
'PWRGD_CPUPWRGD_LVC1'
 '@S9S_MB_2U_LIB.S9S_MB_2U(SCH_1):PWRGD_CPUPWRGD_LVC1':
 C_SIGNAL='@s9s_mb_2u_lib.s9s_mb_2u(sch_1):pwrgd_cpupwrgd_lvc1';
NODE_NAME     R1443 1
 '@S9S_MB_2U_LIB.S9S_MB_2U(SCH_1):PAGE211_I49@PURE_QUANTA.Q_RES(CHIPS)':
 'A': CDS_PINID='A';
NODE_NAME     U301 6
 '@S9S_MB_2U_LIB.S9S_MB_2U(SCH_1):PAGE321_I91@PURE_QUANTA.GTL2014PW(CHIPS)':
 'B3': CDS_PINID='B3';
NET_NAME
'PWRGD_CPUPWRGD_LVC1_R'
 '@S9S_MB_2U_LIB.S9S_MB_2U(SCH_1):PWRGD_CPUPWRGD_LVC1_R':
 C_SIGNAL='@s9s_mb_2u_lib.s9s_mb_2u(sch_1):pwrgd_cpupwrgd_lvc1_r';
NODE_NAME     R315 2
 '@S9S_MB_2U_LIB.S9S_MB_2U(SCH_1):PAGE118_I92@PURE_QUANTA.Q_RES(CHIPS)':
 'B': CDS_PINID='B';
NODE_NAME     R1443 2
 '@S9S_MB_2U_LIB.S9S_MB_2U(SCH_1):PAGE211_I49@PURE_QUANTA.Q_RES(CHIPS)':
 'B': CDS_PINID='B';
NET_NAME
'PWRGD_CPUPWRGD_LVC2_R'
 '@S9S_MB_2U_LIB.S9S_MB_2U(SCH_1):PWRGD_CPUPWRGD_LVC2_R':
 C_SIGNAL='@s9s_mb_2u_lib.s9s_mb_2u(sch_1):pwrgd_cpupwrgd_lvc2_r';
NODE_NAME     R4021 1
 '@S9S_MB_2U_LIB.S9S_MB_2U(SCH_1):PAGE321_I78@PURE_QUANTA.Q_RES(CHIPS)':
 'A': CDS_PINID='A';
NODE_NAME     U301 9
 '@S9S_MB_2U_LIB.S9S_MB_2U(SCH_1):PAGE321_I91@PURE_QUANTA.GTL2014PW(CHIPS)':
 'A3': CDS_PINID='A3';
NET_NAME
'PWRGD_CPUPWRGD_LVC2_R1'
 '@S9S_MB_2U_LIB.S9S_MB_2U(SCH_1):PWRGD_CPUPWRGD_LVC2_R1':
 C_SIGNAL='@s9s_mb_2u_lib.s9s_mb_2u(sch_1):pwrgd_cpupwrgd_lvc2_r1';
NODE_NAME     Q88 2
 '@S9S_MB_2U_LIB.S9S_MB_2U(SCH_1):PAGE241_I8@PURE_QUANTA.MOSFET_NCH_DUAL(CHIPS)':
 'G1': CDS_PINID='G1';
NODE_NAME     U249 P5
 '@S9S_MB_2U_LIB.S9S_MB_2U(SCH_1):PAGE311_I33@PURE_QUANTA.LCMXO3LF9400C5BG484C(CHIPS)':
 'PL21C': CDS_PINID='PL21C';
NODE_NAME     R4021 2
 '@S9S_MB_2U_LIB.S9S_MB_2U(SCH_1):PAGE321_I78@PURE_QUANTA.Q_RES(CHIPS)':
 'B': CDS_PINID='B';
NET_NAME
'PWRGD_DRAMPWRGD_CPU0_AB_LVC1_R'
 '@S9S_MB_2U_LIB.S9S_MB_2U(SCH_1):PWRGD_DRAMPWRGD_CPU0_AB_LVC1_R':
 C_SIGNAL='@s9s_mb_2u_lib.s9s_mb_2u(sch_1):pwrgd_drampwrgd_cpu0_ab_lvc1_r';
NODE_NAME     U2 A43
 '@S9S_MB_2U_LIB.S9S_MB_2U(SCH_1):PAGE14_I1@PURE_QUANTA.SOCKET4677_AZIF0045P001C01CS(CHIPS)':
 'DDR01_DRAM_PWR_OK': CDS_PINID='DDR01_DRAM_PWR_OK';
NODE_NAME     R4295 2
 '@S9S_MB_2U_LIB.S9S_MB_2U(SCH_1):PAGE124_I87@PURE_QUANTA.Q_RES(CHIPS)':
 'B': CDS_PINID='B';
NET_NAME
'PWRGD_DRAMPWRGD_CPU0_AB_LVC1_R2'
 '@S9S_MB_2U_LIB.S9S_MB_2U(SCH_1):PWRGD_DRAMPWRGD_CPU0_AB_LVC1_R2':
 C_SIGNAL='@s9s_mb_2u_lib.s9s_mb_2u(sch_1):pwrgd_drampwrgd_cpu0_ab_lvc1_r2';
NODE_NAME     R160 2
 '@S9S_MB_2U_LIB.S9S_MB_2U(SCH_1):PAGE124_I17@PURE_QUANTA.Q_RES(CHIPS)':
 'B': CDS_PINID='B';
NODE_NAME     R175 1
 '@S9S_MB_2U_LIB.S9S_MB_2U(SCH_1):PAGE124_I76@PURE_QUANTA.Q_RES(CHIPS)':
 'A': CDS_PINID='A';
NODE_NAME     R4295 1
 '@S9S_MB_2U_LIB.S9S_MB_2U(SCH_1):PAGE124_I87@PURE_QUANTA.Q_RES(CHIPS)':
 'A': CDS_PINID='A';
NET_NAME
'PWRGD_DRAMPWRGD_CPU0_AB_R_LVC1'
 '@S9S_MB_2U_LIB.S9S_MB_2U(SCH_1):PWRGD_DRAMPWRGD_CPU0_AB_R_LVC1':
 C_SIGNAL='@s9s_mb_2u_lib.s9s_mb_2u(sch_1):pwrgd_drampwrgd_cpu0_ab_r_lvc1';
NODE_NAME     R160 1
 '@S9S_MB_2U_LIB.S9S_MB_2U(SCH_1):PAGE124_I17@PURE_QUANTA.Q_RES(CHIPS)':
 'A': CDS_PINID='A';
NODE_NAME     R1302 1
 '@S9S_MB_2U_LIB.S9S_MB_2U(SCH_1):PAGE208_I12@PURE_QUANTA.Q_RES(CHIPS)':
 'A': CDS_PINID='A';
NODE_NAME     U249 G2
 '@S9S_MB_2U_LIB.S9S_MB_2U(SCH_1):PAGE311_I33@PURE_QUANTA.LCMXO3LF9400C5BG484C(CHIPS)':
 'PL7A||PCLKT5_0': CDS_PINID='\pl7a||pclkt5_0\';
NET_NAME
'PWRGD_DRAMPWRGD_CPU0_CD_LVC1_R'
 '@S9S_MB_2U_LIB.S9S_MB_2U(SCH_1):PWRGD_DRAMPWRGD_CPU0_CD_LVC1_R':
 C_SIGNAL='@s9s_mb_2u_lib.s9s_mb_2u(sch_1):pwrgd_drampwrgd_cpu0_cd_lvc1_r';
NODE_NAME     U2 F47
 '@S9S_MB_2U_LIB.S9S_MB_2U(SCH_1):PAGE14_I1@PURE_QUANTA.SOCKET4677_AZIF0045P001C01CS(CHIPS)':
 'DDR23_DRAM_PWR_OK': CDS_PINID='DDR23_DRAM_PWR_OK';
NODE_NAME     R4296 2
 '@S9S_MB_2U_LIB.S9S_MB_2U(SCH_1):PAGE124_I85@PURE_QUANTA.Q_RES(CHIPS)':
 'B': CDS_PINID='B';
NET_NAME
'PWRGD_DRAMPWRGD_CPU0_CD_LVC1_R2'
 '@S9S_MB_2U_LIB.S9S_MB_2U(SCH_1):PWRGD_DRAMPWRGD_CPU0_CD_LVC1_R2':
 C_SIGNAL='@s9s_mb_2u_lib.s9s_mb_2u(sch_1):pwrgd_drampwrgd_cpu0_cd_lvc1_r2';
NODE_NAME     R162 2
 '@S9S_MB_2U_LIB.S9S_MB_2U(SCH_1):PAGE124_I19@PURE_QUANTA.Q_RES(CHIPS)':
 'B': CDS_PINID='B';
NODE_NAME     R177 1
 '@S9S_MB_2U_LIB.S9S_MB_2U(SCH_1):PAGE124_I72@PURE_QUANTA.Q_RES(CHIPS)':
 'A': CDS_PINID='A';
NODE_NAME     R4296 1
 '@S9S_MB_2U_LIB.S9S_MB_2U(SCH_1):PAGE124_I85@PURE_QUANTA.Q_RES(CHIPS)':
 'A': CDS_PINID='A';
NET_NAME
'PWRGD_DRAMPWRGD_CPU0_CD_R_LVC1'
 '@S9S_MB_2U_LIB.S9S_MB_2U(SCH_1):PWRGD_DRAMPWRGD_CPU0_CD_R_LVC1':
 C_SIGNAL='@s9s_mb_2u_lib.s9s_mb_2u(sch_1):pwrgd_drampwrgd_cpu0_cd_r_lvc1';
NODE_NAME     R162 1
 '@S9S_MB_2U_LIB.S9S_MB_2U(SCH_1):PAGE124_I19@PURE_QUANTA.Q_RES(CHIPS)':
 'A': CDS_PINID='A';
NODE_NAME     R1326 1
 '@S9S_MB_2U_LIB.S9S_MB_2U(SCH_1):PAGE208_I11@PURE_QUANTA.Q_RES(CHIPS)':
 'A': CDS_PINID='A';
NODE_NAME     U249 G1
 '@S9S_MB_2U_LIB.S9S_MB_2U(SCH_1):PAGE311_I33@PURE_QUANTA.LCMXO3LF9400C5BG484C(CHIPS)':
 'PL7B||PCLKC5_0': CDS_PINID='\pl7b||pclkc5_0\';
NET_NAME
'PWRGD_DRAMPWRGD_CPU0_EF_LVC1_R'
 '@S9S_MB_2U_LIB.S9S_MB_2U(SCH_1):PWRGD_DRAMPWRGD_CPU0_EF_LVC1_R':
 C_SIGNAL='@s9s_mb_2u_lib.s9s_mb_2u(sch_1):pwrgd_drampwrgd_cpu0_ef_lvc1_r';
NODE_NAME     U2 CY44
 '@S9S_MB_2U_LIB.S9S_MB_2U(SCH_1):PAGE14_I1@PURE_QUANTA.SOCKET4677_AZIF0045P001C01CS(CHIPS)':
 'DDR45_DRAM_PWR_OK': CDS_PINID='DDR45_DRAM_PWR_OK';
NODE_NAME     R4297 2
 '@S9S_MB_2U_LIB.S9S_MB_2U(SCH_1):PAGE124_I82@PURE_QUANTA.Q_RES(CHIPS)':
 'B': CDS_PINID='B';
NET_NAME
'PWRGD_DRAMPWRGD_CPU0_EF_LVC1_R2'
 '@S9S_MB_2U_LIB.S9S_MB_2U(SCH_1):PWRGD_DRAMPWRGD_CPU0_EF_LVC1_R2':
 C_SIGNAL='@s9s_mb_2u_lib.s9s_mb_2u(sch_1):pwrgd_drampwrgd_cpu0_ef_lvc1_r2';
NODE_NAME     R164 2
 '@S9S_MB_2U_LIB.S9S_MB_2U(SCH_1):PAGE124_I26@PURE_QUANTA.Q_RES(CHIPS)':
 'B': CDS_PINID='B';
NODE_NAME     R179 1
 '@S9S_MB_2U_LIB.S9S_MB_2U(SCH_1):PAGE124_I70@PURE_QUANTA.Q_RES(CHIPS)':
 'A': CDS_PINID='A';
NODE_NAME     R4297 1
 '@S9S_MB_2U_LIB.S9S_MB_2U(SCH_1):PAGE124_I82@PURE_QUANTA.Q_RES(CHIPS)':
 'A': CDS_PINID='A';
NET_NAME
'PWRGD_DRAMPWRGD_CPU0_EF_R_LVC1'
 '@S9S_MB_2U_LIB.S9S_MB_2U(SCH_1):PWRGD_DRAMPWRGD_CPU0_EF_R_LVC1':
 C_SIGNAL='@s9s_mb_2u_lib.s9s_mb_2u(sch_1):pwrgd_drampwrgd_cpu0_ef_r_lvc1';
NODE_NAME     R164 1
 '@S9S_MB_2U_LIB.S9S_MB_2U(SCH_1):PAGE124_I26@PURE_QUANTA.Q_RES(CHIPS)':
 'A': CDS_PINID='A';
NODE_NAME     R1327 1
 '@S9S_MB_2U_LIB.S9S_MB_2U(SCH_1):PAGE208_I14@PURE_QUANTA.Q_RES(CHIPS)':
 'A': CDS_PINID='A';
NODE_NAME     U249 H4
 '@S9S_MB_2U_LIB.S9S_MB_2U(SCH_1):PAGE311_I33@PURE_QUANTA.LCMXO3LF9400C5BG484C(CHIPS)':
 'PL7C': CDS_PINID='PL7C';
NET_NAME
'PWRGD_DRAMPWRGD_CPU0_GH_LVC1_R'
 '@S9S_MB_2U_LIB.S9S_MB_2U(SCH_1):PWRGD_DRAMPWRGD_CPU0_GH_LVC1_R':
 C_SIGNAL='@s9s_mb_2u_lib.s9s_mb_2u(sch_1):pwrgd_drampwrgd_cpu0_gh_lvc1_r';
NODE_NAME     U2 CW45
 '@S9S_MB_2U_LIB.S9S_MB_2U(SCH_1):PAGE14_I1@PURE_QUANTA.SOCKET4677_AZIF0045P001C01CS(CHIPS)':
 'DDR67_DRAM_PWR_OK': CDS_PINID='DDR67_DRAM_PWR_OK';
NODE_NAME     R4298 2
 '@S9S_MB_2U_LIB.S9S_MB_2U(SCH_1):PAGE124_I79@PURE_QUANTA.Q_RES(CHIPS)':
 'B': CDS_PINID='B';
NET_NAME
'PWRGD_DRAMPWRGD_CPU0_GH_LVC1_R2'
 '@S9S_MB_2U_LIB.S9S_MB_2U(SCH_1):PWRGD_DRAMPWRGD_CPU0_GH_LVC1_R2':
 C_SIGNAL='@s9s_mb_2u_lib.s9s_mb_2u(sch_1):pwrgd_drampwrgd_cpu0_gh_lvc1_r2';
NODE_NAME     R166 2
 '@S9S_MB_2U_LIB.S9S_MB_2U(SCH_1):PAGE124_I33@PURE_QUANTA.Q_RES(CHIPS)':
 'B': CDS_PINID='B';
NODE_NAME     R181 1
 '@S9S_MB_2U_LIB.S9S_MB_2U(SCH_1):PAGE124_I68@PURE_QUANTA.Q_RES(CHIPS)':
 'A': CDS_PINID='A';
NODE_NAME     R4298 1
 '@S9S_MB_2U_LIB.S9S_MB_2U(SCH_1):PAGE124_I79@PURE_QUANTA.Q_RES(CHIPS)':
 'A': CDS_PINID='A';
NET_NAME
'PWRGD_DRAMPWRGD_CPU0_GH_R_LVC1'
 '@S9S_MB_2U_LIB.S9S_MB_2U(SCH_1):PWRGD_DRAMPWRGD_CPU0_GH_R_LVC1':
 C_SIGNAL='@s9s_mb_2u_lib.s9s_mb_2u(sch_1):pwrgd_drampwrgd_cpu0_gh_r_lvc1';
NODE_NAME     R166 1
 '@S9S_MB_2U_LIB.S9S_MB_2U(SCH_1):PAGE124_I33@PURE_QUANTA.Q_RES(CHIPS)':
 'A': CDS_PINID='A';
NODE_NAME     R1328 1
 '@S9S_MB_2U_LIB.S9S_MB_2U(SCH_1):PAGE208_I13@PURE_QUANTA.Q_RES(CHIPS)':
 'A': CDS_PINID='A';
NODE_NAME     U249 H3
 '@S9S_MB_2U_LIB.S9S_MB_2U(SCH_1):PAGE311_I33@PURE_QUANTA.LCMXO3LF9400C5BG484C(CHIPS)':
 'PL7D': CDS_PINID='PL7D';
NET_NAME
'PWRGD_DRAMPWRGD_CPU1_AB_LVC1_R'
 '@S9S_MB_2U_LIB.S9S_MB_2U(SCH_1):PWRGD_DRAMPWRGD_CPU1_AB_LVC1_R':
 C_SIGNAL='@s9s_mb_2u_lib.s9s_mb_2u(sch_1):pwrgd_drampwrgd_cpu1_ab_lvc1_r';
NODE_NAME     U1 A43
 '@S9S_MB_2U_LIB.S9S_MB_2U(SCH_1):PAGE45_I29@PURE_QUANTA.SOCKET4677_AZIF0045P001C01CS(CHIPS)':
 'DDR01_DRAM_PWR_OK': CDS_PINID='DDR01_DRAM_PWR_OK';
NODE_NAME     R4299 2
 '@S9S_MB_2U_LIB.S9S_MB_2U(SCH_1):PAGE125_I72@PURE_QUANTA.Q_RES(CHIPS)':
 'B': CDS_PINID='B';
NET_NAME
'PWRGD_DRAMPWRGD_CPU1_AB_LVC1_R2'
 '@S9S_MB_2U_LIB.S9S_MB_2U(SCH_1):PWRGD_DRAMPWRGD_CPU1_AB_LVC1_R2':
 C_SIGNAL='@s9s_mb_2u_lib.s9s_mb_2u(sch_1):pwrgd_drampwrgd_cpu1_ab_lvc1_r2';
NODE_NAME     R122 2
 '@S9S_MB_2U_LIB.S9S_MB_2U(SCH_1):PAGE125_I17@PURE_QUANTA.Q_RES(CHIPS)':
 'B': CDS_PINID='B';
NODE_NAME     R135 1
 '@S9S_MB_2U_LIB.S9S_MB_2U(SCH_1):PAGE125_I62@PURE_QUANTA.Q_RES(CHIPS)':
 'A': CDS_PINID='A';
NODE_NAME     R4299 1
 '@S9S_MB_2U_LIB.S9S_MB_2U(SCH_1):PAGE125_I72@PURE_QUANTA.Q_RES(CHIPS)':
 'A': CDS_PINID='A';
NET_NAME
'PWRGD_DRAMPWRGD_CPU1_AB_R_LVC1'
 '@S9S_MB_2U_LIB.S9S_MB_2U(SCH_1):PWRGD_DRAMPWRGD_CPU1_AB_R_LVC1':
 C_SIGNAL='@s9s_mb_2u_lib.s9s_mb_2u(sch_1):pwrgd_drampwrgd_cpu1_ab_r_lvc1';
NODE_NAME     R122 1
 '@S9S_MB_2U_LIB.S9S_MB_2U(SCH_1):PAGE125_I17@PURE_QUANTA.Q_RES(CHIPS)':
 'A': CDS_PINID='A';
NODE_NAME     R1329 1
 '@S9S_MB_2U_LIB.S9S_MB_2U(SCH_1):PAGE208_I15@PURE_QUANTA.Q_RES(CHIPS)':
 'A': CDS_PINID='A';
NODE_NAME     U249 H2
 '@S9S_MB_2U_LIB.S9S_MB_2U(SCH_1):PAGE311_I33@PURE_QUANTA.LCMXO3LF9400C5BG484C(CHIPS)':
 'PL10A': CDS_PINID='PL10A';
NET_NAME
'PWRGD_DRAMPWRGD_CPU1_CD_LVC1_R'
 '@S9S_MB_2U_LIB.S9S_MB_2U(SCH_1):PWRGD_DRAMPWRGD_CPU1_CD_LVC1_R':
 C_SIGNAL='@s9s_mb_2u_lib.s9s_mb_2u(sch_1):pwrgd_drampwrgd_cpu1_cd_lvc1_r';
NODE_NAME     U1 F47
 '@S9S_MB_2U_LIB.S9S_MB_2U(SCH_1):PAGE45_I29@PURE_QUANTA.SOCKET4677_AZIF0045P001C01CS(CHIPS)':
 'DDR23_DRAM_PWR_OK': CDS_PINID='DDR23_DRAM_PWR_OK';
NODE_NAME     R4300 2
 '@S9S_MB_2U_LIB.S9S_MB_2U(SCH_1):PAGE125_I70@PURE_QUANTA.Q_RES(CHIPS)':
 'B': CDS_PINID='B';
NET_NAME
'PWRGD_DRAMPWRGD_CPU1_CD_LVC1_R2'
 '@S9S_MB_2U_LIB.S9S_MB_2U(SCH_1):PWRGD_DRAMPWRGD_CPU1_CD_LVC1_R2':
 C_SIGNAL='@s9s_mb_2u_lib.s9s_mb_2u(sch_1):pwrgd_drampwrgd_cpu1_cd_lvc1_r2';
NODE_NAME     R124 2
 '@S9S_MB_2U_LIB.S9S_MB_2U(SCH_1):PAGE125_I15@PURE_QUANTA.Q_RES(CHIPS)':
 'B': CDS_PINID='B';
NODE_NAME     R137 1
 '@S9S_MB_2U_LIB.S9S_MB_2U(SCH_1):PAGE125_I60@PURE_QUANTA.Q_RES(CHIPS)':
 'A': CDS_PINID='A';
NODE_NAME     R4300 1
 '@S9S_MB_2U_LIB.S9S_MB_2U(SCH_1):PAGE125_I70@PURE_QUANTA.Q_RES(CHIPS)':
 'A': CDS_PINID='A';
NET_NAME
'PWRGD_DRAMPWRGD_CPU1_CD_R_LVC1'
 '@S9S_MB_2U_LIB.S9S_MB_2U(SCH_1):PWRGD_DRAMPWRGD_CPU1_CD_R_LVC1':
 C_SIGNAL='@s9s_mb_2u_lib.s9s_mb_2u(sch_1):pwrgd_drampwrgd_cpu1_cd_r_lvc1';
NODE_NAME     R124 1
 '@S9S_MB_2U_LIB.S9S_MB_2U(SCH_1):PAGE125_I15@PURE_QUANTA.Q_RES(CHIPS)':
 'A': CDS_PINID='A';
NODE_NAME     R1330 1
 '@S9S_MB_2U_LIB.S9S_MB_2U(SCH_1):PAGE208_I16@PURE_QUANTA.Q_RES(CHIPS)':
 'A': CDS_PINID='A';
NODE_NAME     U249 H1
 '@S9S_MB_2U_LIB.S9S_MB_2U(SCH_1):PAGE311_I33@PURE_QUANTA.LCMXO3LF9400C5BG484C(CHIPS)':
 'PL10B': CDS_PINID='PL10B';
NET_NAME
'PWRGD_DRAMPWRGD_CPU1_EF_LVC1_R'
 '@S9S_MB_2U_LIB.S9S_MB_2U(SCH_1):PWRGD_DRAMPWRGD_CPU1_EF_LVC1_R':
 C_SIGNAL='@s9s_mb_2u_lib.s9s_mb_2u(sch_1):pwrgd_drampwrgd_cpu1_ef_lvc1_r';
NODE_NAME     U1 CY44
 '@S9S_MB_2U_LIB.S9S_MB_2U(SCH_1):PAGE45_I29@PURE_QUANTA.SOCKET4677_AZIF0045P001C01CS(CHIPS)':
 'DDR45_DRAM_PWR_OK': CDS_PINID='DDR45_DRAM_PWR_OK';
NODE_NAME     R4301 2
 '@S9S_MB_2U_LIB.S9S_MB_2U(SCH_1):PAGE125_I68@PURE_QUANTA.Q_RES(CHIPS)':
 'B': CDS_PINID='B';
NET_NAME
'PWRGD_DRAMPWRGD_CPU1_EF_LVC1_R2'
 '@S9S_MB_2U_LIB.S9S_MB_2U(SCH_1):PWRGD_DRAMPWRGD_CPU1_EF_LVC1_R2':
 C_SIGNAL='@s9s_mb_2u_lib.s9s_mb_2u(sch_1):pwrgd_drampwrgd_cpu1_ef_lvc1_r2';
NODE_NAME     R126 2
 '@S9S_MB_2U_LIB.S9S_MB_2U(SCH_1):PAGE125_I13@PURE_QUANTA.Q_RES(CHIPS)':
 'B': CDS_PINID='B';
NODE_NAME     R151 1
 '@S9S_MB_2U_LIB.S9S_MB_2U(SCH_1):PAGE125_I58@PURE_QUANTA.Q_RES(CHIPS)':
 'A': CDS_PINID='A';
NODE_NAME     R4301 1
 '@S9S_MB_2U_LIB.S9S_MB_2U(SCH_1):PAGE125_I68@PURE_QUANTA.Q_RES(CHIPS)':
 'A': CDS_PINID='A';
NET_NAME
'PWRGD_DRAMPWRGD_CPU1_EF_R_LVC1'
 '@S9S_MB_2U_LIB.S9S_MB_2U(SCH_1):PWRGD_DRAMPWRGD_CPU1_EF_R_LVC1':
 C_SIGNAL='@s9s_mb_2u_lib.s9s_mb_2u(sch_1):pwrgd_drampwrgd_cpu1_ef_r_lvc1';
NODE_NAME     R126 1
 '@S9S_MB_2U_LIB.S9S_MB_2U(SCH_1):PAGE125_I13@PURE_QUANTA.Q_RES(CHIPS)':
 'A': CDS_PINID='A';
NODE_NAME     R1388 1
 '@S9S_MB_2U_LIB.S9S_MB_2U(SCH_1):PAGE208_I17@PURE_QUANTA.Q_RES(CHIPS)':
 'A': CDS_PINID='A';
NODE_NAME     U249 J7
 '@S9S_MB_2U_LIB.S9S_MB_2U(SCH_1):PAGE311_I33@PURE_QUANTA.LCMXO3LF9400C5BG484C(CHIPS)':
 'PL10C': CDS_PINID='PL10C';
NET_NAME
'PWRGD_DRAMPWRGD_CPU1_GH_LVC1_R'
 '@S9S_MB_2U_LIB.S9S_MB_2U(SCH_1):PWRGD_DRAMPWRGD_CPU1_GH_LVC1_R':
 C_SIGNAL='@s9s_mb_2u_lib.s9s_mb_2u(sch_1):pwrgd_drampwrgd_cpu1_gh_lvc1_r';
NODE_NAME     U1 CW45
 '@S9S_MB_2U_LIB.S9S_MB_2U(SCH_1):PAGE45_I29@PURE_QUANTA.SOCKET4677_AZIF0045P001C01CS(CHIPS)':
 'DDR67_DRAM_PWR_OK': CDS_PINID='DDR67_DRAM_PWR_OK';
NODE_NAME     R4302 2
 '@S9S_MB_2U_LIB.S9S_MB_2U(SCH_1):PAGE125_I66@PURE_QUANTA.Q_RES(CHIPS)':
 'B': CDS_PINID='B';
NET_NAME
'PWRGD_DRAMPWRGD_CPU1_GH_LVC1_R2'
 '@S9S_MB_2U_LIB.S9S_MB_2U(SCH_1):PWRGD_DRAMPWRGD_CPU1_GH_LVC1_R2':
 C_SIGNAL='@s9s_mb_2u_lib.s9s_mb_2u(sch_1):pwrgd_drampwrgd_cpu1_gh_lvc1_r2';
NODE_NAME     R128 2
 '@S9S_MB_2U_LIB.S9S_MB_2U(SCH_1):PAGE125_I7@PURE_QUANTA.Q_RES(CHIPS)':
 'B': CDS_PINID='B';
NODE_NAME     R153 1
 '@S9S_MB_2U_LIB.S9S_MB_2U(SCH_1):PAGE125_I56@PURE_QUANTA.Q_RES(CHIPS)':
 'A': CDS_PINID='A';
NODE_NAME     R4302 1
 '@S9S_MB_2U_LIB.S9S_MB_2U(SCH_1):PAGE125_I66@PURE_QUANTA.Q_RES(CHIPS)':
 'A': CDS_PINID='A';
NET_NAME
'PWRGD_DRAMPWRGD_CPU1_GH_R_LVC1'
 '@S9S_MB_2U_LIB.S9S_MB_2U(SCH_1):PWRGD_DRAMPWRGD_CPU1_GH_R_LVC1':
 C_SIGNAL='@s9s_mb_2u_lib.s9s_mb_2u(sch_1):pwrgd_drampwrgd_cpu1_gh_r_lvc1';
NODE_NAME     R128 1
 '@S9S_MB_2U_LIB.S9S_MB_2U(SCH_1):PAGE125_I7@PURE_QUANTA.Q_RES(CHIPS)':
 'A': CDS_PINID='A';
NODE_NAME     R4533 1
 '@S9S_MB_2U_LIB.S9S_MB_2U(SCH_1):PAGE208_I19@PURE_QUANTA.Q_RES(CHIPS)':
 'A': CDS_PINID='A';
NODE_NAME     U249 J6
 '@S9S_MB_2U_LIB.S9S_MB_2U(SCH_1):PAGE311_I33@PURE_QUANTA.LCMXO3LF9400C5BG484C(CHIPS)':
 'PL10D': CDS_PINID='PL10D';
NET_NAME
'PWRGD_DSW_PWROK'
 '@S9S_MB_2U_LIB.S9S_MB_2U(SCH_1):PWRGD_DSW_PWROK':
 C_SIGNAL='@s9s_mb_2u_lib.s9s_mb_2u(sch_1):pwrgd_dsw_pwrok';
NODE_NAME     U4 BE8
 '@S9S_MB_2U_LIB.S9S_MB_2U(SCH_1):PAGE174_I36@PURE_QUANTA.EMMITSBURG_REV0P9(CHIPS)':
 'DSW_PWROK': CDS_PINID='DSW_PWROK';
NODE_NAME     R1694 2
 '@S9S_MB_2U_LIB.S9S_MB_2U(SCH_1):PAGE232_I33@PURE_QUANTA.Q_RES(CHIPS)':
 'B': CDS_PINID='B';
NODE_NAME     C1319 1
 '@S9S_MB_2U_LIB.S9S_MB_2U(SCH_1):PAGE232_I35@PURE_QUANTA.Q_CAP(CHIPS)':
 'A': CDS_PINID='A';
NODE_NAME     R2412 1
 '@S9S_MB_2U_LIB.S9S_MB_2U(SCH_1):PAGE313_I83@PURE_QUANTA.Q_RES(CHIPS)':
 'A': CDS_PINID='A';
NODE_NAME     R2330 2
 '@S9S_MB_2U_LIB.S9S_MB_2U(SCH_1):PAGE326_I33@PURE_QUANTA.Q_RES(CHIPS)':
 'B': CDS_PINID='B';
NODE_NAME     R4789 2
 '@S9S_MB_2U_LIB.S9S_MB_2U(SCH_1):PAGE329_I49@PURE_QUANTA.Q_RES(CHIPS)':
 'B': CDS_PINID='B';
NODE_NAME     R4788 2
 '@S9S_MB_2U_LIB.S9S_MB_2U(SCH_1):PAGE329_I50@PURE_QUANTA.Q_RES(CHIPS)':
 'B': CDS_PINID='B';
NODE_NAME     R4808 1
 '@S9S_MB_2U_LIB.S9S_MB_2U(SCH_1):PAGE232_I31@PURE_QUANTA.Q_RES(CHIPS)':
 'A': CDS_PINID='A';
NODE_NAME     R1693 2
 '@S9S_MB_2U_LIB.S9S_MB_2U(SCH_1):PAGE232_I32@PURE_QUANTA.Q_RES(CHIPS)':
 'B': CDS_PINID='B';
NODE_NAME     R1695 1
 '@S9S_MB_2U_LIB.S9S_MB_2U(SCH_1):PAGE232_I36@PURE_QUANTA.Q_RES(CHIPS)':
 'A': CDS_PINID='A';
NET_NAME
'PWRGD_DSW_PWROK_R1'
 '@S9S_MB_2U_LIB.S9S_MB_2U(SCH_1):PWRGD_DSW_PWROK_R1':
 C_SIGNAL='@s9s_mb_2u_lib.s9s_mb_2u(sch_1):pwrgd_dsw_pwrok_r1';
NODE_NAME     R1691 2
 '@S9S_MB_2U_LIB.S9S_MB_2U(SCH_1):PAGE232_I4@PURE_QUANTA.Q_RES(CHIPS)':
 'B': CDS_PINID='B';
NODE_NAME     R1692 1
 '@S9S_MB_2U_LIB.S9S_MB_2U(SCH_1):PAGE232_I3@PURE_QUANTA.Q_RES(CHIPS)':
 'A': CDS_PINID='A';
NODE_NAME     C1318 1
 '@S9S_MB_2U_LIB.S9S_MB_2U(SCH_1):PAGE232_I7@PURE_QUANTA.Q_CAP(CHIPS)':
 'A': CDS_PINID='A';
NODE_NAME     U95 2
 '@S9S_MB_2U_LIB.S9S_MB_2U(SCH_1):PAGE232_I11@PURE_QUANTA.74LVC1G07SE7(CHIPS)':
 'A': CDS_PINID='A';
NODE_NAME     R4807 1
 '@S9S_MB_2U_LIB.S9S_MB_2U(SCH_1):PAGE232_I13@PURE_QUANTA.Q_RES(CHIPS)':
 'A': CDS_PINID='A';
NODE_NAME     U117 4
 '@S9S_MB_2U_LIB.S9S_MB_2U(SCH_1):PAGE232_I26@PURE_QUANTA.TPS3895ADRYR(CHIPS)':
 'SENSE_OUT': CDS_PINID='SENSE_OUT';
NODE_NAME     U94 4
 '@S9S_MB_2U_LIB.S9S_MB_2U(SCH_1):PAGE232_I27@PURE_QUANTA.ADM1086AKSZREEL7(CHIPS)':
 'ENOUT': CDS_PINID='ENOUT';
NET_NAME
'PWRGD_DSW_PWROK_R2'
 '@S9S_MB_2U_LIB.S9S_MB_2U(SCH_1):PWRGD_DSW_PWROK_R2':
 C_SIGNAL='@s9s_mb_2u_lib.s9s_mb_2u(sch_1):pwrgd_dsw_pwrok_r2';
NODE_NAME     U95 4
 '@S9S_MB_2U_LIB.S9S_MB_2U(SCH_1):PAGE232_I11@PURE_QUANTA.74LVC1G07SE7(CHIPS)':
 'Y': CDS_PINID='Y';
NODE_NAME     R4807 2
 '@S9S_MB_2U_LIB.S9S_MB_2U(SCH_1):PAGE232_I13@PURE_QUANTA.Q_RES(CHIPS)':
 'B': CDS_PINID='B';
NODE_NAME     R1693 1
 '@S9S_MB_2U_LIB.S9S_MB_2U(SCH_1):PAGE232_I32@PURE_QUANTA.Q_RES(CHIPS)':
 'A': CDS_PINID='A';
NET_NAME
'PWRGD_DSW_PWROK_R3'
 '@S9S_MB_2U_LIB.S9S_MB_2U(SCH_1):PWRGD_DSW_PWROK_R3':
 C_SIGNAL='@s9s_mb_2u_lib.s9s_mb_2u(sch_1):pwrgd_dsw_pwrok_r3';
NODE_NAME     U249 T22
 '@S9S_MB_2U_LIB.S9S_MB_2U(SCH_1):PAGE313_I1@PURE_QUANTA.LCMXO3LF9400C5BG484C(CHIPS)':
 'PR21A': CDS_PINID='PR21A';
NODE_NAME     R2412 2
 '@S9S_MB_2U_LIB.S9S_MB_2U(SCH_1):PAGE313_I83@PURE_QUANTA.Q_RES(CHIPS)':
 'B': CDS_PINID='B';
NET_NAME
'PWRGD_DSW_PWROK_R4'
 '@S9S_MB_2U_LIB.S9S_MB_2U(SCH_1):PWRGD_DSW_PWROK_R4':
 C_SIGNAL='@s9s_mb_2u_lib.s9s_mb_2u(sch_1):pwrgd_dsw_pwrok_r4';
NODE_NAME     U205 1
 '@S9S_MB_2U_LIB.S9S_MB_2U(SCH_1):PAGE326_I5@PURE_QUANTA.TPS3700DDCR(CHIPS)':
 'OUTA': CDS_PINID='OUTA';
NODE_NAME     R2330 1
 '@S9S_MB_2U_LIB.S9S_MB_2U(SCH_1):PAGE326_I33@PURE_QUANTA.Q_RES(CHIPS)':
 'A': CDS_PINID='A';
NET_NAME
'PWRGD_DSW_PWROK_R5'
 '@S9S_MB_2U_LIB.S9S_MB_2U(SCH_1):PWRGD_DSW_PWROK_R5':
 C_SIGNAL='@s9s_mb_2u_lib.s9s_mb_2u(sch_1):pwrgd_dsw_pwrok_r5';
NODE_NAME     U342 4
 '@S9S_MB_2U_LIB.S9S_MB_2U(SCH_1):PAGE329_I45@PURE_QUANTA.AP331AWG7(CHIPS)':
 'OUTPUT': CDS_PINID='OUTPUT';
NODE_NAME     R4787 2
 '@S9S_MB_2U_LIB.S9S_MB_2U(SCH_1):PAGE329_I46@PURE_QUANTA.Q_RES(CHIPS)':
 'B': CDS_PINID='B';
NODE_NAME     R4788 1
 '@S9S_MB_2U_LIB.S9S_MB_2U(SCH_1):PAGE329_I50@PURE_QUANTA.Q_RES(CHIPS)':
 'A': CDS_PINID='A';
NET_NAME
'PWRGD_DSW_PWROK_TRIGGER'
 '@S9S_MB_2U_LIB.S9S_MB_2U(SCH_1):PWRGD_DSW_PWROK_TRIGGER':
 C_SIGNAL='@s9s_mb_2u_lib.s9s_mb_2u(sch_1):pwrgd_dsw_pwrok_trigger';
NODE_NAME     U342 3
 '@S9S_MB_2U_LIB.S9S_MB_2U(SCH_1):PAGE329_I45@PURE_QUANTA.AP331AWG7(CHIPS)':
 'IN+': CDS_PINID='\in+\';
NODE_NAME     R4787 1
 '@S9S_MB_2U_LIB.S9S_MB_2U(SCH_1):PAGE329_I46@PURE_QUANTA.Q_RES(CHIPS)':
 'A': CDS_PINID='A';
NODE_NAME     C2386 1
 '@S9S_MB_2U_LIB.S9S_MB_2U(SCH_1):PAGE329_I55@PURE_QUANTA.Q_CAP(CHIPS)':
 'A': CDS_PINID='A';
NODE_NAME     R4790 2
 '@S9S_MB_2U_LIB.S9S_MB_2U(SCH_1):PAGE329_I67@PURE_QUANTA.Q_RES(CHIPS)':
 'B': CDS_PINID='B';
NODE_NAME     R4791 1
 '@S9S_MB_2U_LIB.S9S_MB_2U(SCH_1):PAGE329_I68@PURE_QUANTA.Q_RES(CHIPS)':
 'A': CDS_PINID='A';
NET_NAME
'PWRGD_FAIL_CPU0_AB'
 '@S9S_MB_2U_LIB.S9S_MB_2U(SCH_1):PWRGD_FAIL_CPU0_AB':
 C_SIGNAL='@s9s_mb_2u_lib.s9s_mb_2u(sch_1):pwrgd_fail_cpu0_ab';
NODE_NAME     R2490 1
 '@S9S_MB_2U_LIB.S9S_MB_2U(SCH_1):PAGE115_I46@PURE_QUANTA.Q_RES(CHIPS)':
 'A': CDS_PINID='A';
NODE_NAME     R880 2
 '@S9S_MB_2U_LIB.S9S_MB_2U(SCH_1):PAGE114_I29@PURE_QUANTA.Q_RES(CHIPS)':
 'B': CDS_PINID='B';
NODE_NAME     R2728 2
 '@S9S_MB_2U_LIB.S9S_MB_2U(SCH_1):PAGE114_I30@PURE_QUANTA.Q_RES(CHIPS)':
 'B': CDS_PINID='B';
NODE_NAME     R2727 2
 '@S9S_MB_2U_LIB.S9S_MB_2U(SCH_1):PAGE114_I31@PURE_QUANTA.Q_RES(CHIPS)':
 'B': CDS_PINID='B';
NODE_NAME     R2726 2
 '@S9S_MB_2U_LIB.S9S_MB_2U(SCH_1):PAGE114_I32@PURE_QUANTA.Q_RES(CHIPS)':
 'B': CDS_PINID='B';
NET_NAME
'PWRGD_FAIL_CPU0_AB_R'
 '@S9S_MB_2U_LIB.S9S_MB_2U(SCH_1):PWRGD_FAIL_CPU0_AB_R':
 C_SIGNAL='@s9s_mb_2u_lib.s9s_mb_2u(sch_1):pwrgd_fail_cpu0_ab_r';
NODE_NAME     U249 W22
 '@S9S_MB_2U_LIB.S9S_MB_2U(SCH_1):PAGE313_I1@PURE_QUANTA.LCMXO3LF9400C5BG484C(CHIPS)':
 'PR25B': CDS_PINID='PR25B';
NODE_NAME     R2498 2
 '@S9S_MB_2U_LIB.S9S_MB_2U(SCH_1):PAGE115_I72@PURE_QUANTA.Q_RES(CHIPS)':
 'B': CDS_PINID='B';
NET_NAME
'PWRGD_FAIL_CPU0_AB_R1'
 '@S9S_MB_2U_LIB.S9S_MB_2U(SCH_1):PWRGD_FAIL_CPU0_AB_R1':
 C_SIGNAL='@s9s_mb_2u_lib.s9s_mb_2u(sch_1):pwrgd_fail_cpu0_ab_r1';
NODE_NAME     R2490 2
 '@S9S_MB_2U_LIB.S9S_MB_2U(SCH_1):PAGE115_I46@PURE_QUANTA.Q_RES(CHIPS)':
 'B': CDS_PINID='B';
NODE_NAME     R940 2
 '@S9S_MB_2U_LIB.S9S_MB_2U(SCH_1):PAGE115_I48@PURE_QUANTA.Q_RES(CHIPS)':
 'B': CDS_PINID='B';
NODE_NAME     D42 1
 '@S9S_MB_2U_LIB.S9S_MB_2U(SCH_1):PAGE115_I59@PURE_QUANTA.SCHOTTKY_12(CHIPS)':
 'A': CDS_PINID='A';
NODE_NAME     R2498 1
 '@S9S_MB_2U_LIB.S9S_MB_2U(SCH_1):PAGE115_I72@PURE_QUANTA.Q_RES(CHIPS)':
 'A': CDS_PINID='A';
NET_NAME
'PWRGD_FAIL_CPU0_CD'
 '@S9S_MB_2U_LIB.S9S_MB_2U(SCH_1):PWRGD_FAIL_CPU0_CD':
 C_SIGNAL='@s9s_mb_2u_lib.s9s_mb_2u(sch_1):pwrgd_fail_cpu0_cd';
NODE_NAME     R2491 1
 '@S9S_MB_2U_LIB.S9S_MB_2U(SCH_1):PAGE115_I42@PURE_QUANTA.Q_RES(CHIPS)':
 'A': CDS_PINID='A';
NODE_NAME     R884 2
 '@S9S_MB_2U_LIB.S9S_MB_2U(SCH_1):PAGE114_I26@PURE_QUANTA.Q_RES(CHIPS)':
 'B': CDS_PINID='B';
NODE_NAME     R2729 2
 '@S9S_MB_2U_LIB.S9S_MB_2U(SCH_1):PAGE114_I28@PURE_QUANTA.Q_RES(CHIPS)':
 'B': CDS_PINID='B';
NODE_NAME     R2731 2
 '@S9S_MB_2U_LIB.S9S_MB_2U(SCH_1):PAGE114_I25@PURE_QUANTA.Q_RES(CHIPS)':
 'B': CDS_PINID='B';
NODE_NAME     R2730 2
 '@S9S_MB_2U_LIB.S9S_MB_2U(SCH_1):PAGE114_I27@PURE_QUANTA.Q_RES(CHIPS)':
 'B': CDS_PINID='B';
NET_NAME
'PWRGD_FAIL_CPU0_CD_R'
 '@S9S_MB_2U_LIB.S9S_MB_2U(SCH_1):PWRGD_FAIL_CPU0_CD_R':
 C_SIGNAL='@s9s_mb_2u_lib.s9s_mb_2u(sch_1):pwrgd_fail_cpu0_cd_r';
NODE_NAME     U249 R20
 '@S9S_MB_2U_LIB.S9S_MB_2U(SCH_1):PAGE313_I1@PURE_QUANTA.LCMXO3LF9400C5BG484C(CHIPS)':
 'PR25C': CDS_PINID='PR25C';
NODE_NAME     R2499 2
 '@S9S_MB_2U_LIB.S9S_MB_2U(SCH_1):PAGE115_I71@PURE_QUANTA.Q_RES(CHIPS)':
 'B': CDS_PINID='B';
NET_NAME
'PWRGD_FAIL_CPU0_CD_R1'
 '@S9S_MB_2U_LIB.S9S_MB_2U(SCH_1):PWRGD_FAIL_CPU0_CD_R1':
 C_SIGNAL='@s9s_mb_2u_lib.s9s_mb_2u(sch_1):pwrgd_fail_cpu0_cd_r1';
NODE_NAME     R2491 2
 '@S9S_MB_2U_LIB.S9S_MB_2U(SCH_1):PAGE115_I42@PURE_QUANTA.Q_RES(CHIPS)':
 'B': CDS_PINID='B';
NODE_NAME     R941 2
 '@S9S_MB_2U_LIB.S9S_MB_2U(SCH_1):PAGE115_I45@PURE_QUANTA.Q_RES(CHIPS)':
 'B': CDS_PINID='B';
NODE_NAME     D43 1
 '@S9S_MB_2U_LIB.S9S_MB_2U(SCH_1):PAGE115_I54@PURE_QUANTA.SCHOTTKY_12(CHIPS)':
 'A': CDS_PINID='A';
NODE_NAME     R2499 1
 '@S9S_MB_2U_LIB.S9S_MB_2U(SCH_1):PAGE115_I71@PURE_QUANTA.Q_RES(CHIPS)':
 'A': CDS_PINID='A';
NET_NAME
'PWRGD_FAIL_CPU0_EF'
 '@S9S_MB_2U_LIB.S9S_MB_2U(SCH_1):PWRGD_FAIL_CPU0_EF':
 C_SIGNAL='@s9s_mb_2u_lib.s9s_mb_2u(sch_1):pwrgd_fail_cpu0_ef';
NODE_NAME     R2733 2
 '@S9S_MB_2U_LIB.S9S_MB_2U(SCH_1):PAGE114_I21@PURE_QUANTA.Q_RES(CHIPS)':
 'B': CDS_PINID='B';
NODE_NAME     R886 2
 '@S9S_MB_2U_LIB.S9S_MB_2U(SCH_1):PAGE114_I23@PURE_QUANTA.Q_RES(CHIPS)':
 'B': CDS_PINID='B';
NODE_NAME     R885 2
 '@S9S_MB_2U_LIB.S9S_MB_2U(SCH_1):PAGE114_I24@PURE_QUANTA.Q_RES(CHIPS)':
 'B': CDS_PINID='B';
NODE_NAME     R2492 1
 '@S9S_MB_2U_LIB.S9S_MB_2U(SCH_1):PAGE115_I41@PURE_QUANTA.Q_RES(CHIPS)':
 'A': CDS_PINID='A';
NODE_NAME     R2732 2
 '@S9S_MB_2U_LIB.S9S_MB_2U(SCH_1):PAGE114_I22@PURE_QUANTA.Q_RES(CHIPS)':
 'B': CDS_PINID='B';
NET_NAME
'PWRGD_FAIL_CPU0_EF_R'
 '@S9S_MB_2U_LIB.S9S_MB_2U(SCH_1):PWRGD_FAIL_CPU0_EF_R':
 C_SIGNAL='@s9s_mb_2u_lib.s9s_mb_2u(sch_1):pwrgd_fail_cpu0_ef_r';
NODE_NAME     U249 R19
 '@S9S_MB_2U_LIB.S9S_MB_2U(SCH_1):PAGE313_I1@PURE_QUANTA.LCMXO3LF9400C5BG484C(CHIPS)':
 'PR25D': CDS_PINID='PR25D';
NODE_NAME     R2500 2
 '@S9S_MB_2U_LIB.S9S_MB_2U(SCH_1):PAGE115_I70@PURE_QUANTA.Q_RES(CHIPS)':
 'B': CDS_PINID='B';
NET_NAME
'PWRGD_FAIL_CPU0_EF_R1'
 '@S9S_MB_2U_LIB.S9S_MB_2U(SCH_1):PWRGD_FAIL_CPU0_EF_R1':
 C_SIGNAL='@s9s_mb_2u_lib.s9s_mb_2u(sch_1):pwrgd_fail_cpu0_ef_r1';
NODE_NAME     R942 2
 '@S9S_MB_2U_LIB.S9S_MB_2U(SCH_1):PAGE115_I40@PURE_QUANTA.Q_RES(CHIPS)':
 'B': CDS_PINID='B';
NODE_NAME     R2492 2
 '@S9S_MB_2U_LIB.S9S_MB_2U(SCH_1):PAGE115_I41@PURE_QUANTA.Q_RES(CHIPS)':
 'B': CDS_PINID='B';
NODE_NAME     D44 1
 '@S9S_MB_2U_LIB.S9S_MB_2U(SCH_1):PAGE115_I52@PURE_QUANTA.SCHOTTKY_12(CHIPS)':
 'A': CDS_PINID='A';
NODE_NAME     R2500 1
 '@S9S_MB_2U_LIB.S9S_MB_2U(SCH_1):PAGE115_I70@PURE_QUANTA.Q_RES(CHIPS)':
 'A': CDS_PINID='A';
NET_NAME
'PWRGD_FAIL_CPU0_GH'
 '@S9S_MB_2U_LIB.S9S_MB_2U(SCH_1):PWRGD_FAIL_CPU0_GH':
 C_SIGNAL='@s9s_mb_2u_lib.s9s_mb_2u(sch_1):pwrgd_fail_cpu0_gh';
NODE_NAME     R2493 1
 '@S9S_MB_2U_LIB.S9S_MB_2U(SCH_1):PAGE115_I38@PURE_QUANTA.Q_RES(CHIPS)':
 'A': CDS_PINID='A';
NODE_NAME     R2735 2
 '@S9S_MB_2U_LIB.S9S_MB_2U(SCH_1):PAGE114_I17@PURE_QUANTA.Q_RES(CHIPS)':
 'B': CDS_PINID='B';
NODE_NAME     R2734 2
 '@S9S_MB_2U_LIB.S9S_MB_2U(SCH_1):PAGE114_I18@PURE_QUANTA.Q_RES(CHIPS)':
 'B': CDS_PINID='B';
NODE_NAME     R890 2
 '@S9S_MB_2U_LIB.S9S_MB_2U(SCH_1):PAGE114_I19@PURE_QUANTA.Q_RES(CHIPS)':
 'B': CDS_PINID='B';
NODE_NAME     R889 2
 '@S9S_MB_2U_LIB.S9S_MB_2U(SCH_1):PAGE114_I20@PURE_QUANTA.Q_RES(CHIPS)':
 'B': CDS_PINID='B';
NET_NAME
'PWRGD_FAIL_CPU0_GH_R'
 '@S9S_MB_2U_LIB.S9S_MB_2U(SCH_1):PWRGD_FAIL_CPU0_GH_R':
 C_SIGNAL='@s9s_mb_2u_lib.s9s_mb_2u(sch_1):pwrgd_fail_cpu0_gh_r';
NODE_NAME     U249 R18
 '@S9S_MB_2U_LIB.S9S_MB_2U(SCH_1):PAGE313_I1@PURE_QUANTA.LCMXO3LF9400C5BG484C(CHIPS)':
 'PR26A': CDS_PINID='PR26A';
NODE_NAME     R2501 2
 '@S9S_MB_2U_LIB.S9S_MB_2U(SCH_1):PAGE115_I69@PURE_QUANTA.Q_RES(CHIPS)':
 'B': CDS_PINID='B';
NET_NAME
'PWRGD_FAIL_CPU0_GH_R1'
 '@S9S_MB_2U_LIB.S9S_MB_2U(SCH_1):PWRGD_FAIL_CPU0_GH_R1':
 C_SIGNAL='@s9s_mb_2u_lib.s9s_mb_2u(sch_1):pwrgd_fail_cpu0_gh_r1';
NODE_NAME     R2493 2
 '@S9S_MB_2U_LIB.S9S_MB_2U(SCH_1):PAGE115_I38@PURE_QUANTA.Q_RES(CHIPS)':
 'B': CDS_PINID='B';
NODE_NAME     R943 2
 '@S9S_MB_2U_LIB.S9S_MB_2U(SCH_1):PAGE115_I37@PURE_QUANTA.Q_RES(CHIPS)':
 'B': CDS_PINID='B';
NODE_NAME     D45 1
 '@S9S_MB_2U_LIB.S9S_MB_2U(SCH_1):PAGE115_I50@PURE_QUANTA.SCHOTTKY_12(CHIPS)':
 'A': CDS_PINID='A';
NODE_NAME     R2501 1
 '@S9S_MB_2U_LIB.S9S_MB_2U(SCH_1):PAGE115_I69@PURE_QUANTA.Q_RES(CHIPS)':
 'A': CDS_PINID='A';
NET_NAME
'PWRGD_FAIL_CPU1_AB'
 '@S9S_MB_2U_LIB.S9S_MB_2U(SCH_1):PWRGD_FAIL_CPU1_AB':
 C_SIGNAL='@s9s_mb_2u_lib.s9s_mb_2u(sch_1):pwrgd_fail_cpu1_ab';
NODE_NAME     R896 2
 '@S9S_MB_2U_LIB.S9S_MB_2U(SCH_1):PAGE114_I69@PURE_QUANTA.Q_RES(CHIPS)':
 'B': CDS_PINID='B';
NODE_NAME     R2494 1
 '@S9S_MB_2U_LIB.S9S_MB_2U(SCH_1):PAGE115_I18@PURE_QUANTA.Q_RES(CHIPS)':
 'A': CDS_PINID='A';
NODE_NAME     R895 2
 '@S9S_MB_2U_LIB.S9S_MB_2U(SCH_1):PAGE114_I77@PURE_QUANTA.Q_RES(CHIPS)':
 'B': CDS_PINID='B';
NODE_NAME     R894 2
 '@S9S_MB_2U_LIB.S9S_MB_2U(SCH_1):PAGE114_I78@PURE_QUANTA.Q_RES(CHIPS)':
 'B': CDS_PINID='B';
NODE_NAME     R893 2
 '@S9S_MB_2U_LIB.S9S_MB_2U(SCH_1):PAGE114_I79@PURE_QUANTA.Q_RES(CHIPS)':
 'B': CDS_PINID='B';
NET_NAME
'PWRGD_FAIL_CPU1_AB_R'
 '@S9S_MB_2U_LIB.S9S_MB_2U(SCH_1):PWRGD_FAIL_CPU1_AB_R':
 C_SIGNAL='@s9s_mb_2u_lib.s9s_mb_2u(sch_1):pwrgd_fail_cpu1_ab_r';
NODE_NAME     U249 R17
 '@S9S_MB_2U_LIB.S9S_MB_2U(SCH_1):PAGE313_I1@PURE_QUANTA.LCMXO3LF9400C5BG484C(CHIPS)':
 'PR26B': CDS_PINID='PR26B';
NODE_NAME     R2502 2
 '@S9S_MB_2U_LIB.S9S_MB_2U(SCH_1):PAGE115_I68@PURE_QUANTA.Q_RES(CHIPS)':
 'B': CDS_PINID='B';
NET_NAME
'PWRGD_FAIL_CPU1_AB_R1'
 '@S9S_MB_2U_LIB.S9S_MB_2U(SCH_1):PWRGD_FAIL_CPU1_AB_R1':
 C_SIGNAL='@s9s_mb_2u_lib.s9s_mb_2u(sch_1):pwrgd_fail_cpu1_ab_r1';
NODE_NAME     R944 2
 '@S9S_MB_2U_LIB.S9S_MB_2U(SCH_1):PAGE115_I19@PURE_QUANTA.Q_RES(CHIPS)':
 'B': CDS_PINID='B';
NODE_NAME     R2494 2
 '@S9S_MB_2U_LIB.S9S_MB_2U(SCH_1):PAGE115_I18@PURE_QUANTA.Q_RES(CHIPS)':
 'B': CDS_PINID='B';
NODE_NAME     D46 1
 '@S9S_MB_2U_LIB.S9S_MB_2U(SCH_1):PAGE115_I29@PURE_QUANTA.SCHOTTKY_12(CHIPS)':
 'A': CDS_PINID='A';
NODE_NAME     R2502 1
 '@S9S_MB_2U_LIB.S9S_MB_2U(SCH_1):PAGE115_I68@PURE_QUANTA.Q_RES(CHIPS)':
 'A': CDS_PINID='A';
NET_NAME
'PWRGD_FAIL_CPU1_CD'
 '@S9S_MB_2U_LIB.S9S_MB_2U(SCH_1):PWRGD_FAIL_CPU1_CD':
 C_SIGNAL='@s9s_mb_2u_lib.s9s_mb_2u(sch_1):pwrgd_fail_cpu1_cd';
NODE_NAME     R2495 1
 '@S9S_MB_2U_LIB.S9S_MB_2U(SCH_1):PAGE115_I17@PURE_QUANTA.Q_RES(CHIPS)':
 'A': CDS_PINID='A';
NODE_NAME     R900 2
 '@S9S_MB_2U_LIB.S9S_MB_2U(SCH_1):PAGE114_I66@PURE_QUANTA.Q_RES(CHIPS)':
 'B': CDS_PINID='B';
NODE_NAME     R897 2
 '@S9S_MB_2U_LIB.S9S_MB_2U(SCH_1):PAGE114_I67@PURE_QUANTA.Q_RES(CHIPS)':
 'B': CDS_PINID='B';
NODE_NAME     R899 2
 '@S9S_MB_2U_LIB.S9S_MB_2U(SCH_1):PAGE114_I65@PURE_QUANTA.Q_RES(CHIPS)':
 'B': CDS_PINID='B';
NODE_NAME     R898 2
 '@S9S_MB_2U_LIB.S9S_MB_2U(SCH_1):PAGE114_I68@PURE_QUANTA.Q_RES(CHIPS)':
 'B': CDS_PINID='B';
NET_NAME
'PWRGD_FAIL_CPU1_CD_R'
 '@S9S_MB_2U_LIB.S9S_MB_2U(SCH_1):PWRGD_FAIL_CPU1_CD_R':
 C_SIGNAL='@s9s_mb_2u_lib.s9s_mb_2u(sch_1):pwrgd_fail_cpu1_cd_r';
NODE_NAME     U249 R16
 '@S9S_MB_2U_LIB.S9S_MB_2U(SCH_1):PAGE313_I1@PURE_QUANTA.LCMXO3LF9400C5BG484C(CHIPS)':
 'PR26C': CDS_PINID='PR26C';
NODE_NAME     R2503 2
 '@S9S_MB_2U_LIB.S9S_MB_2U(SCH_1):PAGE115_I67@PURE_QUANTA.Q_RES(CHIPS)':
 'B': CDS_PINID='B';
NET_NAME
'PWRGD_FAIL_CPU1_CD_R1'
 '@S9S_MB_2U_LIB.S9S_MB_2U(SCH_1):PWRGD_FAIL_CPU1_CD_R1':
 C_SIGNAL='@s9s_mb_2u_lib.s9s_mb_2u(sch_1):pwrgd_fail_cpu1_cd_r1';
NODE_NAME     R945 2
 '@S9S_MB_2U_LIB.S9S_MB_2U(SCH_1):PAGE115_I16@PURE_QUANTA.Q_RES(CHIPS)':
 'B': CDS_PINID='B';
NODE_NAME     R2495 2
 '@S9S_MB_2U_LIB.S9S_MB_2U(SCH_1):PAGE115_I17@PURE_QUANTA.Q_RES(CHIPS)':
 'B': CDS_PINID='B';
NODE_NAME     D47 1
 '@S9S_MB_2U_LIB.S9S_MB_2U(SCH_1):PAGE115_I27@PURE_QUANTA.SCHOTTKY_12(CHIPS)':
 'A': CDS_PINID='A';
NODE_NAME     R2503 1
 '@S9S_MB_2U_LIB.S9S_MB_2U(SCH_1):PAGE115_I67@PURE_QUANTA.Q_RES(CHIPS)':
 'A': CDS_PINID='A';
NET_NAME
'PWRGD_FAIL_CPU1_EF'
 '@S9S_MB_2U_LIB.S9S_MB_2U(SCH_1):PWRGD_FAIL_CPU1_EF':
 C_SIGNAL='@s9s_mb_2u_lib.s9s_mb_2u(sch_1):pwrgd_fail_cpu1_ef';
NODE_NAME     R2736 2
 '@S9S_MB_2U_LIB.S9S_MB_2U(SCH_1):PAGE114_I61@PURE_QUANTA.Q_RES(CHIPS)':
 'B': CDS_PINID='B';
NODE_NAME     R902 2
 '@S9S_MB_2U_LIB.S9S_MB_2U(SCH_1):PAGE114_I63@PURE_QUANTA.Q_RES(CHIPS)':
 'B': CDS_PINID='B';
NODE_NAME     R2496 1
 '@S9S_MB_2U_LIB.S9S_MB_2U(SCH_1):PAGE115_I12@PURE_QUANTA.Q_RES(CHIPS)':
 'A': CDS_PINID='A';
NODE_NAME     R903 2
 '@S9S_MB_2U_LIB.S9S_MB_2U(SCH_1):PAGE114_I62@PURE_QUANTA.Q_RES(CHIPS)':
 'B': CDS_PINID='B';
NODE_NAME     R901 2
 '@S9S_MB_2U_LIB.S9S_MB_2U(SCH_1):PAGE114_I64@PURE_QUANTA.Q_RES(CHIPS)':
 'B': CDS_PINID='B';
NET_NAME
'PWRGD_FAIL_CPU1_EF_R'
 '@S9S_MB_2U_LIB.S9S_MB_2U(SCH_1):PWRGD_FAIL_CPU1_EF_R':
 C_SIGNAL='@s9s_mb_2u_lib.s9s_mb_2u(sch_1):pwrgd_fail_cpu1_ef_r';
NODE_NAME     U249 T20
 '@S9S_MB_2U_LIB.S9S_MB_2U(SCH_1):PAGE313_I1@PURE_QUANTA.LCMXO3LF9400C5BG484C(CHIPS)':
 'PR26D': CDS_PINID='PR26D';
NODE_NAME     R2504 2
 '@S9S_MB_2U_LIB.S9S_MB_2U(SCH_1):PAGE115_I66@PURE_QUANTA.Q_RES(CHIPS)':
 'B': CDS_PINID='B';
NET_NAME
'PWRGD_FAIL_CPU1_EF_R1'
 '@S9S_MB_2U_LIB.S9S_MB_2U(SCH_1):PWRGD_FAIL_CPU1_EF_R1':
 C_SIGNAL='@s9s_mb_2u_lib.s9s_mb_2u(sch_1):pwrgd_fail_cpu1_ef_r1';
NODE_NAME     R2496 2
 '@S9S_MB_2U_LIB.S9S_MB_2U(SCH_1):PAGE115_I12@PURE_QUANTA.Q_RES(CHIPS)':
 'B': CDS_PINID='B';
NODE_NAME     R946 2
 '@S9S_MB_2U_LIB.S9S_MB_2U(SCH_1):PAGE115_I14@PURE_QUANTA.Q_RES(CHIPS)':
 'B': CDS_PINID='B';
NODE_NAME     D48 1
 '@S9S_MB_2U_LIB.S9S_MB_2U(SCH_1):PAGE115_I25@PURE_QUANTA.SCHOTTKY_12(CHIPS)':
 'A': CDS_PINID='A';
NODE_NAME     R2504 1
 '@S9S_MB_2U_LIB.S9S_MB_2U(SCH_1):PAGE115_I66@PURE_QUANTA.Q_RES(CHIPS)':
 'A': CDS_PINID='A';
NET_NAME
'PWRGD_FAIL_CPU1_GH'
 '@S9S_MB_2U_LIB.S9S_MB_2U(SCH_1):PWRGD_FAIL_CPU1_GH':
 C_SIGNAL='@s9s_mb_2u_lib.s9s_mb_2u(sch_1):pwrgd_fail_cpu1_gh';
NODE_NAME     R906 2
 '@S9S_MB_2U_LIB.S9S_MB_2U(SCH_1):PAGE114_I59@PURE_QUANTA.Q_RES(CHIPS)':
 'B': CDS_PINID='B';
NODE_NAME     R2497 1
 '@S9S_MB_2U_LIB.S9S_MB_2U(SCH_1):PAGE115_I9@PURE_QUANTA.Q_RES(CHIPS)':
 'A': CDS_PINID='A';
NODE_NAME     R908 2
 '@S9S_MB_2U_LIB.S9S_MB_2U(SCH_1):PAGE114_I57@PURE_QUANTA.Q_RES(CHIPS)':
 'B': CDS_PINID='B';
NODE_NAME     R907 2
 '@S9S_MB_2U_LIB.S9S_MB_2U(SCH_1):PAGE114_I58@PURE_QUANTA.Q_RES(CHIPS)':
 'B': CDS_PINID='B';
NODE_NAME     R905 2
 '@S9S_MB_2U_LIB.S9S_MB_2U(SCH_1):PAGE114_I60@PURE_QUANTA.Q_RES(CHIPS)':
 'B': CDS_PINID='B';
NET_NAME
'PWRGD_FAIL_CPU1_GH_R'
 '@S9S_MB_2U_LIB.S9S_MB_2U(SCH_1):PWRGD_FAIL_CPU1_GH_R':
 C_SIGNAL='@s9s_mb_2u_lib.s9s_mb_2u(sch_1):pwrgd_fail_cpu1_gh_r';
NODE_NAME     U249 T19
 '@S9S_MB_2U_LIB.S9S_MB_2U(SCH_1):PAGE313_I1@PURE_QUANTA.LCMXO3LF9400C5BG484C(CHIPS)':
 'PR27A': CDS_PINID='PR27A';
NODE_NAME     R2505 2
 '@S9S_MB_2U_LIB.S9S_MB_2U(SCH_1):PAGE115_I65@PURE_QUANTA.Q_RES(CHIPS)':
 'B': CDS_PINID='B';
NET_NAME
'PWRGD_FAIL_CPU1_GH_R1'
 '@S9S_MB_2U_LIB.S9S_MB_2U(SCH_1):PWRGD_FAIL_CPU1_GH_R1':
 C_SIGNAL='@s9s_mb_2u_lib.s9s_mb_2u(sch_1):pwrgd_fail_cpu1_gh_r1';
NODE_NAME     R2497 2
 '@S9S_MB_2U_LIB.S9S_MB_2U(SCH_1):PAGE115_I9@PURE_QUANTA.Q_RES(CHIPS)':
 'B': CDS_PINID='B';
NODE_NAME     R947 2
 '@S9S_MB_2U_LIB.S9S_MB_2U(SCH_1):PAGE115_I11@PURE_QUANTA.Q_RES(CHIPS)':
 'B': CDS_PINID='B';
NODE_NAME     D49 1
 '@S9S_MB_2U_LIB.S9S_MB_2U(SCH_1):PAGE115_I22@PURE_QUANTA.SCHOTTKY_12(CHIPS)':
 'A': CDS_PINID='A';
NODE_NAME     R2505 1
 '@S9S_MB_2U_LIB.S9S_MB_2U(SCH_1):PAGE115_I65@PURE_QUANTA.Q_RES(CHIPS)':
 'A': CDS_PINID='A';
NET_NAME
'PWRGD_P1V05_PCH_AUX'
 '@S9S_MB_2U_LIB.S9S_MB_2U(SCH_1):PWRGD_P1V05_PCH_AUX':
 C_SIGNAL='@s9s_mb_2u_lib.s9s_mb_2u(sch_1):pwrgd_p1v05_pch_aux';
NODE_NAME     Q76 5
 '@S9S_MB_2U_LIB.S9S_MB_2U(SCH_1):PAGE242_I8@PURE_QUANTA.MOSFET_NCH_DUAL(CHIPS)':
 'G2': CDS_PINID='G2';
NODE_NAME     U249 J16
 '@S9S_MB_2U_LIB.S9S_MB_2U(SCH_1):PAGE313_I1@PURE_QUANTA.LCMXO3LF9400C5BG484C(CHIPS)':
 'PR11A': CDS_PINID='PR11A';
NODE_NAME     R1650 2
 '@S9S_MB_2U_LIB.S9S_MB_2U(SCH_1):PAGE248_I51@PURE_QUANTA.Q_RES(CHIPS)':
 'B': CDS_PINID='B';
NET_NAME
'PWRGD_P1V05_PCH_AUX_R'
 '@S9S_MB_2U_LIB.S9S_MB_2U(SCH_1):PWRGD_P1V05_PCH_AUX_R':
 C_SIGNAL='@s9s_mb_2u_lib.s9s_mb_2u(sch_1):pwrgd_p1v05_pch_aux_r';
NODE_NAME     R1650 1
 '@S9S_MB_2U_LIB.S9S_MB_2U(SCH_1):PAGE248_I51@PURE_QUANTA.Q_RES(CHIPS)':
 'A': CDS_PINID='A';
NODE_NAME     R2357 2
 '@S9S_MB_2U_LIB.S9S_MB_2U(SCH_1):PAGE248_I32@PURE_QUANTA.Q_RES(CHIPS)':
 'B': CDS_PINID='B';
NODE_NAME     PU73 9
 '@S9S_MB_2U_LIB.S9S_MB_2U(SCH_1):PAGE248_I11@PURE_QUANTA.RS53319LR(CHIPS)':
 'PGOOD': CDS_PINID='PGOOD';
NODE_NAME     R4780 1
 '@S9S_MB_2U_LIB.S9S_MB_2U(SCH_1):PAGE248_I52@PURE_QUANTA.Q_RES(CHIPS)':
 'A': CDS_PINID='A';
NET_NAME
'PWRGD_P1V8_PCH_AUX'
 '@S9S_MB_2U_LIB.S9S_MB_2U(SCH_1):PWRGD_P1V8_PCH_AUX':
 C_SIGNAL='@s9s_mb_2u_lib.s9s_mb_2u(sch_1):pwrgd_p1v8_pch_aux';
NODE_NAME     R2476 2
 '@S9S_MB_2U_LIB.S9S_MB_2U(SCH_1):PAGE183_I70@PURE_QUANTA.Q_RES(CHIPS)':
 'B': CDS_PINID='B';
NODE_NAME     R1444 1
 '@S9S_MB_2U_LIB.S9S_MB_2U(SCH_1):PAGE211_I54@PURE_QUANTA.Q_RES(CHIPS)':
 'A': CDS_PINID='A';
NODE_NAME     Q76 2
 '@S9S_MB_2U_LIB.S9S_MB_2U(SCH_1):PAGE242_I17@PURE_QUANTA.MOSFET_NCH_DUAL(CHIPS)':
 'G1': CDS_PINID='G1';
NODE_NAME     C2287 1
 '@S9S_MB_2U_LIB.S9S_MB_2U(SCH_1):PAGE249_I36@PURE_QUANTA.Q_CAP(CHIPS)':
 'A': CDS_PINID='A';
NODE_NAME     R2360 2
 '@S9S_MB_2U_LIB.S9S_MB_2U(SCH_1):PAGE249_I34@PURE_QUANTA.Q_RES(CHIPS)':
 'B': CDS_PINID='B';
NET_NAME
'PWRGD_P1V8_PCH_AUX_PLD'
 '@S9S_MB_2U_LIB.S9S_MB_2U(SCH_1):PWRGD_P1V8_PCH_AUX_PLD':
 C_SIGNAL='@s9s_mb_2u_lib.s9s_mb_2u(sch_1):pwrgd_p1v8_pch_aux_pld';
NODE_NAME     R1444 2
 '@S9S_MB_2U_LIB.S9S_MB_2U(SCH_1):PAGE211_I54@PURE_QUANTA.Q_RES(CHIPS)':
 'B': CDS_PINID='B';
NODE_NAME     U249 J17
 '@S9S_MB_2U_LIB.S9S_MB_2U(SCH_1):PAGE313_I1@PURE_QUANTA.LCMXO3LF9400C5BG484C(CHIPS)':
 'PR11B': CDS_PINID='PR11B';
NET_NAME
'PWRGD_P1V8_PCH_AUX_R'
 '@S9S_MB_2U_LIB.S9S_MB_2U(SCH_1):PWRGD_P1V8_PCH_AUX_R':
 C_SIGNAL='@s9s_mb_2u_lib.s9s_mb_2u(sch_1):pwrgd_p1v8_pch_aux_r';
NODE_NAME     PU74 13
 '@S9S_MB_2U_LIB.S9S_MB_2U(SCH_1):PAGE249_I26@PURE_QUANTA.NB682GDZ(CHIPS)':
 'PG': CDS_PINID='PG';
NODE_NAME     R2359 2
 '@S9S_MB_2U_LIB.S9S_MB_2U(SCH_1):PAGE249_I31@PURE_QUANTA.Q_RES(CHIPS)':
 'B': CDS_PINID='B';
NODE_NAME     R2360 1
 '@S9S_MB_2U_LIB.S9S_MB_2U(SCH_1):PAGE249_I34@PURE_QUANTA.Q_RES(CHIPS)':
 'A': CDS_PINID='A';
NET_NAME
'PWRGD_P3V3'
 '@S9S_MB_2U_LIB.S9S_MB_2U(SCH_1):PWRGD_P3V3':
 C_SIGNAL='@s9s_mb_2u_lib.s9s_mb_2u(sch_1):pwrgd_p3v3';
NODE_NAME     U249 E12
 '@S9S_MB_2U_LIB.S9S_MB_2U(SCH_1):PAGE314_I188@PURE_QUANTA.LCMXO3LF9400C5BG484C(CHIPS)':
 'PT27B': CDS_PINID='PT27B';
NODE_NAME     R4677 2
 '@S9S_MB_2U_LIB.S9S_MB_2U(SCH_1):PAGE246_I91@PURE_QUANTA.Q_RES(CHIPS)':
 'B': CDS_PINID='B';
NET_NAME
'PWRGD_P3V3_AUX'
 '@S9S_MB_2U_LIB.S9S_MB_2U(SCH_1):PWRGD_P3V3_AUX':
 C_SIGNAL='@s9s_mb_2u_lib.s9s_mb_2u(sch_1):pwrgd_p3v3_aux';
NODE_NAME     R1919 1
 '@S9S_MB_2U_LIB.S9S_MB_2U(SCH_1):PAGE211_I127@PURE_QUANTA.Q_RES(CHIPS)':
 'A': CDS_PINID='A';
NODE_NAME     R4267 1
 '@S9S_MB_2U_LIB.S9S_MB_2U(SCH_1):PAGE211_I129@PURE_QUANTA.Q_RES(CHIPS)':
 'A': CDS_PINID='A';
NODE_NAME     PU9 2
 '@S9S_MB_2U_LIB.S9S_MB_2U(SCH_1):PAGE245_I95@PURE_QUANTA.IR3889MTRPBF(CHIPS)':
 'PGOOD': CDS_PINID='PGOOD';
NODE_NAME     PR73 2
 '@S9S_MB_2U_LIB.S9S_MB_2U(SCH_1):PAGE245_I139@PURE_QUANTA.Q_RES(CHIPS)':
 'B': CDS_PINID='B';
NODE_NAME     PU181 8
 '@S9S_MB_2U_LIB.S9S_MB_2U(SCH_1):PAGE244_I20@PURE_QUANTA.RS53318LR(CHIPS)':
 'EN': CDS_PINID='EN';
NODE_NAME     Q53 G
 '@S9S_MB_2U_LIB.S9S_MB_2U(SCH_1):PAGE232_I39@PURE_QUANTA.MOSFET_NCH_GDS_ESD_PROTECTED(CHIPS)':
 'G': CDS_PINID='G';
NET_NAME
'PWRGD_P3V3_AUX_PDB'
 '@S9S_MB_2U_LIB.S9S_MB_2U(SCH_1):PWRGD_P3V3_AUX_PDB':
 C_SIGNAL='@s9s_mb_2u_lib.s9s_mb_2u(sch_1):pwrgd_p3v3_aux_pdb';
NODE_NAME     R4268 1
 '@S9S_MB_2U_LIB.S9S_MB_2U(SCH_1):PAGE230_I41@PURE_QUANTA.Q_RES(CHIPS)':
 'A': CDS_PINID='A';
NODE_NAME     R4267 2
 '@S9S_MB_2U_LIB.S9S_MB_2U(SCH_1):PAGE211_I129@PURE_QUANTA.Q_RES(CHIPS)':
 'B': CDS_PINID='B';
NET_NAME
'PWRGD_P3V3_AUX_PDB_BUF'
 '@S9S_MB_2U_LIB.S9S_MB_2U(SCH_1):PWRGD_P3V3_AUX_PDB_BUF':
 C_SIGNAL='@s9s_mb_2u_lib.s9s_mb_2u(sch_1):pwrgd_p3v3_aux_pdb_buf';
NODE_NAME     R4266 2
 '@S9S_MB_2U_LIB.S9S_MB_2U(SCH_1):PAGE230_I48@PURE_QUANTA.Q_RES(CHIPS)':
 'B': CDS_PINID='B';
NODE_NAME     J45 B2
 '@S9S_MB_2U_LIB.S9S_MB_2U(SCH_1):PAGE233_I12@PURE_QUANTA.CONN60_101062636003K02LF(CHIPS)':
 'B2': CDS_PINID='B2';
NET_NAME
'PWRGD_P3V3_AUX_PDB_BUF_R'
 '@S9S_MB_2U_LIB.S9S_MB_2U(SCH_1):PWRGD_P3V3_AUX_PDB_BUF_R':
 C_SIGNAL='@s9s_mb_2u_lib.s9s_mb_2u(sch_1):pwrgd_p3v3_aux_pdb_buf_r';
NODE_NAME     U308 6
 '@S9S_MB_2U_LIB.S9S_MB_2U(SCH_1):PAGE230_I37@PURE_QUANTA.74LVC2G07DW7(CHIPS)':
 '1Y': CDS_PINID='\1y\';
NODE_NAME     R4265 1
 '@S9S_MB_2U_LIB.S9S_MB_2U(SCH_1):PAGE230_I43@PURE_QUANTA.Q_RES(CHIPS)':
 'A': CDS_PINID='A';
NODE_NAME     R4264 2
 '@S9S_MB_2U_LIB.S9S_MB_2U(SCH_1):PAGE230_I47@PURE_QUANTA.Q_RES(CHIPS)':
 'B': CDS_PINID='B';
NODE_NAME     R4266 1
 '@S9S_MB_2U_LIB.S9S_MB_2U(SCH_1):PAGE230_I48@PURE_QUANTA.Q_RES(CHIPS)':
 'A': CDS_PINID='A';
NET_NAME
'PWRGD_P3V3_AUX_PDB_R'
 '@S9S_MB_2U_LIB.S9S_MB_2U(SCH_1):PWRGD_P3V3_AUX_PDB_R':
 C_SIGNAL='@s9s_mb_2u_lib.s9s_mb_2u(sch_1):pwrgd_p3v3_aux_pdb_r';
NODE_NAME     U308 1
 '@S9S_MB_2U_LIB.S9S_MB_2U(SCH_1):PAGE230_I37@PURE_QUANTA.74LVC2G07DW7(CHIPS)':
 '1A': CDS_PINID='\1a\';
NODE_NAME     R4268 2
 '@S9S_MB_2U_LIB.S9S_MB_2U(SCH_1):PAGE230_I41@PURE_QUANTA.Q_RES(CHIPS)':
 'B': CDS_PINID='B';
NET_NAME
'PWRGD_P3V3_AUX_PLD'
 '@S9S_MB_2U_LIB.S9S_MB_2U(SCH_1):PWRGD_P3V3_AUX_PLD':
 C_SIGNAL='@s9s_mb_2u_lib.s9s_mb_2u(sch_1):pwrgd_p3v3_aux_pld';
NODE_NAME     R1919 2
 '@S9S_MB_2U_LIB.S9S_MB_2U(SCH_1):PAGE211_I127@PURE_QUANTA.Q_RES(CHIPS)':
 'B': CDS_PINID='B';
NODE_NAME     U249 G12
 '@S9S_MB_2U_LIB.S9S_MB_2U(SCH_1):PAGE314_I188@PURE_QUANTA.LCMXO3LF9400C5BG484C(CHIPS)':
 'PT28A': CDS_PINID='PT28A';
NET_NAME
'PWRGD_P3V3_AUX_R2'
 '@S9S_MB_2U_LIB.S9S_MB_2U(SCH_1):PWRGD_P3V3_AUX_R2':
 C_SIGNAL='@s9s_mb_2u_lib.s9s_mb_2u(sch_1):pwrgd_p3v3_aux_r2';
NODE_NAME     Q52 G
 '@S9S_MB_2U_LIB.S9S_MB_2U(SCH_1):PAGE232_I14@PURE_QUANTA.MOSFET_NCH_GDS_ESD_PROTECTED(CHIPS)':
 'G': CDS_PINID='G';
NODE_NAME     Q53 D
 '@S9S_MB_2U_LIB.S9S_MB_2U(SCH_1):PAGE232_I39@PURE_QUANTA.MOSFET_NCH_GDS_ESD_PROTECTED(CHIPS)':
 'D': CDS_PINID='D';
NODE_NAME     R2486 2
 '@S9S_MB_2U_LIB.S9S_MB_2U(SCH_1):PAGE232_I40@PURE_QUANTA.Q_RES(CHIPS)':
 'B': CDS_PINID='B';
NET_NAME
'PWRGD_P3V3_R1'
 '@S9S_MB_2U_LIB.S9S_MB_2U(SCH_1):PWRGD_P3V3_R1':
 C_SIGNAL='@s9s_mb_2u_lib.s9s_mb_2u(sch_1):pwrgd_p3v3_r1';
NODE_NAME     R1706 2
 '@S9S_MB_2U_LIB.S9S_MB_2U(SCH_1):PAGE246_I89@PURE_QUANTA.Q_RES(CHIPS)':
 'B': CDS_PINID='B';
NODE_NAME     R4677 1
 '@S9S_MB_2U_LIB.S9S_MB_2U(SCH_1):PAGE246_I91@PURE_QUANTA.Q_RES(CHIPS)':
 'A': CDS_PINID='A';
NODE_NAME     U330 2
 '@S9S_MB_2U_LIB.S9S_MB_2U(SCH_1):PAGE246_I105@PURE_QUANTA.APX80929SAG7(CHIPS)':
 'RESET_L': CDS_PINID='RESET_L';
NODE_NAME     R4681 1
 '@S9S_MB_2U_LIB.S9S_MB_2U(SCH_1):PAGE246_I109@PURE_QUANTA.Q_RES(CHIPS)':
 'A': CDS_PINID='A';
NET_NAME
'PWRGD_P5V'
 '@S9S_MB_2U_LIB.S9S_MB_2U(SCH_1):PWRGD_P5V':
 C_SIGNAL='@s9s_mb_2u_lib.s9s_mb_2u(sch_1):pwrgd_p5v';
NODE_NAME     U99 1
 '@S9S_MB_2U_LIB.S9S_MB_2U(SCH_1):PAGE246_I4@PURE_QUANTA.RT9818C44GV(CHIPS)':
 'RESET#': CDS_PINID='\reset#\';
NODE_NAME     R4679 2
 '@S9S_MB_2U_LIB.S9S_MB_2U(SCH_1):PAGE246_I96@PURE_QUANTA.Q_RES(CHIPS)':
 'B': CDS_PINID='B';
NODE_NAME     Q236 2
 '@S9S_MB_2U_LIB.S9S_MB_2U(SCH_1):PAGE246_I99@PURE_QUANTA.MOSFET_NCH_DUAL(CHIPS)':
 'G1': CDS_PINID='G1';
NODE_NAME     R4682 1
 '@S9S_MB_2U_LIB.S9S_MB_2U(SCH_1):PAGE246_I112@PURE_QUANTA.Q_RES(CHIPS)':
 'A': CDS_PINID='A';
NET_NAME
'PWRGD_P5V_AUX'
 '@S9S_MB_2U_LIB.S9S_MB_2U(SCH_1):PWRGD_P5V_AUX':
 C_SIGNAL='@s9s_mb_2u_lib.s9s_mb_2u(sch_1):pwrgd_p5v_aux';
NODE_NAME     R2316 2
 '@S9S_MB_2U_LIB.S9S_MB_2U(SCH_1):PAGE244_I28@PURE_QUANTA.Q_RES(CHIPS)':
 'B': CDS_PINID='B';
NODE_NAME     R2343 2
 '@S9S_MB_2U_LIB.S9S_MB_2U(SCH_1):PAGE314_I41@PURE_QUANTA.Q_RES(CHIPS)':
 'B': CDS_PINID='B';
NODE_NAME     Q50 2
 '@S9S_MB_2U_LIB.S9S_MB_2U(SCH_1):PAGE314_I43@PURE_QUANTA.MOSFET_NCH_DUAL(CHIPS)':
 'G1': CDS_PINID='G1';
NET_NAME
'PWRGD_P5V_AUX_R'
 '@S9S_MB_2U_LIB.S9S_MB_2U(SCH_1):PWRGD_P5V_AUX_R':
 C_SIGNAL='@s9s_mb_2u_lib.s9s_mb_2u(sch_1):pwrgd_p5v_aux_r';
NODE_NAME     R2356 2
 '@S9S_MB_2U_LIB.S9S_MB_2U(SCH_1):PAGE244_I27@PURE_QUANTA.Q_RES(CHIPS)':
 'B': CDS_PINID='B';
NODE_NAME     R2316 1
 '@S9S_MB_2U_LIB.S9S_MB_2U(SCH_1):PAGE244_I28@PURE_QUANTA.Q_RES(CHIPS)':
 'A': CDS_PINID='A';
NODE_NAME     PU181 9
 '@S9S_MB_2U_LIB.S9S_MB_2U(SCH_1):PAGE244_I20@PURE_QUANTA.RS53318LR(CHIPS)':
 'PGOOD': CDS_PINID='PGOOD';
NET_NAME
'PWRGD_P5V_AUX_R1'
 '@S9S_MB_2U_LIB.S9S_MB_2U(SCH_1):PWRGD_P5V_AUX_R1':
 C_SIGNAL='@s9s_mb_2u_lib.s9s_mb_2u(sch_1):pwrgd_p5v_aux_r1';
NODE_NAME     Q50 5
 '@S9S_MB_2U_LIB.S9S_MB_2U(SCH_1):PAGE314_I49@PURE_QUANTA.MOSFET_NCH_DUAL(CHIPS)':
 'G2': CDS_PINID='G2';
NODE_NAME     Q50 6
 '@S9S_MB_2U_LIB.S9S_MB_2U(SCH_1):PAGE314_I43@PURE_QUANTA.MOSFET_NCH_DUAL(CHIPS)':
 'D1': CDS_PINID='D1';
NODE_NAME     R2344 2
 '@S9S_MB_2U_LIB.S9S_MB_2U(SCH_1):PAGE314_I45@PURE_QUANTA.Q_RES(CHIPS)':
 'B': CDS_PINID='B';
NET_NAME
'PWRGD_P5V_AUX_R2'
 '@S9S_MB_2U_LIB.S9S_MB_2U(SCH_1):PWRGD_P5V_AUX_R2':
 C_SIGNAL='@s9s_mb_2u_lib.s9s_mb_2u(sch_1):pwrgd_p5v_aux_r2';
NODE_NAME     Q50 3
 '@S9S_MB_2U_LIB.S9S_MB_2U(SCH_1):PAGE314_I49@PURE_QUANTA.MOSFET_NCH_DUAL(CHIPS)':
 'D2': CDS_PINID='D2';
NODE_NAME     R2346 2
 '@S9S_MB_2U_LIB.S9S_MB_2U(SCH_1):PAGE314_I51@PURE_QUANTA.Q_RES(CHIPS)':
 'B': CDS_PINID='B';
NODE_NAME     U249 D12
 '@S9S_MB_2U_LIB.S9S_MB_2U(SCH_1):PAGE314_I188@PURE_QUANTA.LCMXO3LF9400C5BG484C(CHIPS)':
 'PT27A': CDS_PINID='PT27A';
NET_NAME
'PWRGD_P5V_ISO'
 '@S9S_MB_2U_LIB.S9S_MB_2U(SCH_1):PWRGD_P5V_ISO':
 C_SIGNAL='@s9s_mb_2u_lib.s9s_mb_2u(sch_1):pwrgd_p5v_iso';
NODE_NAME     Q236 3
 '@S9S_MB_2U_LIB.S9S_MB_2U(SCH_1):PAGE246_I98@PURE_QUANTA.MOSFET_NCH_DUAL(CHIPS)':
 'D2': CDS_PINID='D2';
NODE_NAME     R4678 2
 '@S9S_MB_2U_LIB.S9S_MB_2U(SCH_1):PAGE246_I104@PURE_QUANTA.Q_RES(CHIPS)':
 'B': CDS_PINID='B';
NET_NAME
'PWRGD_P5V_ISO_R'
 '@S9S_MB_2U_LIB.S9S_MB_2U(SCH_1):PWRGD_P5V_ISO_R':
 C_SIGNAL='@s9s_mb_2u_lib.s9s_mb_2u(sch_1):pwrgd_p5v_iso_r';
NODE_NAME     R1655 2
 '@S9S_MB_2U_LIB.S9S_MB_2U(SCH_1):PAGE246_I6@PURE_QUANTA.Q_RES(CHIPS)':
 'B': CDS_PINID='B';
NODE_NAME     Q56 4
 '@S9S_MB_2U_LIB.S9S_MB_2U(SCH_1):PAGE246_I51@PURE_QUANTA.MOSFET_NCH_1D3S(CHIPS)':
 '4': CDS_PINID='\4\';
NODE_NAME     C2359 1
 '@S9S_MB_2U_LIB.S9S_MB_2U(SCH_1):PAGE246_I94@PURE_QUANTA.Q_CAP(CHIPS)':
 'A': CDS_PINID='A';
NODE_NAME     R4678 1
 '@S9S_MB_2U_LIB.S9S_MB_2U(SCH_1):PAGE246_I104@PURE_QUANTA.Q_RES(CHIPS)':
 'A': CDS_PINID='A';
NET_NAME
'PWRGD_P5V_N'
 '@S9S_MB_2U_LIB.S9S_MB_2U(SCH_1):PWRGD_P5V_N':
 C_SIGNAL='@s9s_mb_2u_lib.s9s_mb_2u(sch_1):pwrgd_p5v_n';
NODE_NAME     Q236 5
 '@S9S_MB_2U_LIB.S9S_MB_2U(SCH_1):PAGE246_I98@PURE_QUANTA.MOSFET_NCH_DUAL(CHIPS)':
 'G2': CDS_PINID='G2';
NODE_NAME     Q236 6
 '@S9S_MB_2U_LIB.S9S_MB_2U(SCH_1):PAGE246_I99@PURE_QUANTA.MOSFET_NCH_DUAL(CHIPS)':
 'D1': CDS_PINID='D1';
NODE_NAME     R4680 2
 '@S9S_MB_2U_LIB.S9S_MB_2U(SCH_1):PAGE246_I102@PURE_QUANTA.Q_RES(CHIPS)':
 'B': CDS_PINID='B';
NET_NAME
'PWRGD_PCH_PWROK'
 '@S9S_MB_2U_LIB.S9S_MB_2U(SCH_1):PWRGD_PCH_PWROK':
 C_SIGNAL='@s9s_mb_2u_lib.s9s_mb_2u(sch_1):pwrgd_pch_pwrok';
NODE_NAME     U4 BE4
 '@S9S_MB_2U_LIB.S9S_MB_2U(SCH_1):PAGE174_I36@PURE_QUANTA.EMMITSBURG_REV0P9(CHIPS)':
 'PCH_PWROK': CDS_PINID='PCH_PWROK';
NODE_NAME     R1403 1
 '@S9S_MB_2U_LIB.S9S_MB_2U(SCH_1):PAGE208_I24@PURE_QUANTA.Q_RES(CHIPS)':
 'A': CDS_PINID='A';
NODE_NAME     R1442 2
 '@S9S_MB_2U_LIB.S9S_MB_2U(SCH_1):PAGE211_I48@PURE_QUANTA.Q_RES(CHIPS)':
 'B': CDS_PINID='B';
NET_NAME
'PWRGD_PCH_PWROK_R'
 '@S9S_MB_2U_LIB.S9S_MB_2U(SCH_1):PWRGD_PCH_PWROK_R':
 C_SIGNAL='@s9s_mb_2u_lib.s9s_mb_2u(sch_1):pwrgd_pch_pwrok_r';
NODE_NAME     R1442 1
 '@S9S_MB_2U_LIB.S9S_MB_2U(SCH_1):PAGE211_I48@PURE_QUANTA.Q_RES(CHIPS)':
 'A': CDS_PINID='A';
NODE_NAME     Q87 2
 '@S9S_MB_2U_LIB.S9S_MB_2U(SCH_1):PAGE241_I17@PURE_QUANTA.MOSFET_NCH_DUAL(CHIPS)':
 'G1': CDS_PINID='G1';
NODE_NAME     U249 J19
 '@S9S_MB_2U_LIB.S9S_MB_2U(SCH_1):PAGE313_I1@PURE_QUANTA.LCMXO3LF9400C5BG484C(CHIPS)':
 'PR11D': CDS_PINID='PR11D';
NODE_NAME     C1211 1
 '@S9S_MB_2U_LIB.S9S_MB_2U(SCH_1):PAGE209_I4@PURE_QUANTA.Q_CAP(CHIPS)':
 'A': CDS_PINID='A';
NET_NAME
'PWRGD_PLT_AUX_CPU0_LVT3'
 '@S9S_MB_2U_LIB.S9S_MB_2U(SCH_1):PWRGD_PLT_AUX_CPU0_LVT3':
 C_SIGNAL='@s9s_mb_2u_lib.s9s_mb_2u(sch_1):pwrgd_plt_aux_cpu0_lvt3';
NODE_NAME     U2 CV20
 '@S9S_MB_2U_LIB.S9S_MB_2U(SCH_1):PAGE15_I1@PURE_QUANTA.SOCKET4677_AZIF0045P001C01CS(CHIPS)':
 'PLT_AUX_PWRGOOD': CDS_PINID='PLT_AUX_PWRGOOD';
NODE_NAME     R67 2
 '@S9S_MB_2U_LIB.S9S_MB_2U(SCH_1):PAGE43_I12@PURE_QUANTA.Q_RES(CHIPS)':
 'B': CDS_PINID='B';
NODE_NAME     R69 1
 '@S9S_MB_2U_LIB.S9S_MB_2U(SCH_1):PAGE43_I16@PURE_QUANTA.Q_RES(CHIPS)':
 'A': CDS_PINID='A';
NET_NAME
'PWRGD_PLT_AUX_CPU0_LVT3_R'
 '@S9S_MB_2U_LIB.S9S_MB_2U(SCH_1):PWRGD_PLT_AUX_CPU0_LVT3_R':
 C_SIGNAL='@s9s_mb_2u_lib.s9s_mb_2u(sch_1):pwrgd_plt_aux_cpu0_lvt3_r';
NODE_NAME     R67 1
 '@S9S_MB_2U_LIB.S9S_MB_2U(SCH_1):PAGE43_I12@PURE_QUANTA.Q_RES(CHIPS)':
 'A': CDS_PINID='A';
NODE_NAME     U249 AA5
 '@S9S_MB_2U_LIB.S9S_MB_2U(SCH_1):PAGE312_I1@PURE_QUANTA.LCMXO3LF9400C5BG484C(CHIPS)':
 'PB10A': CDS_PINID='PB10A';
NET_NAME
'PWRGD_PLT_AUX_CPU1_LVT3'
 '@S9S_MB_2U_LIB.S9S_MB_2U(SCH_1):PWRGD_PLT_AUX_CPU1_LVT3':
 C_SIGNAL='@s9s_mb_2u_lib.s9s_mb_2u(sch_1):pwrgd_plt_aux_cpu1_lvt3';
NODE_NAME     R68 2
 '@S9S_MB_2U_LIB.S9S_MB_2U(SCH_1):PAGE43_I13@PURE_QUANTA.Q_RES(CHIPS)':
 'B': CDS_PINID='B';
NODE_NAME     R70 1
 '@S9S_MB_2U_LIB.S9S_MB_2U(SCH_1):PAGE43_I17@PURE_QUANTA.Q_RES(CHIPS)':
 'A': CDS_PINID='A';
NODE_NAME     U1 CV20
 '@S9S_MB_2U_LIB.S9S_MB_2U(SCH_1):PAGE46_I5@PURE_QUANTA.SOCKET4677_AZIF0045P001C01CS(CHIPS)':
 'PLT_AUX_PWRGOOD': CDS_PINID='PLT_AUX_PWRGOOD';
NET_NAME
'PWRGD_PLT_AUX_CPU1_LVT3_R'
 '@S9S_MB_2U_LIB.S9S_MB_2U(SCH_1):PWRGD_PLT_AUX_CPU1_LVT3_R':
 C_SIGNAL='@s9s_mb_2u_lib.s9s_mb_2u(sch_1):pwrgd_plt_aux_cpu1_lvt3_r';
NODE_NAME     R68 1
 '@S9S_MB_2U_LIB.S9S_MB_2U(SCH_1):PAGE43_I13@PURE_QUANTA.Q_RES(CHIPS)':
 'A': CDS_PINID='A';
NODE_NAME     U249 AB5
 '@S9S_MB_2U_LIB.S9S_MB_2U(SCH_1):PAGE312_I1@PURE_QUANTA.LCMXO3LF9400C5BG484C(CHIPS)':
 'PB10B': CDS_PINID='PB10B';
NET_NAME
'PWRGD_PS_PWROK'
 '@S9S_MB_2U_LIB.S9S_MB_2U(SCH_1):PWRGD_PS_PWROK':
 C_SIGNAL='@s9s_mb_2u_lib.s9s_mb_2u(sch_1):pwrgd_ps_pwrok';
NODE_NAME     R3054 2
 '@S9S_MB_2U_LIB.S9S_MB_2U(SCH_1):PAGE215_I23@PURE_QUANTA.Q_RES(CHIPS)':
 'B': CDS_PINID='B';
NODE_NAME     R3048 2
 '@S9S_MB_2U_LIB.S9S_MB_2U(SCH_1):PAGE313_I86@PURE_QUANTA.Q_RES(CHIPS)':
 'B': CDS_PINID='B';
NODE_NAME     R1816 1
 '@S9S_MB_2U_LIB.S9S_MB_2U(SCH_1):PAGE227_I27@PURE_QUANTA.Q_RES(CHIPS)':
 'A': CDS_PINID='A';
NET_NAME
'PWRGD_PS_PWROK_ME_CONN'
 '@S9S_MB_2U_LIB.S9S_MB_2U(SCH_1):PWRGD_PS_PWROK_ME_CONN':
 C_SIGNAL='@s9s_mb_2u_lib.s9s_mb_2u(sch_1):pwrgd_ps_pwrok_me_conn';
NODE_NAME     R3054 1
 '@S9S_MB_2U_LIB.S9S_MB_2U(SCH_1):PAGE215_I23@PURE_QUANTA.Q_RES(CHIPS)':
 'A': CDS_PINID='A';
NODE_NAME     J100 18
 '@S9S_MB_2U_LIB.S9S_MB_2U(SCH_1):PAGE215_I32@PURE_QUANTA.SCONN20_513860200CV01(CHIPS)':
 '18': CDS_PINID='\18\';
NET_NAME
'PWRGD_PS_PWROK_PLD'
 '@S9S_MB_2U_LIB.S9S_MB_2U(SCH_1):PWRGD_PS_PWROK_PLD':
 C_SIGNAL='@s9s_mb_2u_lib.s9s_mb_2u(sch_1):pwrgd_ps_pwrok_pld';
NODE_NAME     Q78 5
 '@S9S_MB_2U_LIB.S9S_MB_2U(SCH_1):PAGE242_I26@PURE_QUANTA.MOSFET_NCH_DUAL(CHIPS)':
 'G2': CDS_PINID='G2';
NODE_NAME     R3047 2
 '@S9S_MB_2U_LIB.S9S_MB_2U(SCH_1):PAGE313_I85@PURE_QUANTA.Q_RES(CHIPS)':
 'B': CDS_PINID='B';
NODE_NAME     Q144 2
 '@S9S_MB_2U_LIB.S9S_MB_2U(SCH_1):PAGE213_I27@PURE_QUANTA.MOSFET_NCH_DUAL(CHIPS)':
 'G1': CDS_PINID='G1';
NET_NAME
'PWRGD_PS_PWROK_PLD_ISO'
 '@S9S_MB_2U_LIB.S9S_MB_2U(SCH_1):PWRGD_PS_PWROK_PLD_ISO':
 C_SIGNAL='@s9s_mb_2u_lib.s9s_mb_2u(sch_1):pwrgd_ps_pwrok_pld_iso';
NODE_NAME     Q144 3
 '@S9S_MB_2U_LIB.S9S_MB_2U(SCH_1):PAGE213_I21@PURE_QUANTA.MOSFET_NCH_DUAL(CHIPS)':
 'D2': CDS_PINID='D2';
NODE_NAME     R4605 2
 '@S9S_MB_2U_LIB.S9S_MB_2U(SCH_1):PAGE213_I22@PURE_QUANTA.Q_RES(CHIPS)':
 'B': CDS_PINID='B';
NODE_NAME     R1446 1
 '@S9S_MB_2U_LIB.S9S_MB_2U(SCH_1):PAGE213_I29@PURE_QUANTA.Q_RES(CHIPS)':
 'A': CDS_PINID='A';
NET_NAME
'PWRGD_PS_PWROK_PLD_ISO_R'
 '@S9S_MB_2U_LIB.S9S_MB_2U(SCH_1):PWRGD_PS_PWROK_PLD_ISO_R':
 C_SIGNAL='@s9s_mb_2u_lib.s9s_mb_2u(sch_1):pwrgd_ps_pwrok_pld_iso_r';
NODE_NAME     U249 H16
 '@S9S_MB_2U_LIB.S9S_MB_2U(SCH_1):PAGE313_I1@PURE_QUANTA.LCMXO3LF9400C5BG484C(CHIPS)':
 'PR10D': CDS_PINID='PR10D';
NODE_NAME     R1446 2
 '@S9S_MB_2U_LIB.S9S_MB_2U(SCH_1):PAGE213_I29@PURE_QUANTA.Q_RES(CHIPS)':
 'B': CDS_PINID='B';
NET_NAME
'PWRGD_PS_PWROK_PLD_N'
 '@S9S_MB_2U_LIB.S9S_MB_2U(SCH_1):PWRGD_PS_PWROK_PLD_N':
 C_SIGNAL='@s9s_mb_2u_lib.s9s_mb_2u(sch_1):pwrgd_ps_pwrok_pld_n';
NODE_NAME     R4604 2
 '@S9S_MB_2U_LIB.S9S_MB_2U(SCH_1):PAGE213_I18@PURE_QUANTA.Q_RES(CHIPS)':
 'B': CDS_PINID='B';
NODE_NAME     Q144 5
 '@S9S_MB_2U_LIB.S9S_MB_2U(SCH_1):PAGE213_I21@PURE_QUANTA.MOSFET_NCH_DUAL(CHIPS)':
 'G2': CDS_PINID='G2';
NODE_NAME     Q144 6
 '@S9S_MB_2U_LIB.S9S_MB_2U(SCH_1):PAGE213_I27@PURE_QUANTA.MOSFET_NCH_DUAL(CHIPS)':
 'D1': CDS_PINID='D1';
NET_NAME
'PWRGD_PS_PWROK_R'
 '@S9S_MB_2U_LIB.S9S_MB_2U(SCH_1):PWRGD_PS_PWROK_R':
 C_SIGNAL='@s9s_mb_2u_lib.s9s_mb_2u(sch_1):pwrgd_ps_pwrok_r';
NODE_NAME     R1816 2
 '@S9S_MB_2U_LIB.S9S_MB_2U(SCH_1):PAGE227_I27@PURE_QUANTA.Q_RES(CHIPS)':
 'B': CDS_PINID='B';
NODE_NAME     J41 A44
 '@S9S_MB_2U_LIB.S9S_MB_2U(SCH_1):PAGE227_I173@PURE_QUANTA.SCONN168_ME1016810202011(CHIPS)':
 'PERN8': CDS_PINID='PERN8';
NET_NAME
'PWRGD_PVCCD_HV_CPU0'
 '@S9S_MB_2U_LIB.S9S_MB_2U(SCH_1):PWRGD_PVCCD_HV_CPU0':
 C_SIGNAL='@s9s_mb_2u_lib.s9s_mb_2u(sch_1):pwrgd_pvccd_hv_cpu0';
NODE_NAME     Q79 2
 '@S9S_MB_2U_LIB.S9S_MB_2U(SCH_1):PAGE305_I8@PURE_QUANTA.MOSFET_NCH_DUAL(CHIPS)':
 'G1': CDS_PINID='G1';
NODE_NAME     R362 1
 '@S9S_MB_2U_LIB.S9S_MB_2U(SCH_1):PAGE264_I44@PURE_QUANTA.Q_RES(CHIPS)':
 'A': CDS_PINID='A';
NODE_NAME     U249 F12
 '@S9S_MB_2U_LIB.S9S_MB_2U(SCH_1):PAGE314_I188@PURE_QUANTA.LCMXO3LF9400C5BG484C(CHIPS)':
 'PT28B': CDS_PINID='PT28B';
NET_NAME
'PWRGD_PVCCD_HV_CPU0_R'
 '@S9S_MB_2U_LIB.S9S_MB_2U(SCH_1):PWRGD_PVCCD_HV_CPU0_R':
 C_SIGNAL='@s9s_mb_2u_lib.s9s_mb_2u(sch_1):pwrgd_pvccd_hv_cpu0_r';
NODE_NAME     R361 2
 '@S9S_MB_2U_LIB.S9S_MB_2U(SCH_1):PAGE264_I46@PURE_QUANTA.Q_RES(CHIPS)':
 'B': CDS_PINID='B';
NODE_NAME     C626 1
 '@S9S_MB_2U_LIB.S9S_MB_2U(SCH_1):PAGE264_I47@PURE_QUANTA.Q_CAP(CHIPS)':
 'A': CDS_PINID='A';
NODE_NAME     PU35 12
 '@S9S_MB_2U_LIB.S9S_MB_2U(SCH_1):PAGE264_I53@PURE_QUANTA.ISL69260IRAZT(CHIPS)':
 'PG0': CDS_PINID='PG0';
NODE_NAME     R362 2
 '@S9S_MB_2U_LIB.S9S_MB_2U(SCH_1):PAGE264_I44@PURE_QUANTA.Q_RES(CHIPS)':
 'B': CDS_PINID='B';
NET_NAME
'PWRGD_PVCCD_HV_CPU1'
 '@S9S_MB_2U_LIB.S9S_MB_2U(SCH_1):PWRGD_PVCCD_HV_CPU1':
 C_SIGNAL='@s9s_mb_2u_lib.s9s_mb_2u(sch_1):pwrgd_pvccd_hv_cpu1';
NODE_NAME     Q84 2
 '@S9S_MB_2U_LIB.S9S_MB_2U(SCH_1):PAGE306_I18@PURE_QUANTA.MOSFET_NCH_DUAL(CHIPS)':
 'G1': CDS_PINID='G1';
NODE_NAME     U249 H18
 '@S9S_MB_2U_LIB.S9S_MB_2U(SCH_1):PAGE313_I1@PURE_QUANTA.LCMXO3LF9400C5BG484C(CHIPS)':
 'PR10B': CDS_PINID='PR10B';
NODE_NAME     R2576 1
 '@S9S_MB_2U_LIB.S9S_MB_2U(SCH_1):PAGE282_I44@PURE_QUANTA.Q_RES(CHIPS)':
 'A': CDS_PINID='A';
NET_NAME
'PWRGD_PVCCD_HV_CPU1_R'
 '@S9S_MB_2U_LIB.S9S_MB_2U(SCH_1):PWRGD_PVCCD_HV_CPU1_R':
 C_SIGNAL='@s9s_mb_2u_lib.s9s_mb_2u(sch_1):pwrgd_pvccd_hv_cpu1_r';
NODE_NAME     R2575 2
 '@S9S_MB_2U_LIB.S9S_MB_2U(SCH_1):PAGE282_I46@PURE_QUANTA.Q_RES(CHIPS)':
 'B': CDS_PINID='B';
NODE_NAME     PU18 12
 '@S9S_MB_2U_LIB.S9S_MB_2U(SCH_1):PAGE282_I53@PURE_QUANTA.ISL69260IRAZT(CHIPS)':
 'PG0': CDS_PINID='PG0';
NODE_NAME     C2454 1
 '@S9S_MB_2U_LIB.S9S_MB_2U(SCH_1):PAGE282_I45@PURE_QUANTA.Q_CAP(CHIPS)':
 'A': CDS_PINID='A';
NODE_NAME     R2576 2
 '@S9S_MB_2U_LIB.S9S_MB_2U(SCH_1):PAGE282_I44@PURE_QUANTA.Q_RES(CHIPS)':
 'B': CDS_PINID='B';
NET_NAME
'PWRGD_PVCCFA_EHV_CPU0'
 '@S9S_MB_2U_LIB.S9S_MB_2U(SCH_1):PWRGD_PVCCFA_EHV_CPU0':
 C_SIGNAL='@s9s_mb_2u_lib.s9s_mb_2u(sch_1):pwrgd_pvccfa_ehv_cpu0';
NODE_NAME     Q80 2
 '@S9S_MB_2U_LIB.S9S_MB_2U(SCH_1):PAGE305_I4@PURE_QUANTA.MOSFET_NCH_DUAL(CHIPS)':
 'G1': CDS_PINID='G1';
NODE_NAME     U249 H22
 '@S9S_MB_2U_LIB.S9S_MB_2U(SCH_1):PAGE313_I1@PURE_QUANTA.LCMXO3LF9400C5BG484C(CHIPS)':
 'PR7A': CDS_PINID='PR7A';
NODE_NAME     R2397 1
 '@S9S_MB_2U_LIB.S9S_MB_2U(SCH_1):PAGE260_I11@PURE_QUANTA.Q_RES(CHIPS)':
 'A': CDS_PINID='A';
NET_NAME
'PWRGD_PVCCFA_EHV_CPU0_R'
 '@S9S_MB_2U_LIB.S9S_MB_2U(SCH_1):PWRGD_PVCCFA_EHV_CPU0_R':
 C_SIGNAL='@s9s_mb_2u_lib.s9s_mb_2u(sch_1):pwrgd_pvccfa_ehv_cpu0_r';
NODE_NAME     PU5 16
 '@S9S_MB_2U_LIB.S9S_MB_2U(SCH_1):PAGE260_I65@PURE_QUANTA.ISL69260IRAZT(CHIPS)':
 'PG1': CDS_PINID='PG1';
NODE_NAME     R2397 2
 '@S9S_MB_2U_LIB.S9S_MB_2U(SCH_1):PAGE260_I11@PURE_QUANTA.Q_RES(CHIPS)':
 'B': CDS_PINID='B';
NODE_NAME     R2396 2
 '@S9S_MB_2U_LIB.S9S_MB_2U(SCH_1):PAGE260_I13@PURE_QUANTA.Q_RES(CHIPS)':
 'B': CDS_PINID='B';
NODE_NAME     C3276 1
 '@S9S_MB_2U_LIB.S9S_MB_2U(SCH_1):PAGE260_I22@PURE_QUANTA.Q_CAP(CHIPS)':
 'A': CDS_PINID='A';
NET_NAME
'PWRGD_PVCCFA_EHV_CPU1'
 '@S9S_MB_2U_LIB.S9S_MB_2U(SCH_1):PWRGD_PVCCFA_EHV_CPU1':
 C_SIGNAL='@s9s_mb_2u_lib.s9s_mb_2u(sch_1):pwrgd_pvccfa_ehv_cpu1';
NODE_NAME     Q85 2
 '@S9S_MB_2U_LIB.S9S_MB_2U(SCH_1):PAGE306_I6@PURE_QUANTA.MOSFET_NCH_DUAL(CHIPS)':
 'G1': CDS_PINID='G1';
NODE_NAME     U249 H21
 '@S9S_MB_2U_LIB.S9S_MB_2U(SCH_1):PAGE313_I1@PURE_QUANTA.LCMXO3LF9400C5BG484C(CHIPS)':
 'PR7B': CDS_PINID='PR7B';
NODE_NAME     R2572 1
 '@S9S_MB_2U_LIB.S9S_MB_2U(SCH_1):PAGE278_I29@PURE_QUANTA.Q_RES(CHIPS)':
 'A': CDS_PINID='A';
NET_NAME
'PWRGD_PVCCFA_EHV_CPU1_R'
 '@S9S_MB_2U_LIB.S9S_MB_2U(SCH_1):PWRGD_PVCCFA_EHV_CPU1_R':
 C_SIGNAL='@s9s_mb_2u_lib.s9s_mb_2u(sch_1):pwrgd_pvccfa_ehv_cpu1_r';
NODE_NAME     C2453 1
 '@S9S_MB_2U_LIB.S9S_MB_2U(SCH_1):PAGE278_I32@PURE_QUANTA.Q_CAP(CHIPS)':
 'A': CDS_PINID='A';
NODE_NAME     R2572 2
 '@S9S_MB_2U_LIB.S9S_MB_2U(SCH_1):PAGE278_I29@PURE_QUANTA.Q_RES(CHIPS)':
 'B': CDS_PINID='B';
NODE_NAME     R2571 2
 '@S9S_MB_2U_LIB.S9S_MB_2U(SCH_1):PAGE278_I30@PURE_QUANTA.Q_RES(CHIPS)':
 'B': CDS_PINID='B';
NODE_NAME     PU22 16
 '@S9S_MB_2U_LIB.S9S_MB_2U(SCH_1):PAGE278_I38@PURE_QUANTA.ISL69260IRAZT(CHIPS)':
 'PG1': CDS_PINID='PG1';
NET_NAME
'PWRGD_PVCCFA_EHV_FIVRA_CPU0'
 '@S9S_MB_2U_LIB.S9S_MB_2U(SCH_1):PWRGD_PVCCFA_EHV_FIVRA_CPU0':
 C_SIGNAL='@s9s_mb_2u_lib.s9s_mb_2u(sch_1):pwrgd_pvccfa_ehv_fivra_cpu0';
NODE_NAME     Q80 5
 '@S9S_MB_2U_LIB.S9S_MB_2U(SCH_1):PAGE305_I2@PURE_QUANTA.MOSFET_NCH_DUAL(CHIPS)':
 'G2': CDS_PINID='G2';
NODE_NAME     R2379 1
 '@S9S_MB_2U_LIB.S9S_MB_2U(SCH_1):PAGE252_I55@PURE_QUANTA.Q_RES(CHIPS)':
 'A': CDS_PINID='A';
NODE_NAME     U249 E13
 '@S9S_MB_2U_LIB.S9S_MB_2U(SCH_1):PAGE314_I188@PURE_QUANTA.LCMXO3LF9400C5BG484C(CHIPS)':
 'PT28C': CDS_PINID='PT28C';
NET_NAME
'PWRGD_PVCCFA_EHV_FIVRA_CPU0_R'
 '@S9S_MB_2U_LIB.S9S_MB_2U(SCH_1):PWRGD_PVCCFA_EHV_FIVRA_CPU0_R':
 C_SIGNAL='@s9s_mb_2u_lib.s9s_mb_2u(sch_1):pwrgd_pvccfa_ehv_fivra_cpu0_r';
NODE_NAME     PU14 20
 '@S9S_MB_2U_LIB.S9S_MB_2U(SCH_1):PAGE252_I63@PURE_QUANTA.RAA229126GNPHA0(CHIPS)':
 'PG1': CDS_PINID='PG1';
NODE_NAME     R2377 2
 '@S9S_MB_2U_LIB.S9S_MB_2U(SCH_1):PAGE252_I54@PURE_QUANTA.Q_RES(CHIPS)':
 'B': CDS_PINID='B';
NODE_NAME     R2379 2
 '@S9S_MB_2U_LIB.S9S_MB_2U(SCH_1):PAGE252_I55@PURE_QUANTA.Q_RES(CHIPS)':
 'B': CDS_PINID='B';
NODE_NAME     C3269 1
 '@S9S_MB_2U_LIB.S9S_MB_2U(SCH_1):PAGE252_I57@PURE_QUANTA.Q_CAP(CHIPS)':
 'A': CDS_PINID='A';
NET_NAME
'PWRGD_PVCCFA_EHV_FIVRA_CPU1'
 '@S9S_MB_2U_LIB.S9S_MB_2U(SCH_1):PWRGD_PVCCFA_EHV_FIVRA_CPU1':
 C_SIGNAL='@s9s_mb_2u_lib.s9s_mb_2u(sch_1):pwrgd_pvccfa_ehv_fivra_cpu1';
NODE_NAME     Q85 5
 '@S9S_MB_2U_LIB.S9S_MB_2U(SCH_1):PAGE306_I3@PURE_QUANTA.MOSFET_NCH_DUAL(CHIPS)':
 'G2': CDS_PINID='G2';
NODE_NAME     U249 H19
 '@S9S_MB_2U_LIB.S9S_MB_2U(SCH_1):PAGE313_I1@PURE_QUANTA.LCMXO3LF9400C5BG484C(CHIPS)':
 'PR10A': CDS_PINID='PR10A';
NODE_NAME     R2552 1
 '@S9S_MB_2U_LIB.S9S_MB_2U(SCH_1):PAGE270_I16@PURE_QUANTA.Q_RES(CHIPS)':
 'A': CDS_PINID='A';
NET_NAME
'PWRGD_PVCCFA_EHV_FIVRA_CPU1_R'
 '@S9S_MB_2U_LIB.S9S_MB_2U(SCH_1):PWRGD_PVCCFA_EHV_FIVRA_CPU1_R':
 C_SIGNAL='@s9s_mb_2u_lib.s9s_mb_2u(sch_1):pwrgd_pvccfa_ehv_fivra_cpu1_r';
NODE_NAME     C2447 1
 '@S9S_MB_2U_LIB.S9S_MB_2U(SCH_1):PAGE270_I35@PURE_QUANTA.Q_CAP(CHIPS)':
 'A': CDS_PINID='A';
NODE_NAME     R2552 2
 '@S9S_MB_2U_LIB.S9S_MB_2U(SCH_1):PAGE270_I16@PURE_QUANTA.Q_RES(CHIPS)':
 'B': CDS_PINID='B';
NODE_NAME     R2551 2
 '@S9S_MB_2U_LIB.S9S_MB_2U(SCH_1):PAGE270_I15@PURE_QUANTA.Q_RES(CHIPS)':
 'B': CDS_PINID='B';
NODE_NAME     PU29 20
 '@S9S_MB_2U_LIB.S9S_MB_2U(SCH_1):PAGE270_I33@PURE_QUANTA.RAA229126GNPHA0(CHIPS)':
 'PG1': CDS_PINID='PG1';
NET_NAME
'PWRGD_PVCCINFAON_CPU0'
 '@S9S_MB_2U_LIB.S9S_MB_2U(SCH_1):PWRGD_PVCCINFAON_CPU0':
 C_SIGNAL='@s9s_mb_2u_lib.s9s_mb_2u(sch_1):pwrgd_pvccinfaon_cpu0';
NODE_NAME     Q81 2
 '@S9S_MB_2U_LIB.S9S_MB_2U(SCH_1):PAGE305_I41@PURE_QUANTA.MOSFET_NCH_DUAL(CHIPS)':
 'G1': CDS_PINID='G1';
NODE_NAME     U249 G17
 '@S9S_MB_2U_LIB.S9S_MB_2U(SCH_1):PAGE313_I1@PURE_QUANTA.LCMXO3LF9400C5BG484C(CHIPS)':
 'PR7C': CDS_PINID='PR7C';
NODE_NAME     R2595 1
 '@S9S_MB_2U_LIB.S9S_MB_2U(SCH_1):PAGE260_I58@PURE_QUANTA.Q_RES(CHIPS)':
 'A': CDS_PINID='A';
NET_NAME
'PWRGD_PVCCINFAON_CPU0_R'
 '@S9S_MB_2U_LIB.S9S_MB_2U(SCH_1):PWRGD_PVCCINFAON_CPU0_R':
 C_SIGNAL='@s9s_mb_2u_lib.s9s_mb_2u(sch_1):pwrgd_pvccinfaon_cpu0_r';
NODE_NAME     R2383 2
 '@S9S_MB_2U_LIB.S9S_MB_2U(SCH_1):PAGE260_I59@PURE_QUANTA.Q_RES(CHIPS)':
 'B': CDS_PINID='B';
NODE_NAME     C3273 1
 '@S9S_MB_2U_LIB.S9S_MB_2U(SCH_1):PAGE260_I61@PURE_QUANTA.Q_CAP(CHIPS)':
 'A': CDS_PINID='A';
NODE_NAME     PU5 12
 '@S9S_MB_2U_LIB.S9S_MB_2U(SCH_1):PAGE260_I65@PURE_QUANTA.ISL69260IRAZT(CHIPS)':
 'PG0': CDS_PINID='PG0';
NODE_NAME     R2595 2
 '@S9S_MB_2U_LIB.S9S_MB_2U(SCH_1):PAGE260_I58@PURE_QUANTA.Q_RES(CHIPS)':
 'B': CDS_PINID='B';
NET_NAME
'PWRGD_PVCCINFAON_CPU1'
 '@S9S_MB_2U_LIB.S9S_MB_2U(SCH_1):PWRGD_PVCCINFAON_CPU1':
 C_SIGNAL='@s9s_mb_2u_lib.s9s_mb_2u(sch_1):pwrgd_pvccinfaon_cpu1';
NODE_NAME     Q86 2
 '@S9S_MB_2U_LIB.S9S_MB_2U(SCH_1):PAGE306_I35@PURE_QUANTA.MOSFET_NCH_DUAL(CHIPS)':
 'G1': CDS_PINID='G1';
NODE_NAME     U249 H20
 '@S9S_MB_2U_LIB.S9S_MB_2U(SCH_1):PAGE313_I1@PURE_QUANTA.LCMXO3LF9400C5BG484C(CHIPS)':
 'PR7D': CDS_PINID='PR7D';
NODE_NAME     R4781 1
 '@S9S_MB_2U_LIB.S9S_MB_2U(SCH_1):PAGE278_I103@PURE_QUANTA.Q_RES(CHIPS)':
 'A': CDS_PINID='A';
NET_NAME
'PWRGD_PVCCINFAON_CPU1_R'
 '@S9S_MB_2U_LIB.S9S_MB_2U(SCH_1):PWRGD_PVCCINFAON_CPU1_R':
 C_SIGNAL='@s9s_mb_2u_lib.s9s_mb_2u(sch_1):pwrgd_pvccinfaon_cpu1_r';
NODE_NAME     R4781 2
 '@S9S_MB_2U_LIB.S9S_MB_2U(SCH_1):PAGE278_I103@PURE_QUANTA.Q_RES(CHIPS)':
 'B': CDS_PINID='B';
NODE_NAME     PU22 12
 '@S9S_MB_2U_LIB.S9S_MB_2U(SCH_1):PAGE278_I38@PURE_QUANTA.ISL69260IRAZT(CHIPS)':
 'PG0': CDS_PINID='PG0';
NODE_NAME     R2556 2
 '@S9S_MB_2U_LIB.S9S_MB_2U(SCH_1):PAGE278_I105@PURE_QUANTA.Q_RES(CHIPS)':
 'B': CDS_PINID='B';
NODE_NAME     C2450 1
 '@S9S_MB_2U_LIB.S9S_MB_2U(SCH_1):PAGE278_I106@PURE_QUANTA.Q_CAP(CHIPS)':
 'A': CDS_PINID='A';
NET_NAME
'PWRGD_PVCCIN_CPU0'
 '@S9S_MB_2U_LIB.S9S_MB_2U(SCH_1):PWRGD_PVCCIN_CPU0':
 C_SIGNAL='@s9s_mb_2u_lib.s9s_mb_2u(sch_1):pwrgd_pvccin_cpu0';
NODE_NAME     Q83 2
 '@S9S_MB_2U_LIB.S9S_MB_2U(SCH_1):PAGE305_I32@PURE_QUANTA.MOSFET_NCH_DUAL(CHIPS)':
 'G1': CDS_PINID='G1';
NODE_NAME     R2366 1
 '@S9S_MB_2U_LIB.S9S_MB_2U(SCH_1):PAGE252_I49@PURE_QUANTA.Q_RES(CHIPS)':
 'A': CDS_PINID='A';
NODE_NAME     U249 F13
 '@S9S_MB_2U_LIB.S9S_MB_2U(SCH_1):PAGE314_I188@PURE_QUANTA.LCMXO3LF9400C5BG484C(CHIPS)':
 'PT28D': CDS_PINID='PT28D';
NET_NAME
'PWRGD_PVCCIN_CPU0_R'
 '@S9S_MB_2U_LIB.S9S_MB_2U(SCH_1):PWRGD_PVCCIN_CPU0_R':
 C_SIGNAL='@s9s_mb_2u_lib.s9s_mb_2u(sch_1):pwrgd_pvccin_cpu0_r';
NODE_NAME     R2365 2
 '@S9S_MB_2U_LIB.S9S_MB_2U(SCH_1):PAGE252_I50@PURE_QUANTA.Q_RES(CHIPS)':
 'B': CDS_PINID='B';
NODE_NAME     R2366 2
 '@S9S_MB_2U_LIB.S9S_MB_2U(SCH_1):PAGE252_I49@PURE_QUANTA.Q_RES(CHIPS)':
 'B': CDS_PINID='B';
NODE_NAME     PU14 16
 '@S9S_MB_2U_LIB.S9S_MB_2U(SCH_1):PAGE252_I63@PURE_QUANTA.RAA229126GNPHA0(CHIPS)':
 'PG0': CDS_PINID='PG0';
NODE_NAME     C3266 1
 '@S9S_MB_2U_LIB.S9S_MB_2U(SCH_1):PAGE252_I84@PURE_QUANTA.Q_CAP(CHIPS)':
 'A': CDS_PINID='A';
NET_NAME
'PWRGD_PVCCIN_CPU1'
 '@S9S_MB_2U_LIB.S9S_MB_2U(SCH_1):PWRGD_PVCCIN_CPU1':
 C_SIGNAL='@s9s_mb_2u_lib.s9s_mb_2u(sch_1):pwrgd_pvccin_cpu1';
NODE_NAME     Q83 5
 '@S9S_MB_2U_LIB.S9S_MB_2U(SCH_1):PAGE306_I43@PURE_QUANTA.MOSFET_NCH_DUAL(CHIPS)':
 'G2': CDS_PINID='G2';
NODE_NAME     U249 G18
 '@S9S_MB_2U_LIB.S9S_MB_2U(SCH_1):PAGE313_I1@PURE_QUANTA.LCMXO3LF9400C5BG484C(CHIPS)':
 'PR6D': CDS_PINID='PR6D';
NODE_NAME     R308 1
 '@S9S_MB_2U_LIB.S9S_MB_2U(SCH_1):PAGE270_I60@PURE_QUANTA.Q_RES(CHIPS)':
 'A': CDS_PINID='A';
NET_NAME
'PWRGD_PVCCIN_CPU1_R'
 '@S9S_MB_2U_LIB.S9S_MB_2U(SCH_1):PWRGD_PVCCIN_CPU1_R':
 C_SIGNAL='@s9s_mb_2u_lib.s9s_mb_2u(sch_1):pwrgd_pvccin_cpu1_r';
NODE_NAME     R308 2
 '@S9S_MB_2U_LIB.S9S_MB_2U(SCH_1):PAGE270_I60@PURE_QUANTA.Q_RES(CHIPS)':
 'B': CDS_PINID='B';
NODE_NAME     R307 2
 '@S9S_MB_2U_LIB.S9S_MB_2U(SCH_1):PAGE270_I61@PURE_QUANTA.Q_RES(CHIPS)':
 'B': CDS_PINID='B';
NODE_NAME     C2859 1
 '@S9S_MB_2U_LIB.S9S_MB_2U(SCH_1):PAGE270_I68@PURE_QUANTA.Q_CAP(CHIPS)':
 'A': CDS_PINID='A';
NODE_NAME     PU29 16
 '@S9S_MB_2U_LIB.S9S_MB_2U(SCH_1):PAGE270_I33@PURE_QUANTA.RAA229126GNPHA0(CHIPS)':
 'PG0': CDS_PINID='PG0';
NET_NAME
'PWRGD_PVNN_MAIN_CPU0'
 '@S9S_MB_2U_LIB.S9S_MB_2U(SCH_1):PWRGD_PVNN_MAIN_CPU0':
 C_SIGNAL='@s9s_mb_2u_lib.s9s_mb_2u(sch_1):pwrgd_pvnn_main_cpu0';
NODE_NAME     U17 1
 '@S9S_MB_2U_LIB.S9S_MB_2U(SCH_1):PAGE134_I80@PURE_QUANTA.74CBTLV3126PW(CHIPS)':
 '1OE': CDS_PINID='\1oe\';
NODE_NAME     U17 4
 '@S9S_MB_2U_LIB.S9S_MB_2U(SCH_1):PAGE134_I80@PURE_QUANTA.74CBTLV3126PW(CHIPS)':
 '2OE': CDS_PINID='\2oe\';
NODE_NAME     U17 10
 '@S9S_MB_2U_LIB.S9S_MB_2U(SCH_1):PAGE134_I80@PURE_QUANTA.74CBTLV3126PW(CHIPS)':
 '3OE': CDS_PINID='\3oe\';
NODE_NAME     U17 13
 '@S9S_MB_2U_LIB.S9S_MB_2U(SCH_1):PAGE134_I80@PURE_QUANTA.74CBTLV3126PW(CHIPS)':
 '4OE': CDS_PINID='\4oe\';
NODE_NAME     U18 1
 '@S9S_MB_2U_LIB.S9S_MB_2U(SCH_1):PAGE134_I129@PURE_QUANTA.74CBTLV3126PW(CHIPS)':
 '1OE': CDS_PINID='\1oe\';
NODE_NAME     U18 4
 '@S9S_MB_2U_LIB.S9S_MB_2U(SCH_1):PAGE134_I129@PURE_QUANTA.74CBTLV3126PW(CHIPS)':
 '2OE': CDS_PINID='\2oe\';
NODE_NAME     U18 10
 '@S9S_MB_2U_LIB.S9S_MB_2U(SCH_1):PAGE134_I129@PURE_QUANTA.74CBTLV3126PW(CHIPS)':
 '3OE': CDS_PINID='\3oe\';
NODE_NAME     U18 13
 '@S9S_MB_2U_LIB.S9S_MB_2U(SCH_1):PAGE134_I129@PURE_QUANTA.74CBTLV3126PW(CHIPS)':
 '4OE': CDS_PINID='\4oe\';
NODE_NAME     Q81 5
 '@S9S_MB_2U_LIB.S9S_MB_2U(SCH_1):PAGE305_I40@PURE_QUANTA.MOSFET_NCH_DUAL(CHIPS)':
 'G2': CDS_PINID='G2';
NODE_NAME     C1296 1
 '@S9S_MB_2U_LIB.S9S_MB_2U(SCH_1):PAGE268_I31@PURE_QUANTA.Q_CAP(CHIPS)':
 'A': CDS_PINID='A';
NODE_NAME     R1652 2
 '@S9S_MB_2U_LIB.S9S_MB_2U(SCH_1):PAGE268_I33@PURE_QUANTA.Q_RES(CHIPS)':
 'B': CDS_PINID='B';
NODE_NAME     U249 A13
 '@S9S_MB_2U_LIB.S9S_MB_2U(SCH_1):PAGE314_I188@PURE_QUANTA.LCMXO3LF9400C5BG484C(CHIPS)':
 'PT29A': CDS_PINID='PT29A';
NET_NAME
'PWRGD_PVNN_MAIN_CPU0_R'
 '@S9S_MB_2U_LIB.S9S_MB_2U(SCH_1):PWRGD_PVNN_MAIN_CPU0_R':
 C_SIGNAL='@s9s_mb_2u_lib.s9s_mb_2u(sch_1):pwrgd_pvnn_main_cpu0_r';
NODE_NAME     R1652 1
 '@S9S_MB_2U_LIB.S9S_MB_2U(SCH_1):PAGE268_I33@PURE_QUANTA.Q_RES(CHIPS)':
 'A': CDS_PINID='A';
NODE_NAME     R2409 2
 '@S9S_MB_2U_LIB.S9S_MB_2U(SCH_1):PAGE268_I32@PURE_QUANTA.Q_RES(CHIPS)':
 'B': CDS_PINID='B';
NODE_NAME     PU81 9
 '@S9S_MB_2U_LIB.S9S_MB_2U(SCH_1):PAGE268_I22@PURE_QUANTA.RS53317LR(CHIPS)':
 'PGOOD': CDS_PINID='PGOOD';
NET_NAME
'PWRGD_PVNN_MAIN_CPU1'
 '@S9S_MB_2U_LIB.S9S_MB_2U(SCH_1):PWRGD_PVNN_MAIN_CPU1':
 C_SIGNAL='@s9s_mb_2u_lib.s9s_mb_2u(sch_1):pwrgd_pvnn_main_cpu1';
NODE_NAME     Q86 5
 '@S9S_MB_2U_LIB.S9S_MB_2U(SCH_1):PAGE306_I27@PURE_QUANTA.MOSFET_NCH_DUAL(CHIPS)':
 'G2': CDS_PINID='G2';
NODE_NAME     R2387 2
 '@S9S_MB_2U_LIB.S9S_MB_2U(SCH_1):PAGE286_I29@PURE_QUANTA.Q_RES(CHIPS)':
 'B': CDS_PINID='B';
NODE_NAME     U249 C13
 '@S9S_MB_2U_LIB.S9S_MB_2U(SCH_1):PAGE314_I188@PURE_QUANTA.LCMXO3LF9400C5BG484C(CHIPS)':
 'PT29C': CDS_PINID='PT29C';
NODE_NAME     C1297 1
 '@S9S_MB_2U_LIB.S9S_MB_2U(SCH_1):PAGE286_I37@PURE_QUANTA.Q_CAP(CHIPS)':
 'A': CDS_PINID='A';
NET_NAME
'PWRGD_PVNN_MAIN_CPU1_R'
 '@S9S_MB_2U_LIB.S9S_MB_2U(SCH_1):PWRGD_PVNN_MAIN_CPU1_R':
 C_SIGNAL='@s9s_mb_2u_lib.s9s_mb_2u(sch_1):pwrgd_pvnn_main_cpu1_r';
NODE_NAME     R2387 1
 '@S9S_MB_2U_LIB.S9S_MB_2U(SCH_1):PAGE286_I29@PURE_QUANTA.Q_RES(CHIPS)':
 'A': CDS_PINID='A';
NODE_NAME     R2584 2
 '@S9S_MB_2U_LIB.S9S_MB_2U(SCH_1):PAGE286_I31@PURE_QUANTA.Q_RES(CHIPS)':
 'B': CDS_PINID='B';
NODE_NAME     PU82 9
 '@S9S_MB_2U_LIB.S9S_MB_2U(SCH_1):PAGE286_I20@PURE_QUANTA.RS53317LR(CHIPS)':
 'PGOOD': CDS_PINID='PGOOD';
NET_NAME
'PWRGD_PVNN_PCH_AUX'
 '@S9S_MB_2U_LIB.S9S_MB_2U(SCH_1):PWRGD_PVNN_PCH_AUX':
 C_SIGNAL='@s9s_mb_2u_lib.s9s_mb_2u(sch_1):pwrgd_pvnn_pch_aux';
NODE_NAME     U249 B13
 '@S9S_MB_2U_LIB.S9S_MB_2U(SCH_1):PAGE314_I188@PURE_QUANTA.LCMXO3LF9400C5BG484C(CHIPS)':
 'PT29B': CDS_PINID='PT29B';
NODE_NAME     R4780 2
 '@S9S_MB_2U_LIB.S9S_MB_2U(SCH_1):PAGE248_I52@PURE_QUANTA.Q_RES(CHIPS)':
 'B': CDS_PINID='B';
NET_NAME
'PWRGD_PVPP_HBM_CPU0'
 '@S9S_MB_2U_LIB.S9S_MB_2U(SCH_1):PWRGD_PVPP_HBM_CPU0':
 C_SIGNAL='@s9s_mb_2u_lib.s9s_mb_2u(sch_1):pwrgd_pvpp_hbm_cpu0';
NODE_NAME     Q79 5
 '@S9S_MB_2U_LIB.S9S_MB_2U(SCH_1):PAGE305_I7@PURE_QUANTA.MOSFET_NCH_DUAL(CHIPS)':
 'G2': CDS_PINID='G2';
NODE_NAME     U249 D13
 '@S9S_MB_2U_LIB.S9S_MB_2U(SCH_1):PAGE314_I188@PURE_QUANTA.LCMXO3LF9400C5BG484C(CHIPS)':
 'PT29D': CDS_PINID='PT29D';
NODE_NAME     R2408 2
 '@S9S_MB_2U_LIB.S9S_MB_2U(SCH_1):PAGE267_I29@PURE_QUANTA.Q_RES(CHIPS)':
 'B': CDS_PINID='B';
NET_NAME
'PWRGD_PVPP_HBM_CPU0_R'
 '@S9S_MB_2U_LIB.S9S_MB_2U(SCH_1):PWRGD_PVPP_HBM_CPU0_R':
 C_SIGNAL='@s9s_mb_2u_lib.s9s_mb_2u(sch_1):pwrgd_pvpp_hbm_cpu0_r';
NODE_NAME     C1301 1
 '@S9S_MB_2U_LIB.S9S_MB_2U(SCH_1):PAGE267_I30@PURE_QUANTA.Q_CAP(CHIPS)':
 'A': CDS_PINID='A';
NODE_NAME     R2407 2
 '@S9S_MB_2U_LIB.S9S_MB_2U(SCH_1):PAGE267_I45@PURE_QUANTA.Q_RES(CHIPS)':
 'B': CDS_PINID='B';
NODE_NAME     PU79 9
 '@S9S_MB_2U_LIB.S9S_MB_2U(SCH_1):PAGE267_I19@PURE_QUANTA.RS53318LR(CHIPS)':
 'PGOOD': CDS_PINID='PGOOD';
NODE_NAME     R2408 1
 '@S9S_MB_2U_LIB.S9S_MB_2U(SCH_1):PAGE267_I29@PURE_QUANTA.Q_RES(CHIPS)':
 'A': CDS_PINID='A';
NET_NAME
'PWRGD_PVPP_HBM_CPU1'
 '@S9S_MB_2U_LIB.S9S_MB_2U(SCH_1):PWRGD_PVPP_HBM_CPU1':
 C_SIGNAL='@s9s_mb_2u_lib.s9s_mb_2u(sch_1):pwrgd_pvpp_hbm_cpu1';
NODE_NAME     Q84 5
 '@S9S_MB_2U_LIB.S9S_MB_2U(SCH_1):PAGE306_I8@PURE_QUANTA.MOSFET_NCH_DUAL(CHIPS)':
 'G2': CDS_PINID='G2';
NODE_NAME     R2380 2
 '@S9S_MB_2U_LIB.S9S_MB_2U(SCH_1):PAGE285_I37@PURE_QUANTA.Q_RES(CHIPS)':
 'B': CDS_PINID='B';
NODE_NAME     U249 A14
 '@S9S_MB_2U_LIB.S9S_MB_2U(SCH_1):PAGE314_I188@PURE_QUANTA.LCMXO3LF9400C5BG484C(CHIPS)':
 'PT30A': CDS_PINID='PT30A';
NET_NAME
'PWRGD_PVPP_HBM_CPU1_R'
 '@S9S_MB_2U_LIB.S9S_MB_2U(SCH_1):PWRGD_PVPP_HBM_CPU1_R':
 C_SIGNAL='@s9s_mb_2u_lib.s9s_mb_2u(sch_1):pwrgd_pvpp_hbm_cpu1_r';
NODE_NAME     C2460 1
 '@S9S_MB_2U_LIB.S9S_MB_2U(SCH_1):PAGE285_I36@PURE_QUANTA.Q_CAP(CHIPS)':
 'A': CDS_PINID='A';
NODE_NAME     R2583 2
 '@S9S_MB_2U_LIB.S9S_MB_2U(SCH_1):PAGE285_I27@PURE_QUANTA.Q_RES(CHIPS)':
 'B': CDS_PINID='B';
NODE_NAME     PU80 9
 '@S9S_MB_2U_LIB.S9S_MB_2U(SCH_1):PAGE285_I25@PURE_QUANTA.RS53318LR(CHIPS)':
 'PGOOD': CDS_PINID='PGOOD';
NODE_NAME     R2380 1
 '@S9S_MB_2U_LIB.S9S_MB_2U(SCH_1):PAGE285_I37@PURE_QUANTA.Q_RES(CHIPS)':
 'A': CDS_PINID='A';
NET_NAME
'PWRGD_SYS_PWROK'
 '@S9S_MB_2U_LIB.S9S_MB_2U(SCH_1):PWRGD_SYS_PWROK':
 C_SIGNAL='@s9s_mb_2u_lib.s9s_mb_2u(sch_1):pwrgd_sys_pwrok';
NODE_NAME     U4 AL10
 '@S9S_MB_2U_LIB.S9S_MB_2U(SCH_1):PAGE174_I36@PURE_QUANTA.EMMITSBURG_REV0P9(CHIPS)':
 'SYS_PWROK': CDS_PINID='SYS_PWROK';
NODE_NAME     R1402 1
 '@S9S_MB_2U_LIB.S9S_MB_2U(SCH_1):PAGE208_I23@PURE_QUANTA.Q_RES(CHIPS)':
 'A': CDS_PINID='A';
NODE_NAME     R1423 2
 '@S9S_MB_2U_LIB.S9S_MB_2U(SCH_1):PAGE211_I44@PURE_QUANTA.Q_RES(CHIPS)':
 'B': CDS_PINID='B';
NODE_NAME     J41 A48
 '@S9S_MB_2U_LIB.S9S_MB_2U(SCH_1):PAGE227_I173@PURE_QUANTA.SCONN168_ME1016810202011(CHIPS)':
 'PERP9': CDS_PINID='PERP9';
NET_NAME
'PWRGD_SYS_PWROK_R'
 '@S9S_MB_2U_LIB.S9S_MB_2U(SCH_1):PWRGD_SYS_PWROK_R':
 C_SIGNAL='@s9s_mb_2u_lib.s9s_mb_2u(sch_1):pwrgd_sys_pwrok_r';
NODE_NAME     R1423 1
 '@S9S_MB_2U_LIB.S9S_MB_2U(SCH_1):PAGE211_I44@PURE_QUANTA.Q_RES(CHIPS)':
 'A': CDS_PINID='A';
NODE_NAME     Q87 5
 '@S9S_MB_2U_LIB.S9S_MB_2U(SCH_1):PAGE241_I16@PURE_QUANTA.MOSFET_NCH_DUAL(CHIPS)':
 'G2': CDS_PINID='G2';
NODE_NAME     U249 J18
 '@S9S_MB_2U_LIB.S9S_MB_2U(SCH_1):PAGE313_I1@PURE_QUANTA.LCMXO3LF9400C5BG484C(CHIPS)':
 'PR11C': CDS_PINID='PR11C';
NODE_NAME     C1209 1
 '@S9S_MB_2U_LIB.S9S_MB_2U(SCH_1):PAGE209_I3@PURE_QUANTA.Q_CAP(CHIPS)':
 'A': CDS_PINID='A';
NET_NAME
'RMII_BMC_OCP_RX_ER'
 '@S9S_MB_2U_LIB.S9S_MB_2U(SCH_1):RMII_BMC_OCP_RX_ER':
 C_SIGNAL='@s9s_mb_2u_lib.s9s_mb_2u(sch_1):rmii_bmc_ocp_rx_er';
NODE_NAME     R1356 1
 '@S9S_MB_2U_LIB.S9S_MB_2U(SCH_1):PAGE151_I53@PURE_QUANTA.Q_RES(CHIPS)':
 'A': CDS_PINID='A';
NODE_NAME     J41 B23
 '@S9S_MB_2U_LIB.S9S_MB_2U(SCH_1):PAGE227_I173@PURE_QUANTA.SCONN168_ME1016810202011(CHIPS)':
 'PETN2': CDS_PINID='PETN2';
NET_NAME
'RMII_BMC_OCP_TXD_0'
 '@S9S_MB_2U_LIB.S9S_MB_2U(SCH_1):RMII_BMC_OCP_TXD_0':
 C_SIGNAL='@s9s_mb_2u_lib.s9s_mb_2u(sch_1):rmii_bmc_ocp_txd_0';
NODE_NAME     R3214 2
 '@S9S_MB_2U_LIB.S9S_MB_2U(SCH_1):PAGE307_I60@PURE_QUANTA.Q_RES(CHIPS)':
 'B': CDS_PINID='B';
NODE_NAME     R1354 1
 '@S9S_MB_2U_LIB.S9S_MB_2U(SCH_1):PAGE151_I55@PURE_QUANTA.Q_RES(CHIPS)':
 'A': CDS_PINID='A';
NODE_NAME     R1295 2
 '@S9S_MB_2U_LIB.S9S_MB_2U(SCH_1):PAGE151_I65@PURE_QUANTA.Q_RES(CHIPS)':
 'B': CDS_PINID='B';
NODE_NAME     J41 B21
 '@S9S_MB_2U_LIB.S9S_MB_2U(SCH_1):PAGE227_I173@PURE_QUANTA.SCONN168_ME1016810202011(CHIPS)':
 'PETP1': CDS_PINID='PETP1';
NET_NAME
'RMII_BMC_OCP_TXD_1'
 '@S9S_MB_2U_LIB.S9S_MB_2U(SCH_1):RMII_BMC_OCP_TXD_1':
 C_SIGNAL='@s9s_mb_2u_lib.s9s_mb_2u(sch_1):rmii_bmc_ocp_txd_1';
NODE_NAME     R3215 2
 '@S9S_MB_2U_LIB.S9S_MB_2U(SCH_1):PAGE307_I56@PURE_QUANTA.Q_RES(CHIPS)':
 'B': CDS_PINID='B';
NODE_NAME     R1355 1
 '@S9S_MB_2U_LIB.S9S_MB_2U(SCH_1):PAGE151_I54@PURE_QUANTA.Q_RES(CHIPS)':
 'A': CDS_PINID='A';
NODE_NAME     R1296 2
 '@S9S_MB_2U_LIB.S9S_MB_2U(SCH_1):PAGE151_I61@PURE_QUANTA.Q_RES(CHIPS)':
 'B': CDS_PINID='B';
NODE_NAME     J41 B22
 '@S9S_MB_2U_LIB.S9S_MB_2U(SCH_1):PAGE227_I173@PURE_QUANTA.SCONN168_ME1016810202011(CHIPS)':
 'GND_B22': CDS_PINID='GND_B22';
NET_NAME
'RMII_BMC_OCP_TX_EN'
 '@S9S_MB_2U_LIB.S9S_MB_2U(SCH_1):RMII_BMC_OCP_TX_EN':
 C_SIGNAL='@s9s_mb_2u_lib.s9s_mb_2u(sch_1):rmii_bmc_ocp_tx_en';
NODE_NAME     R1353 1
 '@S9S_MB_2U_LIB.S9S_MB_2U(SCH_1):PAGE151_I56@PURE_QUANTA.Q_RES(CHIPS)':
 'A': CDS_PINID='A';
NODE_NAME     R3213 2
 '@S9S_MB_2U_LIB.S9S_MB_2U(SCH_1):PAGE307_I61@PURE_QUANTA.Q_RES(CHIPS)':
 'B': CDS_PINID='B';
NODE_NAME     R1294 2
 '@S9S_MB_2U_LIB.S9S_MB_2U(SCH_1):PAGE151_I66@PURE_QUANTA.Q_RES(CHIPS)':
 'B': CDS_PINID='B';
NODE_NAME     J41 B20
 '@S9S_MB_2U_LIB.S9S_MB_2U(SCH_1):PAGE227_I173@PURE_QUANTA.SCONN168_ME1016810202011(CHIPS)':
 'PETN1': CDS_PINID='PETN1';
NET_NAME
'RMII_OCP_BMC_CRSDV'
 '@S9S_MB_2U_LIB.S9S_MB_2U(SCH_1):RMII_OCP_BMC_CRSDV':
 C_SIGNAL='@s9s_mb_2u_lib.s9s_mb_2u(sch_1):rmii_ocp_bmc_crsdv';
NODE_NAME     R3210 2
 '@S9S_MB_2U_LIB.S9S_MB_2U(SCH_1):PAGE307_I65@PURE_QUANTA.Q_RES(CHIPS)':
 'B': CDS_PINID='B';
NODE_NAME     R1291 2
 '@S9S_MB_2U_LIB.S9S_MB_2U(SCH_1):PAGE151_I69@PURE_QUANTA.Q_RES(CHIPS)':
 'B': CDS_PINID='B';
NODE_NAME     R1350 1
 '@S9S_MB_2U_LIB.S9S_MB_2U(SCH_1):PAGE151_I73@PURE_QUANTA.Q_RES(CHIPS)':
 'A': CDS_PINID='A';
NODE_NAME     J41 B19
 '@S9S_MB_2U_LIB.S9S_MB_2U(SCH_1):PAGE227_I173@PURE_QUANTA.SCONN168_ME1016810202011(CHIPS)':
 'GND_B19': CDS_PINID='GND_B19';
NET_NAME
'RMII_OCP_BMC_RXD_0'
 '@S9S_MB_2U_LIB.S9S_MB_2U(SCH_1):RMII_OCP_BMC_RXD_0':
 C_SIGNAL='@s9s_mb_2u_lib.s9s_mb_2u(sch_1):rmii_ocp_bmc_rxd_0';
NODE_NAME     R3211 2
 '@S9S_MB_2U_LIB.S9S_MB_2U(SCH_1):PAGE307_I63@PURE_QUANTA.Q_RES(CHIPS)':
 'B': CDS_PINID='B';
NODE_NAME     R1292 2
 '@S9S_MB_2U_LIB.S9S_MB_2U(SCH_1):PAGE151_I68@PURE_QUANTA.Q_RES(CHIPS)':
 'B': CDS_PINID='B';
NODE_NAME     R1351 1
 '@S9S_MB_2U_LIB.S9S_MB_2U(SCH_1):PAGE151_I72@PURE_QUANTA.Q_RES(CHIPS)':
 'A': CDS_PINID='A';
NODE_NAME     J41 B24
 '@S9S_MB_2U_LIB.S9S_MB_2U(SCH_1):PAGE227_I173@PURE_QUANTA.SCONN168_ME1016810202011(CHIPS)':
 'PETP2': CDS_PINID='PETP2';
NET_NAME
'RMII_OCP_BMC_RXD_1'
 '@S9S_MB_2U_LIB.S9S_MB_2U(SCH_1):RMII_OCP_BMC_RXD_1':
 C_SIGNAL='@s9s_mb_2u_lib.s9s_mb_2u(sch_1):rmii_ocp_bmc_rxd_1';
NODE_NAME     R3212 2
 '@S9S_MB_2U_LIB.S9S_MB_2U(SCH_1):PAGE307_I62@PURE_QUANTA.Q_RES(CHIPS)':
 'B': CDS_PINID='B';
NODE_NAME     R1293 2
 '@S9S_MB_2U_LIB.S9S_MB_2U(SCH_1):PAGE151_I67@PURE_QUANTA.Q_RES(CHIPS)':
 'B': CDS_PINID='B';
NODE_NAME     R1352 1
 '@S9S_MB_2U_LIB.S9S_MB_2U(SCH_1):PAGE151_I71@PURE_QUANTA.Q_RES(CHIPS)':
 'A': CDS_PINID='A';
NODE_NAME     J41 B25
 '@S9S_MB_2U_LIB.S9S_MB_2U(SCH_1):PAGE227_I173@PURE_QUANTA.SCONN168_ME1016810202011(CHIPS)':
 'GND_B25': CDS_PINID='GND_B25';
NET_NAME
'ROT_P1_RST_IND_N'
 '@S9S_MB_2U_LIB.S9S_MB_2U(SCH_1):ROT_P1_RST_IND_N':
 C_SIGNAL='@s9s_mb_2u_lib.s9s_mb_2u(sch_1):rot_p1_rst_ind_n';
NODE_NAME     R1798 2
 '@S9S_MB_2U_LIB.S9S_MB_2U(SCH_1):PAGE227_I20@PURE_QUANTA.Q_RES(CHIPS)':
 'B': CDS_PINID='B';
NODE_NAME     J41 A53
 '@S9S_MB_2U_LIB.S9S_MB_2U(SCH_1):PAGE227_I173@PURE_QUANTA.SCONN168_ME1016810202011(CHIPS)':
 'PERN11': CDS_PINID='PERN11';
NET_NAME
'ROT_P1_RST_IND_N_R'
 '@S9S_MB_2U_LIB.S9S_MB_2U(SCH_1):ROT_P1_RST_IND_N_R':
 C_SIGNAL='@s9s_mb_2u_lib.s9s_mb_2u(sch_1):rot_p1_rst_ind_n_r';
NODE_NAME     U249 V15
 '@S9S_MB_2U_LIB.S9S_MB_2U(SCH_1):PAGE312_I1@PURE_QUANTA.LCMXO3LF9400C5BG484C(CHIPS)':
 'PB38C': CDS_PINID='PB38C';
NODE_NAME     R2244 1
 '@S9S_MB_2U_LIB.S9S_MB_2U(SCH_1):PAGE209_I39@PURE_QUANTA.Q_RES(CHIPS)':
 'A': CDS_PINID='A';
NODE_NAME     R1798 1
 '@S9S_MB_2U_LIB.S9S_MB_2U(SCH_1):PAGE227_I20@PURE_QUANTA.Q_RES(CHIPS)':
 'A': CDS_PINID='A';
NET_NAME
'RST_BMC_FROM_SWB'
 '@S9S_MB_2U_LIB.S9S_MB_2U(SCH_1):RST_BMC_FROM_SWB':
 C_SIGNAL='@s9s_mb_2u_lib.s9s_mb_2u(sch_1):rst_bmc_from_swb';
NODE_NAME     R2834 2
 '@S9S_MB_2U_LIB.S9S_MB_2U(SCH_1):PAGE145_I18@PURE_QUANTA.Q_RES(CHIPS)':
 'B': CDS_PINID='B';
NODE_NAME     Q69 5
 '@S9S_MB_2U_LIB.S9S_MB_2U(SCH_1):PAGE145_I88@PURE_QUANTA.MOSFET_NCH_DUAL(CHIPS)':
 'G2': CDS_PINID='G2';
NODE_NAME     Q69 6
 '@S9S_MB_2U_LIB.S9S_MB_2U(SCH_1):PAGE145_I117@PURE_QUANTA.MOSFET_NCH_DUAL(CHIPS)':
 'D1': CDS_PINID='D1';
NET_NAME
'RST_BMC_FROM_SWB_ISO_N'
 '@S9S_MB_2U_LIB.S9S_MB_2U(SCH_1):RST_BMC_FROM_SWB_ISO_N':
 C_SIGNAL='@s9s_mb_2u_lib.s9s_mb_2u(sch_1):rst_bmc_from_swb_iso_n';
NODE_NAME     Q69 3
 '@S9S_MB_2U_LIB.S9S_MB_2U(SCH_1):PAGE145_I88@PURE_QUANTA.MOSFET_NCH_DUAL(CHIPS)':
 'D2': CDS_PINID='D2';
NODE_NAME     R2919 2
 '@S9S_MB_2U_LIB.S9S_MB_2U(SCH_1):PAGE145_I91@PURE_QUANTA.Q_RES(CHIPS)':
 'B': CDS_PINID='B';
NODE_NAME     C1772 1
 '@S9S_MB_2U_LIB.S9S_MB_2U(SCH_1):PAGE145_I116@PURE_QUANTA.Q_CAP(CHIPS)':
 'A': CDS_PINID='A';
NODE_NAME     R2847 1
 '@S9S_MB_2U_LIB.S9S_MB_2U(SCH_1):PAGE314_I107@PURE_QUANTA.Q_RES(CHIPS)':
 'A': CDS_PINID='A';
NET_NAME
'RST_BMC_FROM_SWB_ISO_R_N'
 '@S9S_MB_2U_LIB.S9S_MB_2U(SCH_1):RST_BMC_FROM_SWB_ISO_R_N':
 C_SIGNAL='@s9s_mb_2u_lib.s9s_mb_2u(sch_1):rst_bmc_from_swb_iso_r_n';
NODE_NAME     R2847 2
 '@S9S_MB_2U_LIB.S9S_MB_2U(SCH_1):PAGE314_I107@PURE_QUANTA.Q_RES(CHIPS)':
 'B': CDS_PINID='B';
NODE_NAME     U249 F8
 '@S9S_MB_2U_LIB.S9S_MB_2U(SCH_1):PAGE314_I188@PURE_QUANTA.LCMXO3LF9400C5BG484C(CHIPS)':
 'PT11C': CDS_PINID='PT11C';
NET_NAME
'RST_BMC_FROM_SWB_N'
 '@S9S_MB_2U_LIB.S9S_MB_2U(SCH_1):RST_BMC_FROM_SWB_N':
 C_SIGNAL='@s9s_mb_2u_lib.s9s_mb_2u(sch_1):rst_bmc_from_swb_n';
NODE_NAME     J105 N8
 '@S9S_MB_2U_LIB.S9S_MB_2U(SCH_1):PAGE142_I68@PURE_QUANTA.CONN112_10137002101LF(CHIPS)':
 'N8': CDS_PINID='N8';
NODE_NAME     R2829 1
 '@S9S_MB_2U_LIB.S9S_MB_2U(SCH_1):PAGE145_I58@PURE_QUANTA.Q_RES(CHIPS)':
 'A': CDS_PINID='A';
NODE_NAME     R2828 2
 '@S9S_MB_2U_LIB.S9S_MB_2U(SCH_1):PAGE145_I66@PURE_QUANTA.Q_RES(CHIPS)':
 'B': CDS_PINID='B';
NODE_NAME     Q69 2
 '@S9S_MB_2U_LIB.S9S_MB_2U(SCH_1):PAGE145_I117@PURE_QUANTA.MOSFET_NCH_DUAL(CHIPS)':
 'G1': CDS_PINID='G1';
NET_NAME
'RST_CPU0_BUF_R_N'
 '@S9S_MB_2U_LIB.S9S_MB_2U(SCH_1):RST_CPU0_BUF_R_N':
 C_SIGNAL='@s9s_mb_2u_lib.s9s_mb_2u(sch_1):rst_cpu0_buf_r_n';
NODE_NAME     R171 2
 '@S9S_MB_2U_LIB.S9S_MB_2U(SCH_1):PAGE124_I52@PURE_QUANTA.Q_RES(CHIPS)':
 'B': CDS_PINID='B';
NODE_NAME     R185 1
 '@S9S_MB_2U_LIB.S9S_MB_2U(SCH_1):PAGE124_I60@PURE_QUANTA.Q_RES(CHIPS)':
 'A': CDS_PINID='A';
NODE_NAME     R186 1
 '@S9S_MB_2U_LIB.S9S_MB_2U(SCH_1):PAGE124_I78@PURE_QUANTA.Q_RES(CHIPS)':
 'A': CDS_PINID='A';
NET_NAME
'RST_CPU0_DRAM_AB_N'
 '@S9S_MB_2U_LIB.S9S_MB_2U(SCH_1):RST_CPU0_DRAM_AB_N':
 C_SIGNAL='@s9s_mb_2u_lib.s9s_mb_2u(sch_1):rst_cpu0_dram_ab_n';
NODE_NAME     U2 AU50
 '@S9S_MB_2U_LIB.S9S_MB_2U(SCH_1):PAGE13_I57@PURE_QUANTA.SOCKET4677_AZIF0045P001C01CS(CHIPS)':
 'DDR01_RESET_N': CDS_PINID='DDR01_RESET_N';
NODE_NAME     R851 1
 '@S9S_MB_2U_LIB.S9S_MB_2U(SCH_1):PAGE128_I12@PURE_QUANTA.Q_RES(CHIPS)':
 'A': CDS_PINID='A';
NODE_NAME     R932 1
 '@S9S_MB_2U_LIB.S9S_MB_2U(SCH_1):PAGE128_I80@PURE_QUANTA.Q_RES(CHIPS)':
 'A': CDS_PINID='A';
NET_NAME
'RST_CPU0_DRAM_AB_PLD_LVT3_N'
 '@S9S_MB_2U_LIB.S9S_MB_2U(SCH_1):RST_CPU0_DRAM_AB_PLD_LVT3_N':
 C_SIGNAL='@s9s_mb_2u_lib.s9s_mb_2u(sch_1):rst_cpu0_dram_ab_pld_lvt3_n';
NODE_NAME     U249 D3
 '@S9S_MB_2U_LIB.S9S_MB_2U(SCH_1):PAGE311_I33@PURE_QUANTA.LCMXO3LF9400C5BG484C(CHIPS)':
 'PL2A': CDS_PINID='PL2A';
NODE_NAME     R4042 2
 '@S9S_MB_2U_LIB.S9S_MB_2U(SCH_1):PAGE322_I39@PURE_QUANTA.Q_RES(CHIPS)':
 'B': CDS_PINID='B';
NET_NAME
'RST_CPU0_DRAM_AB_PLD_LVT3_R_N'
 '@S9S_MB_2U_LIB.S9S_MB_2U(SCH_1):RST_CPU0_DRAM_AB_PLD_LVT3_R_N':
 C_SIGNAL='@s9s_mb_2u_lib.s9s_mb_2u(sch_1):rst_cpu0_dram_ab_pld_lvt3_r_n';
NODE_NAME     U304 9
 '@S9S_MB_2U_LIB.S9S_MB_2U(SCH_1):PAGE322_I27@PURE_QUANTA.GTL2014PW(CHIPS)':
 'A3': CDS_PINID='A3';
NODE_NAME     R4042 1
 '@S9S_MB_2U_LIB.S9S_MB_2U(SCH_1):PAGE322_I39@PURE_QUANTA.Q_RES(CHIPS)':
 'A': CDS_PINID='A';
NET_NAME
'RST_CPU0_DRAM_AB_PLD_N'
 '@S9S_MB_2U_LIB.S9S_MB_2U(SCH_1):RST_CPU0_DRAM_AB_PLD_N':
 C_SIGNAL='@s9s_mb_2u_lib.s9s_mb_2u(sch_1):rst_cpu0_dram_ab_pld_n';
NODE_NAME     R851 2
 '@S9S_MB_2U_LIB.S9S_MB_2U(SCH_1):PAGE128_I12@PURE_QUANTA.Q_RES(CHIPS)':
 'B': CDS_PINID='B';
NODE_NAME     U304 6
 '@S9S_MB_2U_LIB.S9S_MB_2U(SCH_1):PAGE322_I27@PURE_QUANTA.GTL2014PW(CHIPS)':
 'B3': CDS_PINID='B3';
NET_NAME
'RST_CPU0_DRAM_CD_N'
 '@S9S_MB_2U_LIB.S9S_MB_2U(SCH_1):RST_CPU0_DRAM_CD_N':
 C_SIGNAL='@s9s_mb_2u_lib.s9s_mb_2u(sch_1):rst_cpu0_dram_cd_n';
NODE_NAME     U2 AV51
 '@S9S_MB_2U_LIB.S9S_MB_2U(SCH_1):PAGE13_I57@PURE_QUANTA.SOCKET4677_AZIF0045P001C01CS(CHIPS)':
 'DDR23_RESET_N': CDS_PINID='DDR23_RESET_N';
NODE_NAME     R852 1
 '@S9S_MB_2U_LIB.S9S_MB_2U(SCH_1):PAGE128_I11@PURE_QUANTA.Q_RES(CHIPS)':
 'A': CDS_PINID='A';
NODE_NAME     R934 1
 '@S9S_MB_2U_LIB.S9S_MB_2U(SCH_1):PAGE128_I79@PURE_QUANTA.Q_RES(CHIPS)':
 'A': CDS_PINID='A';
NET_NAME
'RST_CPU0_DRAM_CD_PLD_LVT3_N'
 '@S9S_MB_2U_LIB.S9S_MB_2U(SCH_1):RST_CPU0_DRAM_CD_PLD_LVT3_N':
 C_SIGNAL='@s9s_mb_2u_lib.s9s_mb_2u(sch_1):rst_cpu0_dram_cd_pld_lvt3_n';
NODE_NAME     U249 D4
 '@S9S_MB_2U_LIB.S9S_MB_2U(SCH_1):PAGE311_I33@PURE_QUANTA.LCMXO3LF9400C5BG484C(CHIPS)':
 'PL2B': CDS_PINID='PL2B';
NODE_NAME     R4043 2
 '@S9S_MB_2U_LIB.S9S_MB_2U(SCH_1):PAGE322_I38@PURE_QUANTA.Q_RES(CHIPS)':
 'B': CDS_PINID='B';
NET_NAME
'RST_CPU0_DRAM_CD_PLD_LVT3_R_N'
 '@S9S_MB_2U_LIB.S9S_MB_2U(SCH_1):RST_CPU0_DRAM_CD_PLD_LVT3_R_N':
 C_SIGNAL='@s9s_mb_2u_lib.s9s_mb_2u(sch_1):rst_cpu0_dram_cd_pld_lvt3_r_n';
NODE_NAME     U304 10
 '@S9S_MB_2U_LIB.S9S_MB_2U(SCH_1):PAGE322_I27@PURE_QUANTA.GTL2014PW(CHIPS)':
 'A2': CDS_PINID='A2';
NODE_NAME     R4043 1
 '@S9S_MB_2U_LIB.S9S_MB_2U(SCH_1):PAGE322_I38@PURE_QUANTA.Q_RES(CHIPS)':
 'A': CDS_PINID='A';
NET_NAME
'RST_CPU0_DRAM_CD_PLD_N'
 '@S9S_MB_2U_LIB.S9S_MB_2U(SCH_1):RST_CPU0_DRAM_CD_PLD_N':
 C_SIGNAL='@s9s_mb_2u_lib.s9s_mb_2u(sch_1):rst_cpu0_dram_cd_pld_n';
NODE_NAME     R852 2
 '@S9S_MB_2U_LIB.S9S_MB_2U(SCH_1):PAGE128_I11@PURE_QUANTA.Q_RES(CHIPS)':
 'B': CDS_PINID='B';
NODE_NAME     U304 5
 '@S9S_MB_2U_LIB.S9S_MB_2U(SCH_1):PAGE322_I27@PURE_QUANTA.GTL2014PW(CHIPS)':
 'B2': CDS_PINID='B2';
NET_NAME
'RST_CPU0_DRAM_EF_N'
 '@S9S_MB_2U_LIB.S9S_MB_2U(SCH_1):RST_CPU0_DRAM_EF_N':
 C_SIGNAL='@s9s_mb_2u_lib.s9s_mb_2u(sch_1):rst_cpu0_dram_ef_n';
NODE_NAME     U2 CY42
 '@S9S_MB_2U_LIB.S9S_MB_2U(SCH_1):PAGE13_I57@PURE_QUANTA.SOCKET4677_AZIF0045P001C01CS(CHIPS)':
 'DDR45_RESET_N': CDS_PINID='DDR45_RESET_N';
NODE_NAME     R853 1
 '@S9S_MB_2U_LIB.S9S_MB_2U(SCH_1):PAGE128_I10@PURE_QUANTA.Q_RES(CHIPS)':
 'A': CDS_PINID='A';
NODE_NAME     R936 1
 '@S9S_MB_2U_LIB.S9S_MB_2U(SCH_1):PAGE128_I78@PURE_QUANTA.Q_RES(CHIPS)':
 'A': CDS_PINID='A';
NET_NAME
'RST_CPU0_DRAM_EF_PLD_LVT3_N'
 '@S9S_MB_2U_LIB.S9S_MB_2U(SCH_1):RST_CPU0_DRAM_EF_PLD_LVT3_N':
 C_SIGNAL='@s9s_mb_2u_lib.s9s_mb_2u(sch_1):rst_cpu0_dram_ef_pld_lvt3_n';
NODE_NAME     U249 F6
 '@S9S_MB_2U_LIB.S9S_MB_2U(SCH_1):PAGE311_I33@PURE_QUANTA.LCMXO3LF9400C5BG484C(CHIPS)':
 'PL2C': CDS_PINID='PL2C';
NODE_NAME     R4044 2
 '@S9S_MB_2U_LIB.S9S_MB_2U(SCH_1):PAGE322_I37@PURE_QUANTA.Q_RES(CHIPS)':
 'B': CDS_PINID='B';
NET_NAME
'RST_CPU0_DRAM_EF_PLD_LVT3_R_N'
 '@S9S_MB_2U_LIB.S9S_MB_2U(SCH_1):RST_CPU0_DRAM_EF_PLD_LVT3_R_N':
 C_SIGNAL='@s9s_mb_2u_lib.s9s_mb_2u(sch_1):rst_cpu0_dram_ef_pld_lvt3_r_n';
NODE_NAME     U304 12
 '@S9S_MB_2U_LIB.S9S_MB_2U(SCH_1):PAGE322_I27@PURE_QUANTA.GTL2014PW(CHIPS)':
 'A1': CDS_PINID='A1';
NODE_NAME     R4044 1
 '@S9S_MB_2U_LIB.S9S_MB_2U(SCH_1):PAGE322_I37@PURE_QUANTA.Q_RES(CHIPS)':
 'A': CDS_PINID='A';
NET_NAME
'RST_CPU0_DRAM_EF_PLD_N'
 '@S9S_MB_2U_LIB.S9S_MB_2U(SCH_1):RST_CPU0_DRAM_EF_PLD_N':
 C_SIGNAL='@s9s_mb_2u_lib.s9s_mb_2u(sch_1):rst_cpu0_dram_ef_pld_n';
NODE_NAME     R853 2
 '@S9S_MB_2U_LIB.S9S_MB_2U(SCH_1):PAGE128_I10@PURE_QUANTA.Q_RES(CHIPS)':
 'B': CDS_PINID='B';
NODE_NAME     U304 3
 '@S9S_MB_2U_LIB.S9S_MB_2U(SCH_1):PAGE322_I27@PURE_QUANTA.GTL2014PW(CHIPS)':
 'B1': CDS_PINID='B1';
NET_NAME
'RST_CPU0_DRAM_GH_N'
 '@S9S_MB_2U_LIB.S9S_MB_2U(SCH_1):RST_CPU0_DRAM_GH_N':
 C_SIGNAL='@s9s_mb_2u_lib.s9s_mb_2u(sch_1):rst_cpu0_dram_gh_n';
NODE_NAME     U2 CY55
 '@S9S_MB_2U_LIB.S9S_MB_2U(SCH_1):PAGE13_I57@PURE_QUANTA.SOCKET4677_AZIF0045P001C01CS(CHIPS)':
 'DDR67_RESET_N': CDS_PINID='DDR67_RESET_N';
NODE_NAME     R854 1
 '@S9S_MB_2U_LIB.S9S_MB_2U(SCH_1):PAGE128_I9@PURE_QUANTA.Q_RES(CHIPS)':
 'A': CDS_PINID='A';
NODE_NAME     R938 1
 '@S9S_MB_2U_LIB.S9S_MB_2U(SCH_1):PAGE128_I77@PURE_QUANTA.Q_RES(CHIPS)':
 'A': CDS_PINID='A';
NET_NAME
'RST_CPU0_DRAM_GH_PLD_LVT3_N'
 '@S9S_MB_2U_LIB.S9S_MB_2U(SCH_1):RST_CPU0_DRAM_GH_PLD_LVT3_N':
 C_SIGNAL='@s9s_mb_2u_lib.s9s_mb_2u(sch_1):rst_cpu0_dram_gh_pld_lvt3_n';
NODE_NAME     U249 G7
 '@S9S_MB_2U_LIB.S9S_MB_2U(SCH_1):PAGE311_I33@PURE_QUANTA.LCMXO3LF9400C5BG484C(CHIPS)':
 'PL2D': CDS_PINID='PL2D';
NODE_NAME     R4045 2
 '@S9S_MB_2U_LIB.S9S_MB_2U(SCH_1):PAGE322_I36@PURE_QUANTA.Q_RES(CHIPS)':
 'B': CDS_PINID='B';
NET_NAME
'RST_CPU0_DRAM_GH_PLD_LVT3_R_N'
 '@S9S_MB_2U_LIB.S9S_MB_2U(SCH_1):RST_CPU0_DRAM_GH_PLD_LVT3_R_N':
 C_SIGNAL='@s9s_mb_2u_lib.s9s_mb_2u(sch_1):rst_cpu0_dram_gh_pld_lvt3_r_n';
NODE_NAME     U304 13
 '@S9S_MB_2U_LIB.S9S_MB_2U(SCH_1):PAGE322_I27@PURE_QUANTA.GTL2014PW(CHIPS)':
 'A0': CDS_PINID='A0';
NODE_NAME     R4045 1
 '@S9S_MB_2U_LIB.S9S_MB_2U(SCH_1):PAGE322_I36@PURE_QUANTA.Q_RES(CHIPS)':
 'A': CDS_PINID='A';
NET_NAME
'RST_CPU0_DRAM_GH_PLD_N'
 '@S9S_MB_2U_LIB.S9S_MB_2U(SCH_1):RST_CPU0_DRAM_GH_PLD_N':
 C_SIGNAL='@s9s_mb_2u_lib.s9s_mb_2u(sch_1):rst_cpu0_dram_gh_pld_n';
NODE_NAME     R854 2
 '@S9S_MB_2U_LIB.S9S_MB_2U(SCH_1):PAGE128_I9@PURE_QUANTA.Q_RES(CHIPS)':
 'B': CDS_PINID='B';
NODE_NAME     U304 2
 '@S9S_MB_2U_LIB.S9S_MB_2U(SCH_1):PAGE322_I27@PURE_QUANTA.GTL2014PW(CHIPS)':
 'B0': CDS_PINID='B0';
NET_NAME
'RST_CPU0_LVC1_N'
 '@S9S_MB_2U_LIB.S9S_MB_2U(SCH_1):RST_CPU0_LVC1_N':
 C_SIGNAL='@s9s_mb_2u_lib.s9s_mb_2u(sch_1):rst_cpu0_lvc1_n';
NODE_NAME     U2 BH61
 '@S9S_MB_2U_LIB.S9S_MB_2U(SCH_1):PAGE14_I1@PURE_QUANTA.SOCKET4677_AZIF0045P001C01CS(CHIPS)':
 'RESET_N': CDS_PINID='RESET_N';
NODE_NAME     R186 2
 '@S9S_MB_2U_LIB.S9S_MB_2U(SCH_1):PAGE124_I78@PURE_QUANTA.Q_RES(CHIPS)':
 'B': CDS_PINID='B';
NET_NAME
'RST_CPU0_LVC1_R_N'
 '@S9S_MB_2U_LIB.S9S_MB_2U(SCH_1):RST_CPU0_LVC1_R_N':
 C_SIGNAL='@s9s_mb_2u_lib.s9s_mb_2u(sch_1):rst_cpu0_lvc1_r_n';
NODE_NAME     R171 1
 '@S9S_MB_2U_LIB.S9S_MB_2U(SCH_1):PAGE124_I52@PURE_QUANTA.Q_RES(CHIPS)':
 'A': CDS_PINID='A';
NODE_NAME     R1415 1
 '@S9S_MB_2U_LIB.S9S_MB_2U(SCH_1):PAGE208_I4@PURE_QUANTA.Q_RES(CHIPS)':
 'A': CDS_PINID='A';
NODE_NAME     U249 U5
 '@S9S_MB_2U_LIB.S9S_MB_2U(SCH_1):PAGE311_I33@PURE_QUANTA.LCMXO3LF9400C5BG484C(CHIPS)':
 'PL28D': CDS_PINID='PL28D';
NET_NAME
'RST_CPU1_BUF_R_N'
 '@S9S_MB_2U_LIB.S9S_MB_2U(SCH_1):RST_CPU1_BUF_R_N':
 C_SIGNAL='@s9s_mb_2u_lib.s9s_mb_2u(sch_1):rst_cpu1_buf_r_n';
NODE_NAME     R132 2
 '@S9S_MB_2U_LIB.S9S_MB_2U(SCH_1):PAGE125_I3@PURE_QUANTA.Q_RES(CHIPS)':
 'B': CDS_PINID='B';
NODE_NAME     R157 1
 '@S9S_MB_2U_LIB.S9S_MB_2U(SCH_1):PAGE125_I24@PURE_QUANTA.Q_RES(CHIPS)':
 'A': CDS_PINID='A';
NODE_NAME     R158 1
 '@S9S_MB_2U_LIB.S9S_MB_2U(SCH_1):PAGE125_I65@PURE_QUANTA.Q_RES(CHIPS)':
 'A': CDS_PINID='A';
NET_NAME
'RST_CPU1_DRAM_AB_N'
 '@S9S_MB_2U_LIB.S9S_MB_2U(SCH_1):RST_CPU1_DRAM_AB_N':
 C_SIGNAL='@s9s_mb_2u_lib.s9s_mb_2u(sch_1):rst_cpu1_dram_ab_n';
NODE_NAME     U1 AU50
 '@S9S_MB_2U_LIB.S9S_MB_2U(SCH_1):PAGE44_I51@PURE_QUANTA.SOCKET4677_AZIF0045P001C01CS(CHIPS)':
 'DDR01_RESET_N': CDS_PINID='DDR01_RESET_N';
NODE_NAME     R859 1
 '@S9S_MB_2U_LIB.S9S_MB_2U(SCH_1):PAGE128_I50@PURE_QUANTA.Q_RES(CHIPS)':
 'A': CDS_PINID='A';
NODE_NAME     R933 1
 '@S9S_MB_2U_LIB.S9S_MB_2U(SCH_1):PAGE128_I82@PURE_QUANTA.Q_RES(CHIPS)':
 'A': CDS_PINID='A';
NET_NAME
'RST_CPU1_DRAM_AB_PLD_LVT3_N'
 '@S9S_MB_2U_LIB.S9S_MB_2U(SCH_1):RST_CPU1_DRAM_AB_PLD_LVT3_N':
 C_SIGNAL='@s9s_mb_2u_lib.s9s_mb_2u(sch_1):rst_cpu1_dram_ab_pld_lvt3_n';
NODE_NAME     U249 E4
 '@S9S_MB_2U_LIB.S9S_MB_2U(SCH_1):PAGE311_I33@PURE_QUANTA.LCMXO3LF9400C5BG484C(CHIPS)':
 'PL3A||L_GPLLT_FB': CDS_PINID='\pl3a||l_gpllt_fb\';
NODE_NAME     R4046 2
 '@S9S_MB_2U_LIB.S9S_MB_2U(SCH_1):PAGE322_I52@PURE_QUANTA.Q_RES(CHIPS)':
 'B': CDS_PINID='B';
NET_NAME
'RST_CPU1_DRAM_AB_PLD_LVT3_R_N'
 '@S9S_MB_2U_LIB.S9S_MB_2U(SCH_1):RST_CPU1_DRAM_AB_PLD_LVT3_R_N':
 C_SIGNAL='@s9s_mb_2u_lib.s9s_mb_2u(sch_1):rst_cpu1_dram_ab_pld_lvt3_r_n';
NODE_NAME     U305 9
 '@S9S_MB_2U_LIB.S9S_MB_2U(SCH_1):PAGE322_I44@PURE_QUANTA.GTL2014PW(CHIPS)':
 'A3': CDS_PINID='A3';
NODE_NAME     R4046 1
 '@S9S_MB_2U_LIB.S9S_MB_2U(SCH_1):PAGE322_I52@PURE_QUANTA.Q_RES(CHIPS)':
 'A': CDS_PINID='A';
NET_NAME
'RST_CPU1_DRAM_AB_PLD_N'
 '@S9S_MB_2U_LIB.S9S_MB_2U(SCH_1):RST_CPU1_DRAM_AB_PLD_N':
 C_SIGNAL='@s9s_mb_2u_lib.s9s_mb_2u(sch_1):rst_cpu1_dram_ab_pld_n';
NODE_NAME     R859 2
 '@S9S_MB_2U_LIB.S9S_MB_2U(SCH_1):PAGE128_I50@PURE_QUANTA.Q_RES(CHIPS)':
 'B': CDS_PINID='B';
NODE_NAME     U305 6
 '@S9S_MB_2U_LIB.S9S_MB_2U(SCH_1):PAGE322_I44@PURE_QUANTA.GTL2014PW(CHIPS)':
 'B3': CDS_PINID='B3';
NET_NAME
'RST_CPU1_DRAM_CD_N'
 '@S9S_MB_2U_LIB.S9S_MB_2U(SCH_1):RST_CPU1_DRAM_CD_N':
 C_SIGNAL='@s9s_mb_2u_lib.s9s_mb_2u(sch_1):rst_cpu1_dram_cd_n';
NODE_NAME     U1 AV51
 '@S9S_MB_2U_LIB.S9S_MB_2U(SCH_1):PAGE44_I51@PURE_QUANTA.SOCKET4677_AZIF0045P001C01CS(CHIPS)':
 'DDR23_RESET_N': CDS_PINID='DDR23_RESET_N';
NODE_NAME     R860 1
 '@S9S_MB_2U_LIB.S9S_MB_2U(SCH_1):PAGE128_I51@PURE_QUANTA.Q_RES(CHIPS)':
 'A': CDS_PINID='A';
NODE_NAME     R935 1
 '@S9S_MB_2U_LIB.S9S_MB_2U(SCH_1):PAGE128_I86@PURE_QUANTA.Q_RES(CHIPS)':
 'A': CDS_PINID='A';
NET_NAME
'RST_CPU1_DRAM_CD_PLD_LVT3_N'
 '@S9S_MB_2U_LIB.S9S_MB_2U(SCH_1):RST_CPU1_DRAM_CD_PLD_LVT3_N':
 C_SIGNAL='@s9s_mb_2u_lib.s9s_mb_2u(sch_1):rst_cpu1_dram_cd_pld_lvt3_n';
NODE_NAME     U249 F5
 '@S9S_MB_2U_LIB.S9S_MB_2U(SCH_1):PAGE311_I33@PURE_QUANTA.LCMXO3LF9400C5BG484C(CHIPS)':
 'PL3B||L_GPLLC_FB': CDS_PINID='\pl3b||l_gpllc_fb\';
NODE_NAME     R4047 2
 '@S9S_MB_2U_LIB.S9S_MB_2U(SCH_1):PAGE322_I53@PURE_QUANTA.Q_RES(CHIPS)':
 'B': CDS_PINID='B';
NET_NAME
'RST_CPU1_DRAM_CD_PLD_LVT3_R_N'
 '@S9S_MB_2U_LIB.S9S_MB_2U(SCH_1):RST_CPU1_DRAM_CD_PLD_LVT3_R_N':
 C_SIGNAL='@s9s_mb_2u_lib.s9s_mb_2u(sch_1):rst_cpu1_dram_cd_pld_lvt3_r_n';
NODE_NAME     U305 10
 '@S9S_MB_2U_LIB.S9S_MB_2U(SCH_1):PAGE322_I44@PURE_QUANTA.GTL2014PW(CHIPS)':
 'A2': CDS_PINID='A2';
NODE_NAME     R4047 1
 '@S9S_MB_2U_LIB.S9S_MB_2U(SCH_1):PAGE322_I53@PURE_QUANTA.Q_RES(CHIPS)':
 'A': CDS_PINID='A';
NET_NAME
'RST_CPU1_DRAM_CD_PLD_N'
 '@S9S_MB_2U_LIB.S9S_MB_2U(SCH_1):RST_CPU1_DRAM_CD_PLD_N':
 C_SIGNAL='@s9s_mb_2u_lib.s9s_mb_2u(sch_1):rst_cpu1_dram_cd_pld_n';
NODE_NAME     R860 2
 '@S9S_MB_2U_LIB.S9S_MB_2U(SCH_1):PAGE128_I51@PURE_QUANTA.Q_RES(CHIPS)':
 'B': CDS_PINID='B';
NODE_NAME     U305 5
 '@S9S_MB_2U_LIB.S9S_MB_2U(SCH_1):PAGE322_I44@PURE_QUANTA.GTL2014PW(CHIPS)':
 'B2': CDS_PINID='B2';
NET_NAME
'RST_CPU1_DRAM_EF_N'
 '@S9S_MB_2U_LIB.S9S_MB_2U(SCH_1):RST_CPU1_DRAM_EF_N':
 C_SIGNAL='@s9s_mb_2u_lib.s9s_mb_2u(sch_1):rst_cpu1_dram_ef_n';
NODE_NAME     U1 CY42
 '@S9S_MB_2U_LIB.S9S_MB_2U(SCH_1):PAGE44_I51@PURE_QUANTA.SOCKET4677_AZIF0045P001C01CS(CHIPS)':
 'DDR45_RESET_N': CDS_PINID='DDR45_RESET_N';
NODE_NAME     R861 1
 '@S9S_MB_2U_LIB.S9S_MB_2U(SCH_1):PAGE128_I48@PURE_QUANTA.Q_RES(CHIPS)':
 'A': CDS_PINID='A';
NODE_NAME     R937 1
 '@S9S_MB_2U_LIB.S9S_MB_2U(SCH_1):PAGE128_I85@PURE_QUANTA.Q_RES(CHIPS)':
 'A': CDS_PINID='A';
NET_NAME
'RST_CPU1_DRAM_EF_PLD_LVT3_N'
 '@S9S_MB_2U_LIB.S9S_MB_2U(SCH_1):RST_CPU1_DRAM_EF_PLD_LVT3_N':
 C_SIGNAL='@s9s_mb_2u_lib.s9s_mb_2u(sch_1):rst_cpu1_dram_ef_pld_lvt3_n';
NODE_NAME     U249 G6
 '@S9S_MB_2U_LIB.S9S_MB_2U(SCH_1):PAGE311_I33@PURE_QUANTA.LCMXO3LF9400C5BG484C(CHIPS)':
 'PL3C': CDS_PINID='PL3C';
NODE_NAME     R4048 2
 '@S9S_MB_2U_LIB.S9S_MB_2U(SCH_1):PAGE322_I55@PURE_QUANTA.Q_RES(CHIPS)':
 'B': CDS_PINID='B';
NET_NAME
'RST_CPU1_DRAM_EF_PLD_LVT3_R_N'
 '@S9S_MB_2U_LIB.S9S_MB_2U(SCH_1):RST_CPU1_DRAM_EF_PLD_LVT3_R_N':
 C_SIGNAL='@s9s_mb_2u_lib.s9s_mb_2u(sch_1):rst_cpu1_dram_ef_pld_lvt3_r_n';
NODE_NAME     U305 12
 '@S9S_MB_2U_LIB.S9S_MB_2U(SCH_1):PAGE322_I44@PURE_QUANTA.GTL2014PW(CHIPS)':
 'A1': CDS_PINID='A1';
NODE_NAME     R4048 1
 '@S9S_MB_2U_LIB.S9S_MB_2U(SCH_1):PAGE322_I55@PURE_QUANTA.Q_RES(CHIPS)':
 'A': CDS_PINID='A';
NET_NAME
'RST_CPU1_DRAM_EF_PLD_N'
 '@S9S_MB_2U_LIB.S9S_MB_2U(SCH_1):RST_CPU1_DRAM_EF_PLD_N':
 C_SIGNAL='@s9s_mb_2u_lib.s9s_mb_2u(sch_1):rst_cpu1_dram_ef_pld_n';
NODE_NAME     R861 2
 '@S9S_MB_2U_LIB.S9S_MB_2U(SCH_1):PAGE128_I48@PURE_QUANTA.Q_RES(CHIPS)':
 'B': CDS_PINID='B';
NODE_NAME     U305 3
 '@S9S_MB_2U_LIB.S9S_MB_2U(SCH_1):PAGE322_I44@PURE_QUANTA.GTL2014PW(CHIPS)':
 'B1': CDS_PINID='B1';
NET_NAME
'RST_CPU1_DRAM_GH_N'
 '@S9S_MB_2U_LIB.S9S_MB_2U(SCH_1):RST_CPU1_DRAM_GH_N':
 C_SIGNAL='@s9s_mb_2u_lib.s9s_mb_2u(sch_1):rst_cpu1_dram_gh_n';
NODE_NAME     U1 CY55
 '@S9S_MB_2U_LIB.S9S_MB_2U(SCH_1):PAGE44_I51@PURE_QUANTA.SOCKET4677_AZIF0045P001C01CS(CHIPS)':
 'DDR67_RESET_N': CDS_PINID='DDR67_RESET_N';
NODE_NAME     R2969 1
 '@S9S_MB_2U_LIB.S9S_MB_2U(SCH_1):PAGE128_I49@PURE_QUANTA.Q_RES(CHIPS)':
 'A': CDS_PINID='A';
NODE_NAME     R939 1
 '@S9S_MB_2U_LIB.S9S_MB_2U(SCH_1):PAGE128_I83@PURE_QUANTA.Q_RES(CHIPS)':
 'A': CDS_PINID='A';
NET_NAME
'RST_CPU1_DRAM_GH_PLD_LVT3_N'
 '@S9S_MB_2U_LIB.S9S_MB_2U(SCH_1):RST_CPU1_DRAM_GH_PLD_LVT3_N':
 C_SIGNAL='@s9s_mb_2u_lib.s9s_mb_2u(sch_1):rst_cpu1_dram_gh_pld_lvt3_n';
NODE_NAME     U249 H7
 '@S9S_MB_2U_LIB.S9S_MB_2U(SCH_1):PAGE311_I33@PURE_QUANTA.LCMXO3LF9400C5BG484C(CHIPS)':
 'PL3D': CDS_PINID='PL3D';
NODE_NAME     R4049 2
 '@S9S_MB_2U_LIB.S9S_MB_2U(SCH_1):PAGE322_I54@PURE_QUANTA.Q_RES(CHIPS)':
 'B': CDS_PINID='B';
NET_NAME
'RST_CPU1_DRAM_GH_PLD_LVT3_R_N'
 '@S9S_MB_2U_LIB.S9S_MB_2U(SCH_1):RST_CPU1_DRAM_GH_PLD_LVT3_R_N':
 C_SIGNAL='@s9s_mb_2u_lib.s9s_mb_2u(sch_1):rst_cpu1_dram_gh_pld_lvt3_r_n';
NODE_NAME     U305 13
 '@S9S_MB_2U_LIB.S9S_MB_2U(SCH_1):PAGE322_I44@PURE_QUANTA.GTL2014PW(CHIPS)':
 'A0': CDS_PINID='A0';
NODE_NAME     R4049 1
 '@S9S_MB_2U_LIB.S9S_MB_2U(SCH_1):PAGE322_I54@PURE_QUANTA.Q_RES(CHIPS)':
 'A': CDS_PINID='A';
NET_NAME
'RST_CPU1_DRAM_GH_PLD_N'
 '@S9S_MB_2U_LIB.S9S_MB_2U(SCH_1):RST_CPU1_DRAM_GH_PLD_N':
 C_SIGNAL='@s9s_mb_2u_lib.s9s_mb_2u(sch_1):rst_cpu1_dram_gh_pld_n';
NODE_NAME     R2969 2
 '@S9S_MB_2U_LIB.S9S_MB_2U(SCH_1):PAGE128_I49@PURE_QUANTA.Q_RES(CHIPS)':
 'B': CDS_PINID='B';
NODE_NAME     U305 2
 '@S9S_MB_2U_LIB.S9S_MB_2U(SCH_1):PAGE322_I44@PURE_QUANTA.GTL2014PW(CHIPS)':
 'B0': CDS_PINID='B0';
NET_NAME
'RST_CPU1_LVC1_N'
 '@S9S_MB_2U_LIB.S9S_MB_2U(SCH_1):RST_CPU1_LVC1_N':
 C_SIGNAL='@s9s_mb_2u_lib.s9s_mb_2u(sch_1):rst_cpu1_lvc1_n';
NODE_NAME     U1 BH61
 '@S9S_MB_2U_LIB.S9S_MB_2U(SCH_1):PAGE45_I29@PURE_QUANTA.SOCKET4677_AZIF0045P001C01CS(CHIPS)':
 'RESET_N': CDS_PINID='RESET_N';
NODE_NAME     R158 2
 '@S9S_MB_2U_LIB.S9S_MB_2U(SCH_1):PAGE125_I65@PURE_QUANTA.Q_RES(CHIPS)':
 'B': CDS_PINID='B';
NET_NAME
'RST_CPU1_LVC1_R_N'
 '@S9S_MB_2U_LIB.S9S_MB_2U(SCH_1):RST_CPU1_LVC1_R_N':
 C_SIGNAL='@s9s_mb_2u_lib.s9s_mb_2u(sch_1):rst_cpu1_lvc1_r_n';
NODE_NAME     R132 1
 '@S9S_MB_2U_LIB.S9S_MB_2U(SCH_1):PAGE125_I3@PURE_QUANTA.Q_RES(CHIPS)':
 'A': CDS_PINID='A';
NODE_NAME     R1416 1
 '@S9S_MB_2U_LIB.S9S_MB_2U(SCH_1):PAGE208_I5@PURE_QUANTA.Q_RES(CHIPS)':
 'A': CDS_PINID='A';
NODE_NAME     U249 V4
 '@S9S_MB_2U_LIB.S9S_MB_2U(SCH_1):PAGE311_I33@PURE_QUANTA.LCMXO3LF9400C5BG484C(CHIPS)':
 'PL28C': CDS_PINID='PL28C';
NET_NAME
'RST_ESPI_RESET_N'
 '@S9S_MB_2U_LIB.S9S_MB_2U(SCH_1):RST_ESPI_RESET_N':
 C_SIGNAL='@s9s_mb_2u_lib.s9s_mb_2u(sch_1):rst_espi_reset_n';
NODE_NAME     U4 BF17
 '@S9S_MB_2U_LIB.S9S_MB_2U(SCH_1):PAGE175_I93@PURE_QUANTA.EMMITSBURG_REV0P9(CHIPS)':
 'GPPC_A_8_ESPI_RESET_N': CDS_PINID='GPPC_A_8_ESPI_RESET_N';
NODE_NAME     R2363 1
 '@S9S_MB_2U_LIB.S9S_MB_2U(SCH_1):PAGE190_I101@PURE_QUANTA.Q_RES(CHIPS)':
 'A': CDS_PINID='A';
NET_NAME
'RST_ESPI_RESET_N_R'
 '@S9S_MB_2U_LIB.S9S_MB_2U(SCH_1):RST_ESPI_RESET_N_R':
 C_SIGNAL='@s9s_mb_2u_lib.s9s_mb_2u(sch_1):rst_espi_reset_n_r';
NODE_NAME     U61 1
 '@S9S_MB_2U_LIB.S9S_MB_2U(SCH_1):PAGE190_I39@PURE_QUANTA.NC7SB3157(CHIPS)':
 'B1': CDS_PINID='B1';
NODE_NAME     R2363 2
 '@S9S_MB_2U_LIB.S9S_MB_2U(SCH_1):PAGE190_I101@PURE_QUANTA.Q_RES(CHIPS)':
 'B': CDS_PINID='B';
NET_NAME
'RST_HP_OCP_SFF_R_N'
 '@S9S_MB_2U_LIB.S9S_MB_2U(SCH_1):RST_HP_OCP_SFF_R_N':
 C_SIGNAL='@s9s_mb_2u_lib.s9s_mb_2u(sch_1):rst_hp_ocp_sff_r_n';
NODE_NAME     U224 4
 '@S9S_MB_2U_LIB.S9S_MB_2U(SCH_1):PAGE151_I7@PURE_QUANTA.74LVC1G126SE7(CHIPS)':
 'Y': CDS_PINID='Y';
NODE_NAME     R3232 1
 '@S9S_MB_2U_LIB.S9S_MB_2U(SCH_1):PAGE151_I13@PURE_QUANTA.Q_RES(CHIPS)':
 'A': CDS_PINID='A';
NODE_NAME     R3233 1
 '@S9S_MB_2U_LIB.S9S_MB_2U(SCH_1):PAGE151_I17@PURE_QUANTA.Q_RES(CHIPS)':
 'A': CDS_PINID='A';
NET_NAME
'RST_HP_OCP_V3_1_N'
 '@S9S_MB_2U_LIB.S9S_MB_2U(SCH_1):RST_HP_OCP_V3_1_N':
 C_SIGNAL='@s9s_mb_2u_lib.s9s_mb_2u(sch_1):rst_hp_ocp_v3_1_n';
NODE_NAME     U75 2
 '@S9S_MB_2U_LIB.S9S_MB_2U(SCH_1):PAGE152_I1@PURE_QUANTA.74LVC1G17GW(CHIPS)':
 'A': CDS_PINID='A';
NODE_NAME     U210 4
 '@S9S_MB_2U_LIB.S9S_MB_2U(SCH_1):PAGE154_I189@PURE_QUANTA.74LVC1G08W57(CHIPS)':
 'Y': CDS_PINID='Y';
NET_NAME
'RST_HP_OCP_V3_2_N'
 '@S9S_MB_2U_LIB.S9S_MB_2U(SCH_1):RST_HP_OCP_V3_2_N':
 C_SIGNAL='@s9s_mb_2u_lib.s9s_mb_2u(sch_1):rst_hp_ocp_v3_2_n';
NODE_NAME     U53 4
 '@S9S_MB_2U_LIB.S9S_MB_2U(SCH_1):PAGE132_I56@PURE_QUANTA.74LVC1G08W57(CHIPS)':
 'Y': CDS_PINID='Y';
NODE_NAME     U207 2
 '@S9S_MB_2U_LIB.S9S_MB_2U(SCH_1):PAGE156_I35@PURE_QUANTA.74LVC1G17GW(CHIPS)':
 'A': CDS_PINID='A';
NET_NAME
'RST_HP_OCP_V3_2_R_N'
 '@S9S_MB_2U_LIB.S9S_MB_2U(SCH_1):RST_HP_OCP_V3_2_R_N':
 C_SIGNAL='@s9s_mb_2u_lib.s9s_mb_2u(sch_1):rst_hp_ocp_v3_2_r_n';
NODE_NAME     R3236 1
 '@S9S_MB_2U_LIB.S9S_MB_2U(SCH_1):PAGE156_I70@PURE_QUANTA.Q_RES(CHIPS)':
 'A': CDS_PINID='A';
NODE_NAME     R3235 1
 '@S9S_MB_2U_LIB.S9S_MB_2U(SCH_1):PAGE156_I72@PURE_QUANTA.Q_RES(CHIPS)':
 'A': CDS_PINID='A';
NODE_NAME     U225 4
 '@S9S_MB_2U_LIB.S9S_MB_2U(SCH_1):PAGE156_I74@PURE_QUANTA.74LVC1G126SE7(CHIPS)':
 'Y': CDS_PINID='Y';
NET_NAME
'RST_MB_STBY_N'
 '@S9S_MB_2U_LIB.S9S_MB_2U(SCH_1):RST_MB_STBY_N':
 C_SIGNAL='@s9s_mb_2u_lib.s9s_mb_2u(sch_1):rst_mb_stby_n';
NODE_NAME     R1206 2
 '@S9S_MB_2U_LIB.S9S_MB_2U(SCH_1):PAGE212_I10@PURE_QUANTA.Q_RES(CHIPS)':
 'B': CDS_PINID='B';
NODE_NAME     J41 A46
 '@S9S_MB_2U_LIB.S9S_MB_2U(SCH_1):PAGE227_I173@PURE_QUANTA.SCONN168_ME1016810202011(CHIPS)':
 'GND_A46': CDS_PINID='GND_A46';
NET_NAME
'RST_MB_STBY_R_N'
 '@S9S_MB_2U_LIB.S9S_MB_2U(SCH_1):RST_MB_STBY_R_N':
 C_SIGNAL='@s9s_mb_2u_lib.s9s_mb_2u(sch_1):rst_mb_stby_r_n';
NODE_NAME     R1206 1
 '@S9S_MB_2U_LIB.S9S_MB_2U(SCH_1):PAGE212_I10@PURE_QUANTA.Q_RES(CHIPS)':
 'A': CDS_PINID='A';
NODE_NAME     U249 AA6
 '@S9S_MB_2U_LIB.S9S_MB_2U(SCH_1):PAGE312_I1@PURE_QUANTA.LCMXO3LF9400C5BG484C(CHIPS)':
 'PB11A': CDS_PINID='PB11A';
NODE_NAME     R1823 2
 '@S9S_MB_2U_LIB.S9S_MB_2U(SCH_1):PAGE311_I4@PURE_QUANTA.Q_RES(CHIPS)':
 'B': CDS_PINID='B';
NET_NAME
'RST_M_AB_CPU0_FPGA_N'
 '@S9S_MB_2U_LIB.S9S_MB_2U(SCH_1):RST_M_AB_CPU0_FPGA_N':
 C_SIGNAL='@s9s_mb_2u_lib.s9s_mb_2u(sch_1):rst_m_ab_cpu0_fpga_n';
NODE_NAME     J1 207
 '@S9S_MB_2U_LIB.S9S_MB_2U(SCH_1):PAGE82_I198@PURE_QUANTA.SCONN288_ADR50017P130CC(CHIPS)':
 'RESET_N': CDS_PINID='RESET_N';
NODE_NAME     J2 207
 '@S9S_MB_2U_LIB.S9S_MB_2U(SCH_1):PAGE83_I177@PURE_QUANTA.SCONN288_ADR50017P087CC(CHIPS)':
 'RESET_N': CDS_PINID='RESET_N';
NODE_NAME     J4 207
 '@S9S_MB_2U_LIB.S9S_MB_2U(SCH_1):PAGE85_I23@PURE_QUANTA.SCONN288_ADR50017P087CC(CHIPS)':
 'RESET_N': CDS_PINID='RESET_N';
NODE_NAME     R836 2
 '@S9S_MB_2U_LIB.S9S_MB_2U(SCH_1):PAGE129_I26@PURE_QUANTA.Q_RES(CHIPS)':
 'B': CDS_PINID='B';
NODE_NAME     R840 2
 '@S9S_MB_2U_LIB.S9S_MB_2U(SCH_1):PAGE129_I119@PURE_QUANTA.Q_RES(CHIPS)':
 'B': CDS_PINID='B';
NODE_NAME     J3 207
 '@S9S_MB_2U_LIB.S9S_MB_2U(SCH_1):PAGE84_I180@PURE_QUANTA.SCONN288_ADR50017P130CC(CHIPS)':
 'RESET_N': CDS_PINID='RESET_N';
NET_NAME
'RST_M_AB_CPU1_FPGA_N'
 '@S9S_MB_2U_LIB.S9S_MB_2U(SCH_1):RST_M_AB_CPU1_FPGA_N':
 C_SIGNAL='@s9s_mb_2u_lib.s9s_mb_2u(sch_1):rst_m_ab_cpu1_fpga_n';
NODE_NAME     J17 207
 '@S9S_MB_2U_LIB.S9S_MB_2U(SCH_1):PAGE98_I12@PURE_QUANTA.SCONN288_ADR50017P130CC(CHIPS)':
 'RESET_N': CDS_PINID='RESET_N';
NODE_NAME     J18 207
 '@S9S_MB_2U_LIB.S9S_MB_2U(SCH_1):PAGE99_I24@PURE_QUANTA.SCONN288_ADR50017P087CC(CHIPS)':
 'RESET_N': CDS_PINID='RESET_N';
NODE_NAME     J19 207
 '@S9S_MB_2U_LIB.S9S_MB_2U(SCH_1):PAGE100_I25@PURE_QUANTA.SCONN288_ADR50017P130CC(CHIPS)':
 'RESET_N': CDS_PINID='RESET_N';
NODE_NAME     J20 207
 '@S9S_MB_2U_LIB.S9S_MB_2U(SCH_1):PAGE101_I47@PURE_QUANTA.SCONN288_ADR50017P087CC(CHIPS)':
 'RESET_N': CDS_PINID='RESET_N';
NODE_NAME     R816 2
 '@S9S_MB_2U_LIB.S9S_MB_2U(SCH_1):PAGE130_I37@PURE_QUANTA.Q_RES(CHIPS)':
 'B': CDS_PINID='B';
NODE_NAME     R820 2
 '@S9S_MB_2U_LIB.S9S_MB_2U(SCH_1):PAGE130_I82@PURE_QUANTA.Q_RES(CHIPS)':
 'B': CDS_PINID='B';
NET_NAME
'RST_M_CD_CPU0_FPGA_N'
 '@S9S_MB_2U_LIB.S9S_MB_2U(SCH_1):RST_M_CD_CPU0_FPGA_N':
 C_SIGNAL='@s9s_mb_2u_lib.s9s_mb_2u(sch_1):rst_m_cd_cpu0_fpga_n';
NODE_NAME     J5 207
 '@S9S_MB_2U_LIB.S9S_MB_2U(SCH_1):PAGE86_I24@PURE_QUANTA.SCONN288_ADR50017P130CC(CHIPS)':
 'RESET_N': CDS_PINID='RESET_N';
NODE_NAME     J6 207
 '@S9S_MB_2U_LIB.S9S_MB_2U(SCH_1):PAGE87_I46@PURE_QUANTA.SCONN288_ADR50017P087CC(CHIPS)':
 'RESET_N': CDS_PINID='RESET_N';
NODE_NAME     J7 207
 '@S9S_MB_2U_LIB.S9S_MB_2U(SCH_1):PAGE88_I12@PURE_QUANTA.SCONN288_ADR50017P130CC(CHIPS)':
 'RESET_N': CDS_PINID='RESET_N';
NODE_NAME     J8 207
 '@S9S_MB_2U_LIB.S9S_MB_2U(SCH_1):PAGE89_I50@PURE_QUANTA.SCONN288_ADR50017P087CC(CHIPS)':
 'RESET_N': CDS_PINID='RESET_N';
NODE_NAME     R837 2
 '@S9S_MB_2U_LIB.S9S_MB_2U(SCH_1):PAGE129_I59@PURE_QUANTA.Q_RES(CHIPS)':
 'B': CDS_PINID='B';
NODE_NAME     R841 2
 '@S9S_MB_2U_LIB.S9S_MB_2U(SCH_1):PAGE129_I121@PURE_QUANTA.Q_RES(CHIPS)':
 'B': CDS_PINID='B';
NET_NAME
'RST_M_CD_CPU1_FPGA_N'
 '@S9S_MB_2U_LIB.S9S_MB_2U(SCH_1):RST_M_CD_CPU1_FPGA_N':
 C_SIGNAL='@s9s_mb_2u_lib.s9s_mb_2u(sch_1):rst_m_cd_cpu1_fpga_n';
NODE_NAME     J21 207
 '@S9S_MB_2U_LIB.S9S_MB_2U(SCH_1):PAGE102_I13@PURE_QUANTA.SCONN288_ADR50017P130CC(CHIPS)':
 'RESET_N': CDS_PINID='RESET_N';
NODE_NAME     J22 207
 '@S9S_MB_2U_LIB.S9S_MB_2U(SCH_1):PAGE103_I51@PURE_QUANTA.SCONN288_ADR50017P087CC(CHIPS)':
 'RESET_N': CDS_PINID='RESET_N';
NODE_NAME     J23 207
 '@S9S_MB_2U_LIB.S9S_MB_2U(SCH_1):PAGE104_I25@PURE_QUANTA.SCONN288_ADR50017P130CC(CHIPS)':
 'RESET_N': CDS_PINID='RESET_N';
NODE_NAME     J24 207
 '@S9S_MB_2U_LIB.S9S_MB_2U(SCH_1):PAGE105_I178@PURE_QUANTA.SCONN288_ADR50017P087CC(CHIPS)':
 'RESET_N': CDS_PINID='RESET_N';
NODE_NAME     R817 2
 '@S9S_MB_2U_LIB.S9S_MB_2U(SCH_1):PAGE130_I26@PURE_QUANTA.Q_RES(CHIPS)':
 'B': CDS_PINID='B';
NODE_NAME     R821 2
 '@S9S_MB_2U_LIB.S9S_MB_2U(SCH_1):PAGE130_I84@PURE_QUANTA.Q_RES(CHIPS)':
 'B': CDS_PINID='B';
NET_NAME
'RST_M_EF_CPU0_FPGA_N'
 '@S9S_MB_2U_LIB.S9S_MB_2U(SCH_1):RST_M_EF_CPU0_FPGA_N':
 C_SIGNAL='@s9s_mb_2u_lib.s9s_mb_2u(sch_1):rst_m_ef_cpu0_fpga_n';
NODE_NAME     J9 207
 '@S9S_MB_2U_LIB.S9S_MB_2U(SCH_1):PAGE90_I12@PURE_QUANTA.SCONN288_ADR50017P130CC(CHIPS)':
 'RESET_N': CDS_PINID='RESET_N';
NODE_NAME     J10 207
 '@S9S_MB_2U_LIB.S9S_MB_2U(SCH_1):PAGE91_I13@PURE_QUANTA.SCONN288_ADR50017P087CC(CHIPS)':
 'RESET_N': CDS_PINID='RESET_N';
NODE_NAME     J11 207
 '@S9S_MB_2U_LIB.S9S_MB_2U(SCH_1):PAGE92_I25@PURE_QUANTA.SCONN288_ADR50017P130CC(CHIPS)':
 'RESET_N': CDS_PINID='RESET_N';
NODE_NAME     J12 207
 '@S9S_MB_2U_LIB.S9S_MB_2U(SCH_1):PAGE93_I24@PURE_QUANTA.SCONN288_ADR50017P087CC(CHIPS)':
 'RESET_N': CDS_PINID='RESET_N';
NODE_NAME     R838 2
 '@S9S_MB_2U_LIB.S9S_MB_2U(SCH_1):PAGE129_I76@PURE_QUANTA.Q_RES(CHIPS)':
 'B': CDS_PINID='B';
NODE_NAME     R842 2
 '@S9S_MB_2U_LIB.S9S_MB_2U(SCH_1):PAGE129_I123@PURE_QUANTA.Q_RES(CHIPS)':
 'B': CDS_PINID='B';
NET_NAME
'RST_M_EF_CPU1_FPGA_N'
 '@S9S_MB_2U_LIB.S9S_MB_2U(SCH_1):RST_M_EF_CPU1_FPGA_N':
 C_SIGNAL='@s9s_mb_2u_lib.s9s_mb_2u(sch_1):rst_m_ef_cpu1_fpga_n';
NODE_NAME     J25 207
 '@S9S_MB_2U_LIB.S9S_MB_2U(SCH_1):PAGE106_I180@PURE_QUANTA.SCONN288_ADR50017P130CC(CHIPS)':
 'RESET_N': CDS_PINID='RESET_N';
NODE_NAME     J26 207
 '@S9S_MB_2U_LIB.S9S_MB_2U(SCH_1):PAGE107_I180@PURE_QUANTA.SCONN288_ADR50017P087CC(CHIPS)':
 'RESET_N': CDS_PINID='RESET_N';
NODE_NAME     J27 207
 '@S9S_MB_2U_LIB.S9S_MB_2U(SCH_1):PAGE108_I179@PURE_QUANTA.SCONN288_ADR50017P130CC(CHIPS)':
 'RESET_N': CDS_PINID='RESET_N';
NODE_NAME     J28 207
 '@S9S_MB_2U_LIB.S9S_MB_2U(SCH_1):PAGE109_I47@PURE_QUANTA.SCONN288_ADR50017P087CC(CHIPS)':
 'RESET_N': CDS_PINID='RESET_N';
NODE_NAME     R818 2
 '@S9S_MB_2U_LIB.S9S_MB_2U(SCH_1):PAGE130_I22@PURE_QUANTA.Q_RES(CHIPS)':
 'B': CDS_PINID='B';
NODE_NAME     R822 2
 '@S9S_MB_2U_LIB.S9S_MB_2U(SCH_1):PAGE130_I88@PURE_QUANTA.Q_RES(CHIPS)':
 'B': CDS_PINID='B';
NET_NAME
'RST_M_GH_CPU0_FPGA_N'
 '@S9S_MB_2U_LIB.S9S_MB_2U(SCH_1):RST_M_GH_CPU0_FPGA_N':
 C_SIGNAL='@s9s_mb_2u_lib.s9s_mb_2u(sch_1):rst_m_gh_cpu0_fpga_n';
NODE_NAME     J13 207
 '@S9S_MB_2U_LIB.S9S_MB_2U(SCH_1):PAGE94_I11@PURE_QUANTA.SCONN288_ADR50017P130CC(CHIPS)':
 'RESET_N': CDS_PINID='RESET_N';
NODE_NAME     J14 207
 '@S9S_MB_2U_LIB.S9S_MB_2U(SCH_1):PAGE95_I47@PURE_QUANTA.SCONN288_ADR50017P087CC(CHIPS)':
 'RESET_N': CDS_PINID='RESET_N';
NODE_NAME     J15 207
 '@S9S_MB_2U_LIB.S9S_MB_2U(SCH_1):PAGE96_I48@PURE_QUANTA.SCONN288_ADR50017P130CC(CHIPS)':
 'RESET_N': CDS_PINID='RESET_N';
NODE_NAME     J16 207
 '@S9S_MB_2U_LIB.S9S_MB_2U(SCH_1):PAGE97_I6@PURE_QUANTA.SCONN288_ADR50017P087CC(CHIPS)':
 'RESET_N': CDS_PINID='RESET_N';
NODE_NAME     R835 2
 '@S9S_MB_2U_LIB.S9S_MB_2U(SCH_1):PAGE129_I86@PURE_QUANTA.Q_RES(CHIPS)':
 'B': CDS_PINID='B';
NODE_NAME     R839 2
 '@S9S_MB_2U_LIB.S9S_MB_2U(SCH_1):PAGE129_I125@PURE_QUANTA.Q_RES(CHIPS)':
 'B': CDS_PINID='B';
NET_NAME
'RST_M_GH_CPU1_FPGA_N'
 '@S9S_MB_2U_LIB.S9S_MB_2U(SCH_1):RST_M_GH_CPU1_FPGA_N':
 C_SIGNAL='@s9s_mb_2u_lib.s9s_mb_2u(sch_1):rst_m_gh_cpu1_fpga_n';
NODE_NAME     J29 207
 '@S9S_MB_2U_LIB.S9S_MB_2U(SCH_1):PAGE110_I179@PURE_QUANTA.SCONN288_ADR50017P130CC(CHIPS)':
 'RESET_N': CDS_PINID='RESET_N';
NODE_NAME     J30 207
 '@S9S_MB_2U_LIB.S9S_MB_2U(SCH_1):PAGE111_I179@PURE_QUANTA.SCONN288_ADR50017P087CC(CHIPS)':
 'RESET_N': CDS_PINID='RESET_N';
NODE_NAME     J31 207
 '@S9S_MB_2U_LIB.S9S_MB_2U(SCH_1):PAGE112_I180@PURE_QUANTA.SCONN288_ADR50017P130CC(CHIPS)':
 'RESET_N': CDS_PINID='RESET_N';
NODE_NAME     J32 207
 '@S9S_MB_2U_LIB.S9S_MB_2U(SCH_1):PAGE113_I179@PURE_QUANTA.SCONN288_ADR50017P087CC(CHIPS)':
 'RESET_N': CDS_PINID='RESET_N';
NODE_NAME     R815 2
 '@S9S_MB_2U_LIB.S9S_MB_2U(SCH_1):PAGE130_I11@PURE_QUANTA.Q_RES(CHIPS)':
 'B': CDS_PINID='B';
NODE_NAME     R819 2
 '@S9S_MB_2U_LIB.S9S_MB_2U(SCH_1):PAGE130_I90@PURE_QUANTA.Q_RES(CHIPS)':
 'B': CDS_PINID='B';
NET_NAME
'RST_OCP_V3_1_BUF_N'
 '@S9S_MB_2U_LIB.S9S_MB_2U(SCH_1):RST_OCP_V3_1_BUF_N':
 C_SIGNAL='@s9s_mb_2u_lib.s9s_mb_2u(sch_1):rst_ocp_v3_1_buf_n';
NODE_NAME     U75 4
 '@S9S_MB_2U_LIB.S9S_MB_2U(SCH_1):PAGE152_I1@PURE_QUANTA.74LVC1G17GW(CHIPS)':
 'Y': CDS_PINID='Y';
NODE_NAME     R419 1
 '@S9S_MB_2U_LIB.S9S_MB_2U(SCH_1):PAGE152_I6@PURE_QUANTA.Q_RES(CHIPS)':
 'A': CDS_PINID='A';
NODE_NAME     R435 1
 '@S9S_MB_2U_LIB.S9S_MB_2U(SCH_1):PAGE152_I8@PURE_QUANTA.Q_RES(CHIPS)':
 'A': CDS_PINID='A';
NODE_NAME     R1504 1
 '@S9S_MB_2U_LIB.S9S_MB_2U(SCH_1):PAGE152_I10@PURE_QUANTA.Q_RES(CHIPS)':
 'A': CDS_PINID='A';
NODE_NAME     R1505 1
 '@S9S_MB_2U_LIB.S9S_MB_2U(SCH_1):PAGE152_I13@PURE_QUANTA.Q_RES(CHIPS)':
 'A': CDS_PINID='A';
NET_NAME
'RST_OCP_V3_1_N'
 '@S9S_MB_2U_LIB.S9S_MB_2U(SCH_1):RST_OCP_V3_1_N':
 C_SIGNAL='@s9s_mb_2u_lib.s9s_mb_2u(sch_1):rst_ocp_v3_1_n';
NODE_NAME     R1514 2
 '@S9S_MB_2U_LIB.S9S_MB_2U(SCH_1):PAGE212_I105@PURE_QUANTA.Q_RES(CHIPS)':
 'B': CDS_PINID='B';
NODE_NAME     U210 2
 '@S9S_MB_2U_LIB.S9S_MB_2U(SCH_1):PAGE154_I189@PURE_QUANTA.74LVC1G08W57(CHIPS)':
 'B': CDS_PINID='B';
NET_NAME
'RST_OCP_V3_2_BUF_N'
 '@S9S_MB_2U_LIB.S9S_MB_2U(SCH_1):RST_OCP_V3_2_BUF_N':
 C_SIGNAL='@s9s_mb_2u_lib.s9s_mb_2u(sch_1):rst_ocp_v3_2_buf_n';
NODE_NAME     U207 4
 '@S9S_MB_2U_LIB.S9S_MB_2U(SCH_1):PAGE156_I35@PURE_QUANTA.74LVC1G17GW(CHIPS)':
 'Y': CDS_PINID='Y';
NODE_NAME     R3189 1
 '@S9S_MB_2U_LIB.S9S_MB_2U(SCH_1):PAGE156_I38@PURE_QUANTA.Q_RES(CHIPS)':
 'A': CDS_PINID='A';
NODE_NAME     R3188 1
 '@S9S_MB_2U_LIB.S9S_MB_2U(SCH_1):PAGE156_I39@PURE_QUANTA.Q_RES(CHIPS)':
 'A': CDS_PINID='A';
NODE_NAME     R3187 1
 '@S9S_MB_2U_LIB.S9S_MB_2U(SCH_1):PAGE156_I40@PURE_QUANTA.Q_RES(CHIPS)':
 'A': CDS_PINID='A';
NODE_NAME     R3186 1
 '@S9S_MB_2U_LIB.S9S_MB_2U(SCH_1):PAGE156_I41@PURE_QUANTA.Q_RES(CHIPS)':
 'A': CDS_PINID='A';
NET_NAME
'RST_OCP_V3_2_N'
 '@S9S_MB_2U_LIB.S9S_MB_2U(SCH_1):RST_OCP_V3_2_N':
 C_SIGNAL='@s9s_mb_2u_lib.s9s_mb_2u(sch_1):rst_ocp_v3_2_n';
NODE_NAME     R1520 2
 '@S9S_MB_2U_LIB.S9S_MB_2U(SCH_1):PAGE212_I113@PURE_QUANTA.Q_RES(CHIPS)':
 'B': CDS_PINID='B';
NODE_NAME     U53 2
 '@S9S_MB_2U_LIB.S9S_MB_2U(SCH_1):PAGE132_I56@PURE_QUANTA.74LVC1G08W57(CHIPS)':
 'B': CDS_PINID='B';
NET_NAME
'RST_PCH_RSTBTN_R_N'
 '@S9S_MB_2U_LIB.S9S_MB_2U(SCH_1):RST_PCH_RSTBTN_R_N':
 C_SIGNAL='@s9s_mb_2u_lib.s9s_mb_2u(sch_1):rst_pch_rstbtn_r_n';
NODE_NAME     U4 AJ10
 '@S9S_MB_2U_LIB.S9S_MB_2U(SCH_1):PAGE174_I36@PURE_QUANTA.EMMITSBURG_REV0P9(CHIPS)':
 'SYS_RESET_N': CDS_PINID='SYS_RESET_N';
NODE_NAME     R696 2
 '@S9S_MB_2U_LIB.S9S_MB_2U(SCH_1):PAGE174_I63@PURE_QUANTA.Q_RES(CHIPS)':
 'B': CDS_PINID='B';
NODE_NAME     R697 2
 '@S9S_MB_2U_LIB.S9S_MB_2U(SCH_1):PAGE174_I66@PURE_QUANTA.Q_RES(CHIPS)':
 'B': CDS_PINID='B';
NET_NAME
'RST_PCIE_CPU0_DEV_PERST_N'
 '@S9S_MB_2U_LIB.S9S_MB_2U(SCH_1):RST_PCIE_CPU0_DEV_PERST_N':
 C_SIGNAL='@s9s_mb_2u_lib.s9s_mb_2u(sch_1):rst_pcie_cpu0_dev_perst_n';
NODE_NAME     R1417 1
 '@S9S_MB_2U_LIB.S9S_MB_2U(SCH_1):PAGE208_I7@PURE_QUANTA.Q_RES(CHIPS)':
 'A': CDS_PINID='A';
NODE_NAME     R1514 1
 '@S9S_MB_2U_LIB.S9S_MB_2U(SCH_1):PAGE212_I105@PURE_QUANTA.Q_RES(CHIPS)':
 'A': CDS_PINID='A';
NODE_NAME     U249 M20
 '@S9S_MB_2U_LIB.S9S_MB_2U(SCH_1):PAGE313_I1@PURE_QUANTA.LCMXO3LF9400C5BG484C(CHIPS)':
 'PR17C': CDS_PINID='PR17C';
NET_NAME
'RST_PCIE_CPU1_DEV_PERST_N'
 '@S9S_MB_2U_LIB.S9S_MB_2U(SCH_1):RST_PCIE_CPU1_DEV_PERST_N':
 C_SIGNAL='@s9s_mb_2u_lib.s9s_mb_2u(sch_1):rst_pcie_cpu1_dev_perst_n';
NODE_NAME     R1418 1
 '@S9S_MB_2U_LIB.S9S_MB_2U(SCH_1):PAGE208_I6@PURE_QUANTA.Q_RES(CHIPS)':
 'A': CDS_PINID='A';
NODE_NAME     R1520 1
 '@S9S_MB_2U_LIB.S9S_MB_2U(SCH_1):PAGE212_I113@PURE_QUANTA.Q_RES(CHIPS)':
 'A': CDS_PINID='A';
NODE_NAME     U249 M19
 '@S9S_MB_2U_LIB.S9S_MB_2U(SCH_1):PAGE313_I1@PURE_QUANTA.LCMXO3LF9400C5BG484C(CHIPS)':
 'PR17D': CDS_PINID='PR17D';
NET_NAME
'RST_PCIE_PCH_DEV_0_N'
 '@S9S_MB_2U_LIB.S9S_MB_2U(SCH_1):RST_PCIE_PCH_DEV_0_N':
 C_SIGNAL='@s9s_mb_2u_lib.s9s_mb_2u(sch_1):rst_pcie_pch_dev_0_n';
NODE_NAME     J59 50
 '@S9S_MB_2U_LIB.S9S_MB_2U(SCH_1):PAGE182_I178@PURE_QUANTA.SCONN75K_APCI0155P004A(CHIPS)':
 'PERST#': CDS_PINID='\perst#\';
NODE_NAME     R2113 2
 '@S9S_MB_2U_LIB.S9S_MB_2U(SCH_1):PAGE182_I344@PURE_QUANTA.Q_RES(CHIPS)':
 'B': CDS_PINID='B';
NET_NAME
'RST_PCIE_PCH_DEV_BUF_M2_0_PERST'
 '@S9S_MB_2U_LIB.S9S_MB_2U(SCH_1):RST_PCIE_PCH_DEV_BUF_M2_0_PERST_N':
 C_SIGNAL='@s9s_mb_2u_lib.s9s_mb_2u(sch_1):rst_pcie_pch_dev_buf_m2_0_perst_n';
NODE_NAME     U259 4
 '@S9S_MB_2U_LIB.S9S_MB_2U(SCH_1):PAGE182_I327@PURE_QUANTA.SN74LVC2G07DCKR(CHIPS)':
 '2Y': CDS_PINID='\2y\';
NODE_NAME     R2121 2
 '@S9S_MB_2U_LIB.S9S_MB_2U(SCH_1):PAGE182_I337@PURE_QUANTA.Q_RES(CHIPS)':
 'B': CDS_PINID='B';
NODE_NAME     R2113 1
 '@S9S_MB_2U_LIB.S9S_MB_2U(SCH_1):PAGE182_I344@PURE_QUANTA.Q_RES(CHIPS)':
 'A': CDS_PINID='A';
NET_NAME
'RST_PCIE_PCH_DEV_PERST_E1S_R_N'
 '@S9S_MB_2U_LIB.S9S_MB_2U(SCH_1):RST_PCIE_PCH_DEV_PERST_E1S_R_N':
 C_SIGNAL='@s9s_mb_2u_lib.s9s_mb_2u(sch_1):rst_pcie_pch_dev_perst_e1s_r_n';
NODE_NAME     R3779 1
 '@S9S_MB_2U_LIB.S9S_MB_2U(SCH_1):PAGE297_I309@PURE_QUANTA.Q_RES(CHIPS)':
 'A': CDS_PINID='A';
NODE_NAME     R4174 2
 '@S9S_MB_2U_LIB.S9S_MB_2U(SCH_1):PAGE312_I134@PURE_QUANTA.Q_RES(CHIPS)':
 'B': CDS_PINID='B';
NET_NAME
'RST_PCIE_PCH_DEV_PERST_M2_R_N'
 '@S9S_MB_2U_LIB.S9S_MB_2U(SCH_1):RST_PCIE_PCH_DEV_PERST_M2_R_N':
 C_SIGNAL='@s9s_mb_2u_lib.s9s_mb_2u(sch_1):rst_pcie_pch_dev_perst_m2_r_n';
NODE_NAME     U259 3
 '@S9S_MB_2U_LIB.S9S_MB_2U(SCH_1):PAGE182_I327@PURE_QUANTA.SN74LVC2G07DCKR(CHIPS)':
 '2A': CDS_PINID='\2a\';
NODE_NAME     R4175 2
 '@S9S_MB_2U_LIB.S9S_MB_2U(SCH_1):PAGE312_I135@PURE_QUANTA.Q_RES(CHIPS)':
 'B': CDS_PINID='B';
NET_NAME
'RST_PCIE_PCH_DEV_PERST_N'
 '@S9S_MB_2U_LIB.S9S_MB_2U(SCH_1):RST_PCIE_PCH_DEV_PERST_N':
 C_SIGNAL='@s9s_mb_2u_lib.s9s_mb_2u(sch_1):rst_pcie_pch_dev_perst_n';
NODE_NAME     R1419 1
 '@S9S_MB_2U_LIB.S9S_MB_2U(SCH_1):PAGE208_I8@PURE_QUANTA.Q_RES(CHIPS)':
 'A': CDS_PINID='A';
NODE_NAME     U249 U14
 '@S9S_MB_2U_LIB.S9S_MB_2U(SCH_1):PAGE312_I1@PURE_QUANTA.LCMXO3LF9400C5BG484C(CHIPS)':
 'PB32C': CDS_PINID='PB32C';
NODE_NAME     R4174 1
 '@S9S_MB_2U_LIB.S9S_MB_2U(SCH_1):PAGE312_I134@PURE_QUANTA.Q_RES(CHIPS)':
 'A': CDS_PINID='A';
NODE_NAME     R4175 1
 '@S9S_MB_2U_LIB.S9S_MB_2U(SCH_1):PAGE312_I135@PURE_QUANTA.Q_RES(CHIPS)':
 'A': CDS_PINID='A';
NET_NAME
'RST_PCIE_PCH_E1S_PERST_N'
 '@S9S_MB_2U_LIB.S9S_MB_2U(SCH_1):RST_PCIE_PCH_E1S_PERST_N':
 C_SIGNAL='@s9s_mb_2u_lib.s9s_mb_2u(sch_1):rst_pcie_pch_e1s_perst_n';
NODE_NAME     R3779 2
 '@S9S_MB_2U_LIB.S9S_MB_2U(SCH_1):PAGE297_I309@PURE_QUANTA.Q_RES(CHIPS)':
 'B': CDS_PINID='B';
NODE_NAME     J90 B10
 '@S9S_MB_2U_LIB.S9S_MB_2U(SCH_1):PAGE297_I318@PURE_QUANTA.SCONN56_123276793(CHIPS)':
 'PERST0#': CDS_PINID='\perst0#\';
NET_NAME
'RST_PERST0_OCP_SFF_N'
 '@S9S_MB_2U_LIB.S9S_MB_2U(SCH_1):RST_PERST0_OCP_SFF_N':
 C_SIGNAL='@s9s_mb_2u_lib.s9s_mb_2u(sch_1):rst_perst0_ocp_sff_n';
NODE_NAME     R419 2
 '@S9S_MB_2U_LIB.S9S_MB_2U(SCH_1):PAGE152_I6@PURE_QUANTA.Q_RES(CHIPS)':
 'B': CDS_PINID='B';
NODE_NAME     J37 B10
 '@S9S_MB_2U_LIB.S9S_MB_2U(SCH_1):PAGE150_I199@PURE_QUANTA.SCONN168_ME1016810202011(CHIPS)':
 'PERST0#': CDS_PINID='\perst0#\';
NET_NAME
'RST_PERST0_OCP_V3_2_N'
 '@S9S_MB_2U_LIB.S9S_MB_2U(SCH_1):RST_PERST0_OCP_V3_2_N':
 C_SIGNAL='@s9s_mb_2u_lib.s9s_mb_2u(sch_1):rst_perst0_ocp_v3_2_n';
NODE_NAME     R3186 2
 '@S9S_MB_2U_LIB.S9S_MB_2U(SCH_1):PAGE156_I41@PURE_QUANTA.Q_RES(CHIPS)':
 'B': CDS_PINID='B';
NODE_NAME     J35 B10
 '@S9S_MB_2U_LIB.S9S_MB_2U(SCH_1):PAGE146_I303@PURE_QUANTA.SCONN168_ME1016810202011(CHIPS)':
 'PERST0#': CDS_PINID='\perst0#\';
NET_NAME
'RST_PERST1_OCP_SFF_N'
 '@S9S_MB_2U_LIB.S9S_MB_2U(SCH_1):RST_PERST1_OCP_SFF_N':
 C_SIGNAL='@s9s_mb_2u_lib.s9s_mb_2u(sch_1):rst_perst1_ocp_sff_n';
NODE_NAME     R435 2
 '@S9S_MB_2U_LIB.S9S_MB_2U(SCH_1):PAGE152_I8@PURE_QUANTA.Q_RES(CHIPS)':
 'B': CDS_PINID='B';
NODE_NAME     J37 A11
 '@S9S_MB_2U_LIB.S9S_MB_2U(SCH_1):PAGE150_I199@PURE_QUANTA.SCONN168_ME1016810202011(CHIPS)':
 'PERST1#': CDS_PINID='\perst1#\';
NET_NAME
'RST_PERST1_OCP_V3_2_N'
 '@S9S_MB_2U_LIB.S9S_MB_2U(SCH_1):RST_PERST1_OCP_V3_2_N':
 C_SIGNAL='@s9s_mb_2u_lib.s9s_mb_2u(sch_1):rst_perst1_ocp_v3_2_n';
NODE_NAME     R3187 2
 '@S9S_MB_2U_LIB.S9S_MB_2U(SCH_1):PAGE156_I40@PURE_QUANTA.Q_RES(CHIPS)':
 'B': CDS_PINID='B';
NODE_NAME     J35 A11
 '@S9S_MB_2U_LIB.S9S_MB_2U(SCH_1):PAGE146_I303@PURE_QUANTA.SCONN168_ME1016810202011(CHIPS)':
 'PERST1#': CDS_PINID='\perst1#\';
NET_NAME
'RST_PERST2_OCP_SFF_N'
 '@S9S_MB_2U_LIB.S9S_MB_2U(SCH_1):RST_PERST2_OCP_SFF_N':
 C_SIGNAL='@s9s_mb_2u_lib.s9s_mb_2u(sch_1):rst_perst2_ocp_sff_n';
NODE_NAME     R1504 2
 '@S9S_MB_2U_LIB.S9S_MB_2U(SCH_1):PAGE152_I10@PURE_QUANTA.Q_RES(CHIPS)':
 'B': CDS_PINID='B';
NODE_NAME     J37 OA1
 '@S9S_MB_2U_LIB.S9S_MB_2U(SCH_1):PAGE150_I199@PURE_QUANTA.SCONN168_ME1016810202011(CHIPS)':
 'PERST2#': CDS_PINID='\perst2#\';
NET_NAME
'RST_PERST2_OCP_V3_2_N'
 '@S9S_MB_2U_LIB.S9S_MB_2U(SCH_1):RST_PERST2_OCP_V3_2_N':
 C_SIGNAL='@s9s_mb_2u_lib.s9s_mb_2u(sch_1):rst_perst2_ocp_v3_2_n';
NODE_NAME     R3188 2
 '@S9S_MB_2U_LIB.S9S_MB_2U(SCH_1):PAGE156_I39@PURE_QUANTA.Q_RES(CHIPS)':
 'B': CDS_PINID='B';
NODE_NAME     J35 OA1
 '@S9S_MB_2U_LIB.S9S_MB_2U(SCH_1):PAGE146_I303@PURE_QUANTA.SCONN168_ME1016810202011(CHIPS)':
 'PERST2#': CDS_PINID='\perst2#\';
NET_NAME
'RST_PERST3_OCP_SFF_N'
 '@S9S_MB_2U_LIB.S9S_MB_2U(SCH_1):RST_PERST3_OCP_SFF_N':
 C_SIGNAL='@s9s_mb_2u_lib.s9s_mb_2u(sch_1):rst_perst3_ocp_sff_n';
NODE_NAME     R1505 2
 '@S9S_MB_2U_LIB.S9S_MB_2U(SCH_1):PAGE152_I13@PURE_QUANTA.Q_RES(CHIPS)':
 'B': CDS_PINID='B';
NODE_NAME     J37 OA2
 '@S9S_MB_2U_LIB.S9S_MB_2U(SCH_1):PAGE150_I199@PURE_QUANTA.SCONN168_ME1016810202011(CHIPS)':
 'PERST3#': CDS_PINID='\perst3#\';
NET_NAME
'RST_PERST3_OCP_V3_2_N'
 '@S9S_MB_2U_LIB.S9S_MB_2U(SCH_1):RST_PERST3_OCP_V3_2_N':
 C_SIGNAL='@s9s_mb_2u_lib.s9s_mb_2u(sch_1):rst_perst3_ocp_v3_2_n';
NODE_NAME     R3189 2
 '@S9S_MB_2U_LIB.S9S_MB_2U(SCH_1):PAGE156_I38@PURE_QUANTA.Q_RES(CHIPS)':
 'B': CDS_PINID='B';
NODE_NAME     J35 OA2
 '@S9S_MB_2U_LIB.S9S_MB_2U(SCH_1):PAGE146_I303@PURE_QUANTA.SCONN168_ME1016810202011(CHIPS)':
 'PERST3#': CDS_PINID='\perst3#\';
NET_NAME
'RST_PERST_0_SWB_BUF_N'
 '@S9S_MB_2U_LIB.S9S_MB_2U(SCH_1):RST_PERST_0_SWB_BUF_N':
 C_SIGNAL='@s9s_mb_2u_lib.s9s_mb_2u(sch_1):rst_perst_0_swb_buf_n';
NODE_NAME     J112 T8
 '@S9S_MB_2U_LIB.S9S_MB_2U(SCH_1):PAGE149_I75@PURE_QUANTA.CONN160_10131762101LF(CHIPS)':
 'T8': CDS_PINID='T8';
NODE_NAME     R3469 2
 '@S9S_MB_2U_LIB.S9S_MB_2U(SCH_1):PAGE160_I199@PURE_QUANTA.Q_RES(CHIPS)':
 'B': CDS_PINID='B';
NET_NAME
'RST_PERST_0_SWB_BUF_R_N'
 '@S9S_MB_2U_LIB.S9S_MB_2U(SCH_1):RST_PERST_0_SWB_BUF_R_N':
 C_SIGNAL='@s9s_mb_2u_lib.s9s_mb_2u(sch_1):rst_perst_0_swb_buf_r_n';
NODE_NAME     U252 6
 '@S9S_MB_2U_LIB.S9S_MB_2U(SCH_1):PAGE160_I153@PURE_QUANTA.74LVC2G17GW(CHIPS)':
 'B0': CDS_PINID='B0';
NODE_NAME     R3467 1
 '@S9S_MB_2U_LIB.S9S_MB_2U(SCH_1):PAGE160_I181@PURE_QUANTA.Q_RES(CHIPS)':
 'A': CDS_PINID='A';
NODE_NAME     R3469 1
 '@S9S_MB_2U_LIB.S9S_MB_2U(SCH_1):PAGE160_I199@PURE_QUANTA.Q_RES(CHIPS)':
 'A': CDS_PINID='A';
NET_NAME
'RST_PERST_1_SWB_BUF_N'
 '@S9S_MB_2U_LIB.S9S_MB_2U(SCH_1):RST_PERST_1_SWB_BUF_N':
 C_SIGNAL='@s9s_mb_2u_lib.s9s_mb_2u(sch_1):rst_perst_1_swb_buf_n';
NODE_NAME     J112 A5
 '@S9S_MB_2U_LIB.S9S_MB_2U(SCH_1):PAGE149_I75@PURE_QUANTA.CONN160_10131762101LF(CHIPS)':
 'A5': CDS_PINID='A5';
NODE_NAME     R3391 2
 '@S9S_MB_2U_LIB.S9S_MB_2U(SCH_1):PAGE160_I200@PURE_QUANTA.Q_RES(CHIPS)':
 'B': CDS_PINID='B';
NET_NAME
'RST_PERST_1_SWB_BUF_R_N'
 '@S9S_MB_2U_LIB.S9S_MB_2U(SCH_1):RST_PERST_1_SWB_BUF_R_N':
 C_SIGNAL='@s9s_mb_2u_lib.s9s_mb_2u(sch_1):rst_perst_1_swb_buf_r_n';
NODE_NAME     R3455 1
 '@S9S_MB_2U_LIB.S9S_MB_2U(SCH_1):PAGE160_I139@PURE_QUANTA.Q_RES(CHIPS)':
 'A': CDS_PINID='A';
NODE_NAME     U252 4
 '@S9S_MB_2U_LIB.S9S_MB_2U(SCH_1):PAGE160_I153@PURE_QUANTA.74LVC2G17GW(CHIPS)':
 'B1': CDS_PINID='B1';
NODE_NAME     R3391 1
 '@S9S_MB_2U_LIB.S9S_MB_2U(SCH_1):PAGE160_I200@PURE_QUANTA.Q_RES(CHIPS)':
 'A': CDS_PINID='A';
NET_NAME
'RST_PERST_2_SWB_BUF_N'
 '@S9S_MB_2U_LIB.S9S_MB_2U(SCH_1):RST_PERST_2_SWB_BUF_N':
 C_SIGNAL='@s9s_mb_2u_lib.s9s_mb_2u(sch_1):rst_perst_2_swb_buf_n';
NODE_NAME     J112 A1
 '@S9S_MB_2U_LIB.S9S_MB_2U(SCH_1):PAGE149_I76@PURE_QUANTA.CONN160_10131762101LF(CHIPS)':
 'A1': CDS_PINID='A1';
NODE_NAME     R3468 2
 '@S9S_MB_2U_LIB.S9S_MB_2U(SCH_1):PAGE160_I197@PURE_QUANTA.Q_RES(CHIPS)':
 'B': CDS_PINID='B';
NET_NAME
'RST_PERST_2_SWB_BUF_R_N'
 '@S9S_MB_2U_LIB.S9S_MB_2U(SCH_1):RST_PERST_2_SWB_BUF_R_N':
 C_SIGNAL='@s9s_mb_2u_lib.s9s_mb_2u(sch_1):rst_perst_2_swb_buf_r_n';
NODE_NAME     U256 6
 '@S9S_MB_2U_LIB.S9S_MB_2U(SCH_1):PAGE160_I173@PURE_QUANTA.74LVC2G17GW(CHIPS)':
 'B0': CDS_PINID='B0';
NODE_NAME     R3466 1
 '@S9S_MB_2U_LIB.S9S_MB_2U(SCH_1):PAGE160_I184@PURE_QUANTA.Q_RES(CHIPS)':
 'A': CDS_PINID='A';
NODE_NAME     R3468 1
 '@S9S_MB_2U_LIB.S9S_MB_2U(SCH_1):PAGE160_I197@PURE_QUANTA.Q_RES(CHIPS)':
 'A': CDS_PINID='A';
NET_NAME
'RST_PERST_SWB_N'
 '@S9S_MB_2U_LIB.S9S_MB_2U(SCH_1):RST_PERST_SWB_N':
 C_SIGNAL='@s9s_mb_2u_lib.s9s_mb_2u(sch_1):rst_perst_swb_n';
NODE_NAME     R2738 1
 '@S9S_MB_2U_LIB.S9S_MB_2U(SCH_1):PAGE212_I127@PURE_QUANTA.Q_RES(CHIPS)':
 'A': CDS_PINID='A';
NODE_NAME     U249 W19
 '@S9S_MB_2U_LIB.S9S_MB_2U(SCH_1):PAGE313_I1@PURE_QUANTA.LCMXO3LF9400C5BG484C(CHIPS)':
 'PR30C': CDS_PINID='PR30C';
NODE_NAME     R4622 1
 '@S9S_MB_2U_LIB.S9S_MB_2U(SCH_1):PAGE208_I66@PURE_QUANTA.Q_RES(CHIPS)':
 'A': CDS_PINID='A';
NET_NAME
'RST_PERST_SWB_R_N'
 '@S9S_MB_2U_LIB.S9S_MB_2U(SCH_1):RST_PERST_SWB_R_N':
 C_SIGNAL='@s9s_mb_2u_lib.s9s_mb_2u(sch_1):rst_perst_swb_r_n';
NODE_NAME     R2738 2
 '@S9S_MB_2U_LIB.S9S_MB_2U(SCH_1):PAGE212_I127@PURE_QUANTA.Q_RES(CHIPS)':
 'B': CDS_PINID='B';
NODE_NAME     U252 1
 '@S9S_MB_2U_LIB.S9S_MB_2U(SCH_1):PAGE160_I153@PURE_QUANTA.74LVC2G17GW(CHIPS)':
 'A0': CDS_PINID='A0';
NODE_NAME     U252 3
 '@S9S_MB_2U_LIB.S9S_MB_2U(SCH_1):PAGE160_I153@PURE_QUANTA.74LVC2G17GW(CHIPS)':
 'A1': CDS_PINID='A1';
NODE_NAME     U256 1
 '@S9S_MB_2U_LIB.S9S_MB_2U(SCH_1):PAGE160_I173@PURE_QUANTA.74LVC2G17GW(CHIPS)':
 'A0': CDS_PINID='A0';
NET_NAME
'RST_PFR_OVR_RTC'
 '@S9S_MB_2U_LIB.S9S_MB_2U(SCH_1):RST_PFR_OVR_RTC':
 C_SIGNAL='@s9s_mb_2u_lib.s9s_mb_2u(sch_1):rst_pfr_ovr_rtc';
NODE_NAME     R1839 1
 '@S9S_MB_2U_LIB.S9S_MB_2U(SCH_1):PAGE177_I85@PURE_QUANTA.Q_RES(CHIPS)':
 'A': CDS_PINID='A';
NODE_NAME     R1843 2
 '@S9S_MB_2U_LIB.S9S_MB_2U(SCH_1):PAGE211_I122@PURE_QUANTA.Q_RES(CHIPS)':
 'B': CDS_PINID='B';
NODE_NAME     Q34 G
 '@S9S_MB_2U_LIB.S9S_MB_2U(SCH_1):PAGE177_I123@PURE_QUANTA.MOSFET_NCH_GDS_ESD_PROTECTED(CHIPS)':
 'G': CDS_PINID='G';
NODE_NAME     R4712 1
 '@S9S_MB_2U_LIB.S9S_MB_2U(SCH_1):PAGE177_I125@PURE_QUANTA.Q_RES(CHIPS)':
 'A': CDS_PINID='A';
NET_NAME
'RST_PFR_OVR_RTC_R'
 '@S9S_MB_2U_LIB.S9S_MB_2U(SCH_1):RST_PFR_OVR_RTC_R':
 C_SIGNAL='@s9s_mb_2u_lib.s9s_mb_2u(sch_1):rst_pfr_ovr_rtc_r';
NODE_NAME     R1843 1
 '@S9S_MB_2U_LIB.S9S_MB_2U(SCH_1):PAGE211_I122@PURE_QUANTA.Q_RES(CHIPS)':
 'A': CDS_PINID='A';
NODE_NAME     U249 W6
 '@S9S_MB_2U_LIB.S9S_MB_2U(SCH_1):PAGE312_I1@PURE_QUANTA.LCMXO3LF9400C5BG484C(CHIPS)':
 'PB11C': CDS_PINID='PB11C';
NET_NAME
'RST_PFR_OVR_SRTC'
 '@S9S_MB_2U_LIB.S9S_MB_2U(SCH_1):RST_PFR_OVR_SRTC':
 C_SIGNAL='@s9s_mb_2u_lib.s9s_mb_2u(sch_1):rst_pfr_ovr_srtc';
NODE_NAME     R1840 1
 '@S9S_MB_2U_LIB.S9S_MB_2U(SCH_1):PAGE177_I89@PURE_QUANTA.Q_RES(CHIPS)':
 'A': CDS_PINID='A';
NODE_NAME     R1844 2
 '@S9S_MB_2U_LIB.S9S_MB_2U(SCH_1):PAGE211_I123@PURE_QUANTA.Q_RES(CHIPS)':
 'B': CDS_PINID='B';
NODE_NAME     Q35 G
 '@S9S_MB_2U_LIB.S9S_MB_2U(SCH_1):PAGE177_I124@PURE_QUANTA.MOSFET_NCH_GDS_ESD_PROTECTED(CHIPS)':
 'G': CDS_PINID='G';
NODE_NAME     R4713 1
 '@S9S_MB_2U_LIB.S9S_MB_2U(SCH_1):PAGE177_I127@PURE_QUANTA.Q_RES(CHIPS)':
 'A': CDS_PINID='A';
NET_NAME
'RST_PFR_OVR_SRTC_R'
 '@S9S_MB_2U_LIB.S9S_MB_2U(SCH_1):RST_PFR_OVR_SRTC_R':
 C_SIGNAL='@s9s_mb_2u_lib.s9s_mb_2u(sch_1):rst_pfr_ovr_srtc_r';
NODE_NAME     R1844 1
 '@S9S_MB_2U_LIB.S9S_MB_2U(SCH_1):PAGE211_I123@PURE_QUANTA.Q_RES(CHIPS)':
 'A': CDS_PINID='A';
NODE_NAME     U249 V7
 '@S9S_MB_2U_LIB.S9S_MB_2U(SCH_1):PAGE312_I1@PURE_QUANTA.LCMXO3LF9400C5BG484C(CHIPS)':
 'PB11D': CDS_PINID='PB11D';
NET_NAME
'RST_PLD_CPU0_DRAM_AB_N'
 '@S9S_MB_2U_LIB.S9S_MB_2U(SCH_1):RST_PLD_CPU0_DRAM_AB_N':
 C_SIGNAL='@s9s_mb_2u_lib.s9s_mb_2u(sch_1):rst_pld_cpu0_dram_ab_n';
NODE_NAME     R836 1
 '@S9S_MB_2U_LIB.S9S_MB_2U(SCH_1):PAGE129_I26@PURE_QUANTA.Q_RES(CHIPS)':
 'A': CDS_PINID='A';
NODE_NAME     C622 1
 '@S9S_MB_2U_LIB.S9S_MB_2U(SCH_1):PAGE129_I91@PURE_QUANTA.Q_CAP(CHIPS)':
 'A': CDS_PINID='A';
NODE_NAME     R706 1
 '@S9S_MB_2U_LIB.S9S_MB_2U(SCH_1):PAGE129_I103@PURE_QUANTA.Q_RES(CHIPS)':
 'A': CDS_PINID='A';
NODE_NAME     Q98 2
 '@S9S_MB_2U_LIB.S9S_MB_2U(SCH_1):PAGE304_I68@PURE_QUANTA.MOSFET_NCH_DUAL(CHIPS)':
 'G1': CDS_PINID='G1';
NODE_NAME     U249 C1
 '@S9S_MB_2U_LIB.S9S_MB_2U(SCH_1):PAGE311_I33@PURE_QUANTA.LCMXO3LF9400C5BG484C(CHIPS)':
 'PL4A||L_GPLLT_IN': CDS_PINID='\pl4a||l_gpllt_in\';
NET_NAME
'RST_PLD_CPU0_DRAM_CD_N'
 '@S9S_MB_2U_LIB.S9S_MB_2U(SCH_1):RST_PLD_CPU0_DRAM_CD_N':
 C_SIGNAL='@s9s_mb_2u_lib.s9s_mb_2u(sch_1):rst_pld_cpu0_dram_cd_n';
NODE_NAME     R837 1
 '@S9S_MB_2U_LIB.S9S_MB_2U(SCH_1):PAGE129_I59@PURE_QUANTA.Q_RES(CHIPS)':
 'A': CDS_PINID='A';
NODE_NAME     C623 1
 '@S9S_MB_2U_LIB.S9S_MB_2U(SCH_1):PAGE129_I94@PURE_QUANTA.Q_CAP(CHIPS)':
 'A': CDS_PINID='A';
NODE_NAME     R707 1
 '@S9S_MB_2U_LIB.S9S_MB_2U(SCH_1):PAGE129_I106@PURE_QUANTA.Q_RES(CHIPS)':
 'A': CDS_PINID='A';
NODE_NAME     Q98 5
 '@S9S_MB_2U_LIB.S9S_MB_2U(SCH_1):PAGE304_I69@PURE_QUANTA.MOSFET_NCH_DUAL(CHIPS)':
 'G2': CDS_PINID='G2';
NODE_NAME     U249 D2
 '@S9S_MB_2U_LIB.S9S_MB_2U(SCH_1):PAGE311_I33@PURE_QUANTA.LCMXO3LF9400C5BG484C(CHIPS)':
 'PL4B||L_GPLLC_IN': CDS_PINID='\pl4b||l_gpllc_in\';
NET_NAME
'RST_PLD_CPU0_DRAM_EF_N'
 '@S9S_MB_2U_LIB.S9S_MB_2U(SCH_1):RST_PLD_CPU0_DRAM_EF_N':
 C_SIGNAL='@s9s_mb_2u_lib.s9s_mb_2u(sch_1):rst_pld_cpu0_dram_ef_n';
NODE_NAME     R838 1
 '@S9S_MB_2U_LIB.S9S_MB_2U(SCH_1):PAGE129_I76@PURE_QUANTA.Q_RES(CHIPS)':
 'A': CDS_PINID='A';
NODE_NAME     C624 1
 '@S9S_MB_2U_LIB.S9S_MB_2U(SCH_1):PAGE129_I99@PURE_QUANTA.Q_CAP(CHIPS)':
 'A': CDS_PINID='A';
NODE_NAME     R708 1
 '@S9S_MB_2U_LIB.S9S_MB_2U(SCH_1):PAGE129_I109@PURE_QUANTA.Q_RES(CHIPS)':
 'A': CDS_PINID='A';
NODE_NAME     Q97 2
 '@S9S_MB_2U_LIB.S9S_MB_2U(SCH_1):PAGE304_I71@PURE_QUANTA.MOSFET_NCH_DUAL(CHIPS)':
 'G1': CDS_PINID='G1';
NODE_NAME     U249 G5
 '@S9S_MB_2U_LIB.S9S_MB_2U(SCH_1):PAGE311_I33@PURE_QUANTA.LCMXO3LF9400C5BG484C(CHIPS)':
 'PL4C': CDS_PINID='PL4C';
NET_NAME
'RST_PLD_CPU0_DRAM_GH_N'
 '@S9S_MB_2U_LIB.S9S_MB_2U(SCH_1):RST_PLD_CPU0_DRAM_GH_N':
 C_SIGNAL='@s9s_mb_2u_lib.s9s_mb_2u(sch_1):rst_pld_cpu0_dram_gh_n';
NODE_NAME     R835 1
 '@S9S_MB_2U_LIB.S9S_MB_2U(SCH_1):PAGE129_I86@PURE_QUANTA.Q_RES(CHIPS)':
 'A': CDS_PINID='A';
NODE_NAME     C621 1
 '@S9S_MB_2U_LIB.S9S_MB_2U(SCH_1):PAGE129_I102@PURE_QUANTA.Q_CAP(CHIPS)':
 'A': CDS_PINID='A';
NODE_NAME     R705 1
 '@S9S_MB_2U_LIB.S9S_MB_2U(SCH_1):PAGE129_I112@PURE_QUANTA.Q_RES(CHIPS)':
 'A': CDS_PINID='A';
NODE_NAME     Q97 5
 '@S9S_MB_2U_LIB.S9S_MB_2U(SCH_1):PAGE304_I70@PURE_QUANTA.MOSFET_NCH_DUAL(CHIPS)':
 'G2': CDS_PINID='G2';
NODE_NAME     U249 H6
 '@S9S_MB_2U_LIB.S9S_MB_2U(SCH_1):PAGE311_I33@PURE_QUANTA.LCMXO3LF9400C5BG484C(CHIPS)':
 'PL4D': CDS_PINID='PL4D';
NET_NAME
'RST_PLD_CPU1_DRAM_AB_N'
 '@S9S_MB_2U_LIB.S9S_MB_2U(SCH_1):RST_PLD_CPU1_DRAM_AB_N':
 C_SIGNAL='@s9s_mb_2u_lib.s9s_mb_2u(sch_1):rst_pld_cpu1_dram_ab_n';
NODE_NAME     R816 1
 '@S9S_MB_2U_LIB.S9S_MB_2U(SCH_1):PAGE130_I37@PURE_QUANTA.Q_RES(CHIPS)':
 'A': CDS_PINID='A';
NODE_NAME     C614 1
 '@S9S_MB_2U_LIB.S9S_MB_2U(SCH_1):PAGE130_I65@PURE_QUANTA.Q_CAP(CHIPS)':
 'A': CDS_PINID='A';
NODE_NAME     R703 1
 '@S9S_MB_2U_LIB.S9S_MB_2U(SCH_1):PAGE130_I79@PURE_QUANTA.Q_RES(CHIPS)':
 'A': CDS_PINID='A';
NODE_NAME     U249 D1
 '@S9S_MB_2U_LIB.S9S_MB_2U(SCH_1):PAGE311_I33@PURE_QUANTA.LCMXO3LF9400C5BG484C(CHIPS)':
 'PL5A': CDS_PINID='PL5A';
NODE_NAME     Q105 2
 '@S9S_MB_2U_LIB.S9S_MB_2U(SCH_1):PAGE304_I76@PURE_QUANTA.MOSFET_NCH_DUAL(CHIPS)':
 'G1': CDS_PINID='G1';
NET_NAME
'RST_PLD_CPU1_DRAM_CD_N'
 '@S9S_MB_2U_LIB.S9S_MB_2U(SCH_1):RST_PLD_CPU1_DRAM_CD_N':
 C_SIGNAL='@s9s_mb_2u_lib.s9s_mb_2u(sch_1):rst_pld_cpu1_dram_cd_n';
NODE_NAME     R817 1
 '@S9S_MB_2U_LIB.S9S_MB_2U(SCH_1):PAGE130_I26@PURE_QUANTA.Q_RES(CHIPS)':
 'A': CDS_PINID='A';
NODE_NAME     C615 1
 '@S9S_MB_2U_LIB.S9S_MB_2U(SCH_1):PAGE130_I62@PURE_QUANTA.Q_CAP(CHIPS)':
 'A': CDS_PINID='A';
NODE_NAME     R701 1
 '@S9S_MB_2U_LIB.S9S_MB_2U(SCH_1):PAGE130_I63@PURE_QUANTA.Q_RES(CHIPS)':
 'A': CDS_PINID='A';
NODE_NAME     Q99 2
 '@S9S_MB_2U_LIB.S9S_MB_2U(SCH_1):PAGE304_I72@PURE_QUANTA.MOSFET_NCH_DUAL(CHIPS)':
 'G1': CDS_PINID='G1';
NODE_NAME     U249 E2
 '@S9S_MB_2U_LIB.S9S_MB_2U(SCH_1):PAGE311_I33@PURE_QUANTA.LCMXO3LF9400C5BG484C(CHIPS)':
 'PL5B': CDS_PINID='PL5B';
NET_NAME
'RST_PLD_CPU1_DRAM_EF_N'
 '@S9S_MB_2U_LIB.S9S_MB_2U(SCH_1):RST_PLD_CPU1_DRAM_EF_N':
 C_SIGNAL='@s9s_mb_2u_lib.s9s_mb_2u(sch_1):rst_pld_cpu1_dram_ef_n';
NODE_NAME     R818 1
 '@S9S_MB_2U_LIB.S9S_MB_2U(SCH_1):PAGE130_I22@PURE_QUANTA.Q_RES(CHIPS)':
 'A': CDS_PINID='A';
NODE_NAME     C616 1
 '@S9S_MB_2U_LIB.S9S_MB_2U(SCH_1):PAGE130_I59@PURE_QUANTA.Q_CAP(CHIPS)':
 'A': CDS_PINID='A';
NODE_NAME     R704 1
 '@S9S_MB_2U_LIB.S9S_MB_2U(SCH_1):PAGE130_I75@PURE_QUANTA.Q_RES(CHIPS)':
 'A': CDS_PINID='A';
NODE_NAME     Q100 2
 '@S9S_MB_2U_LIB.S9S_MB_2U(SCH_1):PAGE304_I74@PURE_QUANTA.MOSFET_NCH_DUAL(CHIPS)':
 'G1': CDS_PINID='G1';
NODE_NAME     U249 E3
 '@S9S_MB_2U_LIB.S9S_MB_2U(SCH_1):PAGE311_I33@PURE_QUANTA.LCMXO3LF9400C5BG484C(CHIPS)':
 'PL5C': CDS_PINID='PL5C';
NET_NAME
'RST_PLD_CPU1_DRAM_GH_N'
 '@S9S_MB_2U_LIB.S9S_MB_2U(SCH_1):RST_PLD_CPU1_DRAM_GH_N':
 C_SIGNAL='@s9s_mb_2u_lib.s9s_mb_2u(sch_1):rst_pld_cpu1_dram_gh_n';
NODE_NAME     R815 1
 '@S9S_MB_2U_LIB.S9S_MB_2U(SCH_1):PAGE130_I11@PURE_QUANTA.Q_RES(CHIPS)':
 'A': CDS_PINID='A';
NODE_NAME     C613 1
 '@S9S_MB_2U_LIB.S9S_MB_2U(SCH_1):PAGE130_I68@PURE_QUANTA.Q_CAP(CHIPS)':
 'A': CDS_PINID='A';
NODE_NAME     R702 1
 '@S9S_MB_2U_LIB.S9S_MB_2U(SCH_1):PAGE130_I76@PURE_QUANTA.Q_RES(CHIPS)':
 'A': CDS_PINID='A';
NODE_NAME     Q100 5
 '@S9S_MB_2U_LIB.S9S_MB_2U(SCH_1):PAGE304_I75@PURE_QUANTA.MOSFET_NCH_DUAL(CHIPS)':
 'G2': CDS_PINID='G2';
NODE_NAME     U249 F4
 '@S9S_MB_2U_LIB.S9S_MB_2U(SCH_1):PAGE311_I33@PURE_QUANTA.LCMXO3LF9400C5BG484C(CHIPS)':
 'PL5D': CDS_PINID='PL5D';
NET_NAME
'RST_PLTRST_B_MUX_N'
 '@S9S_MB_2U_LIB.S9S_MB_2U(SCH_1):RST_PLTRST_B_MUX_N':
 C_SIGNAL='@s9s_mb_2u_lib.s9s_mb_2u(sch_1):rst_pltrst_b_mux_n';
NODE_NAME     U61 3
 '@S9S_MB_2U_LIB.S9S_MB_2U(SCH_1):PAGE190_I39@PURE_QUANTA.NC7SB3157(CHIPS)':
 'B0': CDS_PINID='B0';
NODE_NAME     R1470 2
 '@S9S_MB_2U_LIB.S9S_MB_2U(SCH_1):PAGE212_I56@PURE_QUANTA.Q_RES(CHIPS)':
 'B': CDS_PINID='B';
NET_NAME
'RST_PLTRST_B_N'
 '@S9S_MB_2U_LIB.S9S_MB_2U(SCH_1):RST_PLTRST_B_N':
 C_SIGNAL='@s9s_mb_2u_lib.s9s_mb_2u(sch_1):rst_pltrst_b_n';
NODE_NAME     R1469 2
 '@S9S_MB_2U_LIB.S9S_MB_2U(SCH_1):PAGE212_I55@PURE_QUANTA.Q_RES(CHIPS)':
 'B': CDS_PINID='B';
NODE_NAME     J41 A51
 '@S9S_MB_2U_LIB.S9S_MB_2U(SCH_1):PAGE227_I173@PURE_QUANTA.SCONN168_ME1016810202011(CHIPS)':
 'PERP10': CDS_PINID='PERP10';
NET_NAME
'RST_PLTRST_N'
 '@S9S_MB_2U_LIB.S9S_MB_2U(SCH_1):RST_PLTRST_N':
 C_SIGNAL='@s9s_mb_2u_lib.s9s_mb_2u(sch_1):rst_pltrst_n';
NODE_NAME     U4 AB4
 '@S9S_MB_2U_LIB.S9S_MB_2U(SCH_1):PAGE175_I93@PURE_QUANTA.EMMITSBURG_REV0P9(CHIPS)':
 'GPP_D_11_PLTRST_N': CDS_PINID='GPP_D_11_PLTRST_N';
NODE_NAME     R1205 1
 '@S9S_MB_2U_LIB.S9S_MB_2U(SCH_1):PAGE212_I7@PURE_QUANTA.Q_RES(CHIPS)':
 'A': CDS_PINID='A';
NODE_NAME     R1541 2
 '@S9S_MB_2U_LIB.S9S_MB_2U(SCH_1):PAGE212_I92@PURE_QUANTA.Q_RES(CHIPS)':
 'B': CDS_PINID='B';
NODE_NAME     Q88 5
 '@S9S_MB_2U_LIB.S9S_MB_2U(SCH_1):PAGE241_I42@PURE_QUANTA.MOSFET_NCH_DUAL(CHIPS)':
 'G2': CDS_PINID='G2';
NET_NAME
'RST_PLTRST_PLD_B_N'
 '@S9S_MB_2U_LIB.S9S_MB_2U(SCH_1):RST_PLTRST_PLD_B_N':
 C_SIGNAL='@s9s_mb_2u_lib.s9s_mb_2u(sch_1):rst_pltrst_pld_b_n';
NODE_NAME     R1420 1
 '@S9S_MB_2U_LIB.S9S_MB_2U(SCH_1):PAGE208_I9@PURE_QUANTA.Q_RES(CHIPS)':
 'A': CDS_PINID='A';
NODE_NAME     R1469 1
 '@S9S_MB_2U_LIB.S9S_MB_2U(SCH_1):PAGE212_I55@PURE_QUANTA.Q_RES(CHIPS)':
 'A': CDS_PINID='A';
NODE_NAME     R1470 1
 '@S9S_MB_2U_LIB.S9S_MB_2U(SCH_1):PAGE212_I56@PURE_QUANTA.Q_RES(CHIPS)':
 'A': CDS_PINID='A';
NODE_NAME     U249 AB14
 '@S9S_MB_2U_LIB.S9S_MB_2U(SCH_1):PAGE312_I1@PURE_QUANTA.LCMXO3LF9400C5BG484C(CHIPS)':
 'PB33A': CDS_PINID='PB33A';
NET_NAME
'RST_PLTRST_PLD_N'
 '@S9S_MB_2U_LIB.S9S_MB_2U(SCH_1):RST_PLTRST_PLD_N':
 C_SIGNAL='@s9s_mb_2u_lib.s9s_mb_2u(sch_1):rst_pltrst_pld_n';
NODE_NAME     R1205 2
 '@S9S_MB_2U_LIB.S9S_MB_2U(SCH_1):PAGE212_I7@PURE_QUANTA.Q_RES(CHIPS)':
 'B': CDS_PINID='B';
NODE_NAME     U249 Y17
 '@S9S_MB_2U_LIB.S9S_MB_2U(SCH_1):PAGE312_I1@PURE_QUANTA.LCMXO3LF9400C5BG484C(CHIPS)':
 'PB40C': CDS_PINID='PB40C';
NET_NAME
'RST_RSMRST_NM_HDR_N'
 '@S9S_MB_2U_LIB.S9S_MB_2U(SCH_1):RST_RSMRST_NM_HDR_N':
 C_SIGNAL='@s9s_mb_2u_lib.s9s_mb_2u(sch_1):rst_rsmrst_nm_hdr_n';
NODE_NAME     R3050 2
 '@S9S_MB_2U_LIB.S9S_MB_2U(SCH_1):PAGE212_I129@PURE_QUANTA.Q_RES(CHIPS)':
 'B': CDS_PINID='B';
NODE_NAME     J100 9
 '@S9S_MB_2U_LIB.S9S_MB_2U(SCH_1):PAGE215_I32@PURE_QUANTA.SCONN20_513860200CV01(CHIPS)':
 '9': CDS_PINID='\9\';
NET_NAME
'RST_RSMRST_PCH_N'
 '@S9S_MB_2U_LIB.S9S_MB_2U(SCH_1):RST_RSMRST_PCH_N':
 C_SIGNAL='@s9s_mb_2u_lib.s9s_mb_2u(sch_1):rst_rsmrst_pch_n';
NODE_NAME     R772 2
 '@S9S_MB_2U_LIB.S9S_MB_2U(SCH_1):PAGE133_I118@PURE_QUANTA.Q_RES(CHIPS)':
 'B': CDS_PINID='B';
NODE_NAME     U4 BD9
 '@S9S_MB_2U_LIB.S9S_MB_2U(SCH_1):PAGE174_I36@PURE_QUANTA.EMMITSBURG_REV0P9(CHIPS)':
 'RSMRST_N': CDS_PINID='RSMRST_N';
NODE_NAME     R1207 2
 '@S9S_MB_2U_LIB.S9S_MB_2U(SCH_1):PAGE212_I15@PURE_QUANTA.Q_RES(CHIPS)':
 'B': CDS_PINID='B';
NODE_NAME     R1695 2
 '@S9S_MB_2U_LIB.S9S_MB_2U(SCH_1):PAGE232_I36@PURE_QUANTA.Q_RES(CHIPS)':
 'B': CDS_PINID='B';
NET_NAME
'RST_RSMRST_PLD_R_N'
 '@S9S_MB_2U_LIB.S9S_MB_2U(SCH_1):RST_RSMRST_PLD_R_N':
 C_SIGNAL='@s9s_mb_2u_lib.s9s_mb_2u(sch_1):rst_rsmrst_pld_r_n';
NODE_NAME     R1421 1
 '@S9S_MB_2U_LIB.S9S_MB_2U(SCH_1):PAGE208_I10@PURE_QUANTA.Q_RES(CHIPS)':
 'A': CDS_PINID='A';
NODE_NAME     R1207 1
 '@S9S_MB_2U_LIB.S9S_MB_2U(SCH_1):PAGE212_I15@PURE_QUANTA.Q_RES(CHIPS)':
 'A': CDS_PINID='A';
NODE_NAME     R3050 1
 '@S9S_MB_2U_LIB.S9S_MB_2U(SCH_1):PAGE212_I129@PURE_QUANTA.Q_RES(CHIPS)':
 'A': CDS_PINID='A';
NODE_NAME     Q77 2
 '@S9S_MB_2U_LIB.S9S_MB_2U(SCH_1):PAGE242_I6@PURE_QUANTA.MOSFET_NCH_DUAL(CHIPS)':
 'G1': CDS_PINID='G1';
NODE_NAME     U249 V16
 '@S9S_MB_2U_LIB.S9S_MB_2U(SCH_1):PAGE312_I1@PURE_QUANTA.LCMXO3LF9400C5BG484C(CHIPS)':
 'PB40D': CDS_PINID='PB40D';
NET_NAME
'RST_RTCRST_N'
 '@S9S_MB_2U_LIB.S9S_MB_2U(SCH_1):RST_RTCRST_N':
 C_SIGNAL='@s9s_mb_2u_lib.s9s_mb_2u(sch_1):rst_rtcrst_n';
NODE_NAME     U4 BD7
 '@S9S_MB_2U_LIB.S9S_MB_2U(SCH_1):PAGE177_I27@PURE_QUANTA.EMMITSBURG_REV0P9(CHIPS)':
 'RCTRST_N': CDS_PINID='RCTRST_N';
NODE_NAME     R1839 2
 '@S9S_MB_2U_LIB.S9S_MB_2U(SCH_1):PAGE177_I85@PURE_QUANTA.Q_RES(CHIPS)':
 'B': CDS_PINID='B';
NODE_NAME     SW5 3
 '@S9S_MB_2U_LIB.S9S_MB_2U(SCH_1):PAGE189_I122@PURE_QUANTA.SW_PUSHBUTTON4P_24(CHIPS)':
 '3': CDS_PINID='\3\';
NODE_NAME     SW5 4
 '@S9S_MB_2U_LIB.S9S_MB_2U(SCH_1):PAGE189_I122@PURE_QUANTA.SW_PUSHBUTTON4P_24(CHIPS)':
 '4': CDS_PINID='\4\';
NODE_NAME     R1340 2
 '@S9S_MB_2U_LIB.S9S_MB_2U(SCH_1):PAGE189_I127@PURE_QUANTA.Q_RES(CHIPS)':
 'B': CDS_PINID='B';
NODE_NAME     C1177 1
 '@S9S_MB_2U_LIB.S9S_MB_2U(SCH_1):PAGE189_I128@PURE_QUANTA.Q_CAP(CHIPS)':
 'A': CDS_PINID='A';
NODE_NAME     Q34 D
 '@S9S_MB_2U_LIB.S9S_MB_2U(SCH_1):PAGE177_I123@PURE_QUANTA.MOSFET_NCH_GDS_ESD_PROTECTED(CHIPS)':
 'D': CDS_PINID='D';
NET_NAME
'RST_SGPIO_RESET_N'
 '@S9S_MB_2U_LIB.S9S_MB_2U(SCH_1):RST_SGPIO_RESET_N':
 C_SIGNAL='@s9s_mb_2u_lib.s9s_mb_2u(sch_1):rst_sgpio_reset_n';
NODE_NAME     R1811 1
 '@S9S_MB_2U_LIB.S9S_MB_2U(SCH_1):PAGE211_I110@PURE_QUANTA.Q_RES(CHIPS)':
 'A': CDS_PINID='A';
NODE_NAME     J41 B39
 '@S9S_MB_2U_LIB.S9S_MB_2U(SCH_1):PAGE227_I173@PURE_QUANTA.SCONN168_ME1016810202011(CHIPS)':
 'PETN7': CDS_PINID='PETN7';
NET_NAME
'RST_SGPIO_RESET_N_R'
 '@S9S_MB_2U_LIB.S9S_MB_2U(SCH_1):RST_SGPIO_RESET_N_R':
 C_SIGNAL='@s9s_mb_2u_lib.s9s_mb_2u(sch_1):rst_sgpio_reset_n_r';
NODE_NAME     R1811 2
 '@S9S_MB_2U_LIB.S9S_MB_2U(SCH_1):PAGE211_I110@PURE_QUANTA.Q_RES(CHIPS)':
 'B': CDS_PINID='B';
NODE_NAME     U249 T13
 '@S9S_MB_2U_LIB.S9S_MB_2U(SCH_1):PAGE312_I1@PURE_QUANTA.LCMXO3LF9400C5BG484C(CHIPS)':
 'PB32A': CDS_PINID='PB32A';
NET_NAME
'RST_SMB_BUF_E1S_0_N'
 '@S9S_MB_2U_LIB.S9S_MB_2U(SCH_1):RST_SMB_BUF_E1S_0_N':
 C_SIGNAL='@s9s_mb_2u_lib.s9s_mb_2u(sch_1):rst_smb_buf_e1s_0_n';
NODE_NAME     R3772 1
 '@S9S_MB_2U_LIB.S9S_MB_2U(SCH_1):PAGE297_I301@PURE_QUANTA.Q_RES(CHIPS)':
 'A': CDS_PINID='A';
NODE_NAME     U134 6
 '@S9S_MB_2U_LIB.S9S_MB_2U(SCH_1):PAGE297_I305@PURE_QUANTA.74LVC2G07DW7(CHIPS)':
 '1Y': CDS_PINID='\1y\';
NET_NAME
'RST_SMB_E1S_0_N'
 '@S9S_MB_2U_LIB.S9S_MB_2U(SCH_1):RST_SMB_E1S_0_N':
 C_SIGNAL='@s9s_mb_2u_lib.s9s_mb_2u(sch_1):rst_smb_e1s_0_n';
NODE_NAME     R3773 2
 '@S9S_MB_2U_LIB.S9S_MB_2U(SCH_1):PAGE297_I299@PURE_QUANTA.Q_RES(CHIPS)':
 'B': CDS_PINID='B';
NODE_NAME     R3772 2
 '@S9S_MB_2U_LIB.S9S_MB_2U(SCH_1):PAGE297_I301@PURE_QUANTA.Q_RES(CHIPS)':
 'B': CDS_PINID='B';
NODE_NAME     R1673 2
 '@S9S_MB_2U_LIB.S9S_MB_2U(SCH_1):PAGE297_I312@PURE_QUANTA.Q_RES(CHIPS)':
 'B': CDS_PINID='B';
NODE_NAME     J90 A9
 '@S9S_MB_2U_LIB.S9S_MB_2U(SCH_1):PAGE297_I318@PURE_QUANTA.SCONN56_123276793(CHIPS)':
 'SMBRST#': CDS_PINID='\smbrst#\';
NET_NAME
'RST_SMB_E1S_N'
 '@S9S_MB_2U_LIB.S9S_MB_2U(SCH_1):RST_SMB_E1S_N':
 C_SIGNAL='@s9s_mb_2u_lib.s9s_mb_2u(sch_1):rst_smb_e1s_n';
NODE_NAME     U134 1
 '@S9S_MB_2U_LIB.S9S_MB_2U(SCH_1):PAGE297_I305@PURE_QUANTA.74LVC2G07DW7(CHIPS)':
 '1A': CDS_PINID='\1a\';
NODE_NAME     U134 3
 '@S9S_MB_2U_LIB.S9S_MB_2U(SCH_1):PAGE297_I305@PURE_QUANTA.74LVC2G07DW7(CHIPS)':
 '2A': CDS_PINID='\2a\';
NODE_NAME     R3775 2
 '@S9S_MB_2U_LIB.S9S_MB_2U(SCH_1):PAGE297_I307@PURE_QUANTA.Q_RES(CHIPS)':
 'B': CDS_PINID='B';
NET_NAME
'RST_SMB_OCP_SFF_N'
 '@S9S_MB_2U_LIB.S9S_MB_2U(SCH_1):RST_SMB_OCP_SFF_N':
 C_SIGNAL='@s9s_mb_2u_lib.s9s_mb_2u(sch_1):rst_smb_ocp_sff_n';
NODE_NAME     J37 A9
 '@S9S_MB_2U_LIB.S9S_MB_2U(SCH_1):PAGE150_I199@PURE_QUANTA.SCONN168_ME1016810202011(CHIPS)':
 'SMRST#': CDS_PINID='\smrst#\';
NODE_NAME     R3233 2
 '@S9S_MB_2U_LIB.S9S_MB_2U(SCH_1):PAGE151_I17@PURE_QUANTA.Q_RES(CHIPS)':
 'B': CDS_PINID='B';
NET_NAME
'RST_SMB_OCP_V3_2_N'
 '@S9S_MB_2U_LIB.S9S_MB_2U(SCH_1):RST_SMB_OCP_V3_2_N':
 C_SIGNAL='@s9s_mb_2u_lib.s9s_mb_2u(sch_1):rst_smb_ocp_v3_2_n';
NODE_NAME     R3236 2
 '@S9S_MB_2U_LIB.S9S_MB_2U(SCH_1):PAGE156_I70@PURE_QUANTA.Q_RES(CHIPS)':
 'B': CDS_PINID='B';
NODE_NAME     J35 A9
 '@S9S_MB_2U_LIB.S9S_MB_2U(SCH_1):PAGE146_I303@PURE_QUANTA.SCONN168_ME1016810202011(CHIPS)':
 'SMRST#': CDS_PINID='\smrst#\';
NET_NAME
'RST_SMB_S3M_N'
 '@S9S_MB_2U_LIB.S9S_MB_2U(SCH_1):RST_SMB_S3M_N':
 C_SIGNAL='@s9s_mb_2u_lib.s9s_mb_2u(sch_1):rst_smb_s3m_n';
NODE_NAME     R2313 2
 '@S9S_MB_2U_LIB.S9S_MB_2U(SCH_1):PAGE224_I97@PURE_QUANTA.Q_RES(CHIPS)':
 'B': CDS_PINID='B';
NODE_NAME     U143 3
 '@S9S_MB_2U_LIB.S9S_MB_2U(SCH_1):PAGE224_I106@PURE_QUANTA.PCA9545APW(CHIPS)':
 'RESET#': CDS_PINID='\reset#\';
NET_NAME
'RST_SMB_SWITCH_N'
 '@S9S_MB_2U_LIB.S9S_MB_2U(SCH_1):RST_SMB_SWITCH_N':
 C_SIGNAL='@s9s_mb_2u_lib.s9s_mb_2u(sch_1):rst_smb_switch_n';
NODE_NAME     R2313 1
 '@S9S_MB_2U_LIB.S9S_MB_2U(SCH_1):PAGE224_I97@PURE_QUANTA.Q_RES(CHIPS)':
 'A': CDS_PINID='A';
NODE_NAME     R2921 2
 '@S9S_MB_2U_LIB.S9S_MB_2U(SCH_1):PAGE214_I93@PURE_QUANTA.Q_RES(CHIPS)':
 'B': CDS_PINID='B';
NODE_NAME     R2922 1
 '@S9S_MB_2U_LIB.S9S_MB_2U(SCH_1):PAGE214_I95@PURE_QUANTA.Q_RES(CHIPS)':
 'A': CDS_PINID='A';
NODE_NAME     U249 AB6
 '@S9S_MB_2U_LIB.S9S_MB_2U(SCH_1):PAGE312_I1@PURE_QUANTA.LCMXO3LF9400C5BG484C(CHIPS)':
 'PB11B': CDS_PINID='PB11B';
NODE_NAME     R3775 1
 '@S9S_MB_2U_LIB.S9S_MB_2U(SCH_1):PAGE297_I307@PURE_QUANTA.Q_RES(CHIPS)':
 'A': CDS_PINID='A';
NODE_NAME     U225 2
 '@S9S_MB_2U_LIB.S9S_MB_2U(SCH_1):PAGE156_I74@PURE_QUANTA.74LVC1G126SE7(CHIPS)':
 'A': CDS_PINID='A';
NODE_NAME     R3710 1
 '@S9S_MB_2U_LIB.S9S_MB_2U(SCH_1):PAGE221_I145@PURE_QUANTA.Q_RES(CHIPS)':
 'A': CDS_PINID='A';
NODE_NAME     R3705 2
 '@S9S_MB_2U_LIB.S9S_MB_2U(SCH_1):PAGE221_I147@PURE_QUANTA.Q_RES(CHIPS)':
 'B': CDS_PINID='B';
NODE_NAME     U224 2
 '@S9S_MB_2U_LIB.S9S_MB_2U(SCH_1):PAGE151_I7@PURE_QUANTA.74LVC1G126SE7(CHIPS)':
 'A': CDS_PINID='A';
NODE_NAME     R2905 1
 '@S9S_MB_2U_LIB.S9S_MB_2U(SCH_1):PAGE233_I34@PURE_QUANTA.Q_RES(CHIPS)':
 'A': CDS_PINID='A';
NODE_NAME     R1822 2
 '@S9S_MB_2U_LIB.S9S_MB_2U(SCH_1):PAGE219_I18@PURE_QUANTA.Q_RES(CHIPS)':
 'B': CDS_PINID='B';
NODE_NAME     R2268 1
 '@S9S_MB_2U_LIB.S9S_MB_2U(SCH_1):PAGE219_I41@PURE_QUANTA.Q_RES(CHIPS)':
 'A': CDS_PINID='A';
NET_NAME
'RST_SMB_SWITCH_R_N'
 '@S9S_MB_2U_LIB.S9S_MB_2U(SCH_1):RST_SMB_SWITCH_R_N':
 C_SIGNAL='@s9s_mb_2u_lib.s9s_mb_2u(sch_1):rst_smb_switch_r_n';
NODE_NAME     J45 B1
 '@S9S_MB_2U_LIB.S9S_MB_2U(SCH_1):PAGE233_I12@PURE_QUANTA.CONN60_101062636003K02LF(CHIPS)':
 'B1': CDS_PINID='B1';
NODE_NAME     R2905 2
 '@S9S_MB_2U_LIB.S9S_MB_2U(SCH_1):PAGE233_I34@PURE_QUANTA.Q_RES(CHIPS)':
 'B': CDS_PINID='B';
NODE_NAME     C2293 1
 '@S9S_MB_2U_LIB.S9S_MB_2U(SCH_1):PAGE233_I57@PURE_QUANTA.Q_CAP(CHIPS)':
 'A': CDS_PINID='A';
NET_NAME
'RST_SRST_PLD_BMC_N'
 '@S9S_MB_2U_LIB.S9S_MB_2U(SCH_1):RST_SRST_PLD_BMC_N':
 C_SIGNAL='@s9s_mb_2u_lib.s9s_mb_2u(sch_1):rst_srst_pld_bmc_n';
NODE_NAME     R4697 2
 '@S9S_MB_2U_LIB.S9S_MB_2U(SCH_1):PAGE314_I14@PURE_QUANTA.Q_RES(CHIPS)':
 'B': CDS_PINID='B';
NODE_NAME     J41 OB11
 '@S9S_MB_2U_LIB.S9S_MB_2U(SCH_1):PAGE227_I173@PURE_QUANTA.SCONN168_ME1016810202011(CHIPS)':
 'REFCLKN2': CDS_PINID='REFCLKN2';
NET_NAME
'RST_SRST_PLD_BMC_R_N'
 '@S9S_MB_2U_LIB.S9S_MB_2U(SCH_1):RST_SRST_PLD_BMC_R_N':
 C_SIGNAL='@s9s_mb_2u_lib.s9s_mb_2u(sch_1):rst_srst_pld_bmc_r_n';
NODE_NAME     R4697 1
 '@S9S_MB_2U_LIB.S9S_MB_2U(SCH_1):PAGE314_I14@PURE_QUANTA.Q_RES(CHIPS)':
 'A': CDS_PINID='A';
NODE_NAME     U249 F15
 '@S9S_MB_2U_LIB.S9S_MB_2U(SCH_1):PAGE314_I188@PURE_QUANTA.LCMXO3LF9400C5BG484C(CHIPS)':
 'PT42C': CDS_PINID='PT42C';
NET_NAME
'RST_SRTCRST_N'
 '@S9S_MB_2U_LIB.S9S_MB_2U(SCH_1):RST_SRTCRST_N':
 C_SIGNAL='@s9s_mb_2u_lib.s9s_mb_2u(sch_1):rst_srtcrst_n';
NODE_NAME     U4 BF9
 '@S9S_MB_2U_LIB.S9S_MB_2U(SCH_1):PAGE177_I27@PURE_QUANTA.EMMITSBURG_REV0P9(CHIPS)':
 'SRTCRST_N': CDS_PINID='SRTCRST_N';
NODE_NAME     C610 1
 '@S9S_MB_2U_LIB.S9S_MB_2U(SCH_1):PAGE177_I68@PURE_QUANTA.Q_CAP(CHIPS)':
 'A': CDS_PINID='A';
NODE_NAME     R1202 2
 '@S9S_MB_2U_LIB.S9S_MB_2U(SCH_1):PAGE177_I70@PURE_QUANTA.Q_RES(CHIPS)':
 'B': CDS_PINID='B';
NODE_NAME     R1840 2
 '@S9S_MB_2U_LIB.S9S_MB_2U(SCH_1):PAGE177_I89@PURE_QUANTA.Q_RES(CHIPS)':
 'B': CDS_PINID='B';
NODE_NAME     Q35 D
 '@S9S_MB_2U_LIB.S9S_MB_2U(SCH_1):PAGE177_I124@PURE_QUANTA.MOSFET_NCH_GDS_ESD_PROTECTED(CHIPS)':
 'D': CDS_PINID='D';
NET_NAME
'RST_SWB_BIC_BUF_N'
 '@S9S_MB_2U_LIB.S9S_MB_2U(SCH_1):RST_SWB_BIC_BUF_N':
 C_SIGNAL='@s9s_mb_2u_lib.s9s_mb_2u(sch_1):rst_swb_bic_buf_n';
NODE_NAME     J105 N6
 '@S9S_MB_2U_LIB.S9S_MB_2U(SCH_1):PAGE142_I68@PURE_QUANTA.CONN112_10137002101LF(CHIPS)':
 'N6': CDS_PINID='N6';
NODE_NAME     R2924 2
 '@S9S_MB_2U_LIB.S9S_MB_2U(SCH_1):PAGE140_I207@PURE_QUANTA.Q_RES(CHIPS)':
 'B': CDS_PINID='B';
NET_NAME
'RST_SWB_BIC_BUF_R_N'
 '@S9S_MB_2U_LIB.S9S_MB_2U(SCH_1):RST_SWB_BIC_BUF_R_N':
 C_SIGNAL='@s9s_mb_2u_lib.s9s_mb_2u(sch_1):rst_swb_bic_buf_r_n';
NODE_NAME     U195 4
 '@S9S_MB_2U_LIB.S9S_MB_2U(SCH_1):PAGE140_I65@PURE_QUANTA.74LVC2G17GW(CHIPS)':
 'B1': CDS_PINID='B1';
NODE_NAME     R2911 2
 '@S9S_MB_2U_LIB.S9S_MB_2U(SCH_1):PAGE140_I153@PURE_QUANTA.Q_RES(CHIPS)':
 'B': CDS_PINID='B';
NODE_NAME     R2927 1
 '@S9S_MB_2U_LIB.S9S_MB_2U(SCH_1):PAGE140_I203@PURE_QUANTA.Q_RES(CHIPS)':
 'A': CDS_PINID='A';
NODE_NAME     R2924 1
 '@S9S_MB_2U_LIB.S9S_MB_2U(SCH_1):PAGE140_I207@PURE_QUANTA.Q_RES(CHIPS)':
 'A': CDS_PINID='A';
NET_NAME
'RST_SWB_BIC_N'
 '@S9S_MB_2U_LIB.S9S_MB_2U(SCH_1):RST_SWB_BIC_N':
 C_SIGNAL='@s9s_mb_2u_lib.s9s_mb_2u(sch_1):rst_swb_bic_n';
NODE_NAME     R2848 1
 '@S9S_MB_2U_LIB.S9S_MB_2U(SCH_1):PAGE214_I34@PURE_QUANTA.Q_RES(CHIPS)':
 'A': CDS_PINID='A';
NODE_NAME     U181 5
 '@S9S_MB_2U_LIB.S9S_MB_2U(SCH_1):PAGE214_I66@PURE_QUANTA.PCA9539RPW(CHIPS)':
 'IO0_1': CDS_PINID='IO0_1';
NET_NAME
'RST_SWB_BIC_R_N'
 '@S9S_MB_2U_LIB.S9S_MB_2U(SCH_1):RST_SWB_BIC_R_N':
 C_SIGNAL='@s9s_mb_2u_lib.s9s_mb_2u(sch_1):rst_swb_bic_r_n';
NODE_NAME     R2848 2
 '@S9S_MB_2U_LIB.S9S_MB_2U(SCH_1):PAGE214_I34@PURE_QUANTA.Q_RES(CHIPS)':
 'B': CDS_PINID='B';
NODE_NAME     U195 3
 '@S9S_MB_2U_LIB.S9S_MB_2U(SCH_1):PAGE140_I65@PURE_QUANTA.74LVC2G17GW(CHIPS)':
 'A1': CDS_PINID='A1';
NODE_NAME     R2916 1
 '@S9S_MB_2U_LIB.S9S_MB_2U(SCH_1):PAGE140_I93@PURE_QUANTA.Q_RES(CHIPS)':
 'A': CDS_PINID='A';
NODE_NAME     R2909 2
 '@S9S_MB_2U_LIB.S9S_MB_2U(SCH_1):PAGE140_I198@PURE_QUANTA.Q_RES(CHIPS)':
 'B': CDS_PINID='B';
NET_NAME
'RST_USB_HUB_2_R_N'
 '@S9S_MB_2U_LIB.S9S_MB_2U(SCH_1):RST_USB_HUB_2_R_N':
 C_SIGNAL='@s9s_mb_2u_lib.s9s_mb_2u(sch_1):rst_usb_hub_2_r_n';
NODE_NAME     R4451 2
 '@S9S_MB_2U_LIB.S9S_MB_2U(SCH_1):PAGE194_I13@PURE_QUANTA.Q_RES(CHIPS)':
 'B': CDS_PINID='B';
NODE_NAME     C2317 1
 '@S9S_MB_2U_LIB.S9S_MB_2U(SCH_1):PAGE194_I15@PURE_QUANTA.Q_CAP(CHIPS)':
 'A': CDS_PINID='A';
NODE_NAME     R4453 2
 '@S9S_MB_2U_LIB.S9S_MB_2U(SCH_1):PAGE194_I26@PURE_QUANTA.Q_RES(CHIPS)':
 'B': CDS_PINID='B';
NODE_NAME     R4452 2
 '@S9S_MB_2U_LIB.S9S_MB_2U(SCH_1):PAGE194_I27@PURE_QUANTA.Q_RES(CHIPS)':
 'B': CDS_PINID='B';
NODE_NAME     U313 17
 '@S9S_MB_2U_LIB.S9S_MB_2U(SCH_1):PAGE194_I40@PURE_QUANTA.GL852GOHY60(CHIPS)':
 'RESET#': CDS_PINID='\reset#\';
NET_NAME
'RST_USB_HUB_N'
 '@S9S_MB_2U_LIB.S9S_MB_2U(SCH_1):RST_USB_HUB_N':
 C_SIGNAL='@s9s_mb_2u_lib.s9s_mb_2u(sch_1):rst_usb_hub_n';
NODE_NAME     U181 4
 '@S9S_MB_2U_LIB.S9S_MB_2U(SCH_1):PAGE214_I66@PURE_QUANTA.PCA9539RPW(CHIPS)':
 'IO0_0': CDS_PINID='IO0_0';
NODE_NAME     R3654 1
 '@S9S_MB_2U_LIB.S9S_MB_2U(SCH_1):PAGE155_I155@PURE_QUANTA.Q_RES(CHIPS)':
 'A': CDS_PINID='A';
NODE_NAME     R4451 1
 '@S9S_MB_2U_LIB.S9S_MB_2U(SCH_1):PAGE194_I13@PURE_QUANTA.Q_RES(CHIPS)':
 'A': CDS_PINID='A';
NET_NAME
'RST_USB_HUB_R_N'
 '@S9S_MB_2U_LIB.S9S_MB_2U(SCH_1):RST_USB_HUB_R_N':
 C_SIGNAL='@s9s_mb_2u_lib.s9s_mb_2u(sch_1):rst_usb_hub_r_n';
NODE_NAME     U268 17
 '@S9S_MB_2U_LIB.S9S_MB_2U(SCH_1):PAGE155_I100@PURE_QUANTA.GL852GOHY60(CHIPS)':
 'RESET#': CDS_PINID='\reset#\';
NODE_NAME     R3654 2
 '@S9S_MB_2U_LIB.S9S_MB_2U(SCH_1):PAGE155_I155@PURE_QUANTA.Q_RES(CHIPS)':
 'B': CDS_PINID='B';
NODE_NAME     C2041 1
 '@S9S_MB_2U_LIB.S9S_MB_2U(SCH_1):PAGE155_I158@PURE_QUANTA.Q_CAP(CHIPS)':
 'A': CDS_PINID='A';
NODE_NAME     R3660 2
 '@S9S_MB_2U_LIB.S9S_MB_2U(SCH_1):PAGE155_I159@PURE_QUANTA.Q_RES(CHIPS)':
 'B': CDS_PINID='B';
NODE_NAME     R3661 2
 '@S9S_MB_2U_LIB.S9S_MB_2U(SCH_1):PAGE155_I201@PURE_QUANTA.Q_RES(CHIPS)':
 'B': CDS_PINID='B';
NET_NAME
'RTC_EXT_CAP'
 '@S9S_MB_2U_LIB.S9S_MB_2U(SCH_1):RTC_EXT_CAP':
 C_SIGNAL='@s9s_mb_2u_lib.s9s_mb_2u(sch_1):rtc_ext_cap';
NODE_NAME     U4 BF5
 '@S9S_MB_2U_LIB.S9S_MB_2U(SCH_1):PAGE171_I78@PURE_QUANTA.EMMITSBURG_REV0P9(CHIPS)':
 'RTC_EXTCAP': CDS_PINID='RTC_EXTCAP';
NODE_NAME     C609 1
 '@S9S_MB_2U_LIB.S9S_MB_2U(SCH_1):PAGE171_I89@PURE_QUANTA.Q_CAP(CHIPS)':
 'A': CDS_PINID='A';
NET_NAME
'SGPIO_BMC_CLK'
 '@S9S_MB_2U_LIB.S9S_MB_2U(SCH_1):SGPIO_BMC_CLK':
 C_SIGNAL='@s9s_mb_2u_lib.s9s_mb_2u(sch_1):sgpio_bmc_clk';
NODE_NAME     R1756 2
 '@S9S_MB_2U_LIB.S9S_MB_2U(SCH_1):PAGE211_I98@PURE_QUANTA.Q_RES(CHIPS)':
 'B': CDS_PINID='B';
NODE_NAME     U249 D14
 '@S9S_MB_2U_LIB.S9S_MB_2U(SCH_1):PAGE314_I188@PURE_QUANTA.LCMXO3LF9400C5BG484C(CHIPS)':
 'PT30D': CDS_PINID='PT30D';
NET_NAME
'SGPIO_BMC_DIN_R'
 '@S9S_MB_2U_LIB.S9S_MB_2U(SCH_1):SGPIO_BMC_DIN_R':
 C_SIGNAL='@s9s_mb_2u_lib.s9s_mb_2u(sch_1):sgpio_bmc_din_r';
NODE_NAME     R1757 2
 '@S9S_MB_2U_LIB.S9S_MB_2U(SCH_1):PAGE211_I99@PURE_QUANTA.Q_RES(CHIPS)':
 'B': CDS_PINID='B';
NODE_NAME     U249 G14
 '@S9S_MB_2U_LIB.S9S_MB_2U(SCH_1):PAGE314_I188@PURE_QUANTA.LCMXO3LF9400C5BG484C(CHIPS)':
 'PT31A': CDS_PINID='PT31A';
NET_NAME
'SGPIO_BMC_DOUT'
 '@S9S_MB_2U_LIB.S9S_MB_2U(SCH_1):SGPIO_BMC_DOUT':
 C_SIGNAL='@s9s_mb_2u_lib.s9s_mb_2u(sch_1):sgpio_bmc_dout';
NODE_NAME     R1755 2
 '@S9S_MB_2U_LIB.S9S_MB_2U(SCH_1):PAGE211_I96@PURE_QUANTA.Q_RES(CHIPS)':
 'B': CDS_PINID='B';
NODE_NAME     U249 C14
 '@S9S_MB_2U_LIB.S9S_MB_2U(SCH_1):PAGE314_I188@PURE_QUANTA.LCMXO3LF9400C5BG484C(CHIPS)':
 'PT30C': CDS_PINID='PT30C';
NET_NAME
'SGPIO_BMC_LD_N'
 '@S9S_MB_2U_LIB.S9S_MB_2U(SCH_1):SGPIO_BMC_LD_N':
 C_SIGNAL='@s9s_mb_2u_lib.s9s_mb_2u(sch_1):sgpio_bmc_ld_n';
NODE_NAME     R1758 2
 '@S9S_MB_2U_LIB.S9S_MB_2U(SCH_1):PAGE211_I91@PURE_QUANTA.Q_RES(CHIPS)':
 'B': CDS_PINID='B';
NODE_NAME     U249 F14
 '@S9S_MB_2U_LIB.S9S_MB_2U(SCH_1):PAGE314_I188@PURE_QUANTA.LCMXO3LF9400C5BG484C(CHIPS)':
 'PT31B': CDS_PINID='PT31B';
NET_NAME
'SGPIO_CLK_0'
 '@S9S_MB_2U_LIB.S9S_MB_2U(SCH_1):SGPIO_CLK_0':
 C_SIGNAL='@s9s_mb_2u_lib.s9s_mb_2u(sch_1):sgpio_clk_0';
NODE_NAME     R1752 1
 '@S9S_MB_2U_LIB.S9S_MB_2U(SCH_1):PAGE211_I82@PURE_QUANTA.Q_RES(CHIPS)':
 'A': CDS_PINID='A';
NODE_NAME     J41 B30
 '@S9S_MB_2U_LIB.S9S_MB_2U(SCH_1):PAGE227_I173@PURE_QUANTA.SCONN168_ME1016810202011(CHIPS)':
 'PETN4': CDS_PINID='PETN4';
NET_NAME
'SGPIO_CLK_1'
 '@S9S_MB_2U_LIB.S9S_MB_2U(SCH_1):SGPIO_CLK_1':
 C_SIGNAL='@s9s_mb_2u_lib.s9s_mb_2u(sch_1):sgpio_clk_1';
NODE_NAME     R1756 1
 '@S9S_MB_2U_LIB.S9S_MB_2U(SCH_1):PAGE211_I98@PURE_QUANTA.Q_RES(CHIPS)':
 'A': CDS_PINID='A';
NODE_NAME     J41 B35
 '@S9S_MB_2U_LIB.S9S_MB_2U(SCH_1):PAGE227_I173@PURE_QUANTA.SCONN168_ME1016810202011(CHIPS)':
 'GND_B35': CDS_PINID='GND_B35';
NET_NAME
'SGPIO_DEBUG_PLD_CLK'
 '@S9S_MB_2U_LIB.S9S_MB_2U(SCH_1):SGPIO_DEBUG_PLD_CLK':
 C_SIGNAL='@s9s_mb_2u_lib.s9s_mb_2u(sch_1):sgpio_debug_pld_clk';
NODE_NAME     R1752 2
 '@S9S_MB_2U_LIB.S9S_MB_2U(SCH_1):PAGE211_I82@PURE_QUANTA.Q_RES(CHIPS)':
 'B': CDS_PINID='B';
NODE_NAME     U249 B15
 '@S9S_MB_2U_LIB.S9S_MB_2U(SCH_1):PAGE314_I188@PURE_QUANTA.LCMXO3LF9400C5BG484C(CHIPS)':
 'PT38B': CDS_PINID='PT38B';
NET_NAME
'SGPIO_DEBUG_PLD_DIN'
 '@S9S_MB_2U_LIB.S9S_MB_2U(SCH_1):SGPIO_DEBUG_PLD_DIN':
 C_SIGNAL='@s9s_mb_2u_lib.s9s_mb_2u(sch_1):sgpio_debug_pld_din';
NODE_NAME     R1753 2
 '@S9S_MB_2U_LIB.S9S_MB_2U(SCH_1):PAGE211_I84@PURE_QUANTA.Q_RES(CHIPS)':
 'B': CDS_PINID='B';
NODE_NAME     U249 C15
 '@S9S_MB_2U_LIB.S9S_MB_2U(SCH_1):PAGE314_I188@PURE_QUANTA.LCMXO3LF9400C5BG484C(CHIPS)':
 'PT38C': CDS_PINID='PT38C';
NET_NAME
'SGPIO_DEBUG_PLD_DOUT'
 '@S9S_MB_2U_LIB.S9S_MB_2U(SCH_1):SGPIO_DEBUG_PLD_DOUT':
 C_SIGNAL='@s9s_mb_2u_lib.s9s_mb_2u(sch_1):sgpio_debug_pld_dout';
NODE_NAME     R1751 2
 '@S9S_MB_2U_LIB.S9S_MB_2U(SCH_1):PAGE211_I81@PURE_QUANTA.Q_RES(CHIPS)':
 'B': CDS_PINID='B';
NODE_NAME     U249 A15
 '@S9S_MB_2U_LIB.S9S_MB_2U(SCH_1):PAGE314_I188@PURE_QUANTA.LCMXO3LF9400C5BG484C(CHIPS)':
 'PT38A': CDS_PINID='PT38A';
NET_NAME
'SGPIO_DEBUG_PLD_LD_N'
 '@S9S_MB_2U_LIB.S9S_MB_2U(SCH_1):SGPIO_DEBUG_PLD_LD_N':
 C_SIGNAL='@s9s_mb_2u_lib.s9s_mb_2u(sch_1):sgpio_debug_pld_ld_n';
NODE_NAME     R1754 2
 '@S9S_MB_2U_LIB.S9S_MB_2U(SCH_1):PAGE211_I88@PURE_QUANTA.Q_RES(CHIPS)':
 'B': CDS_PINID='B';
NODE_NAME     U249 D15
 '@S9S_MB_2U_LIB.S9S_MB_2U(SCH_1):PAGE314_I188@PURE_QUANTA.LCMXO3LF9400C5BG484C(CHIPS)':
 'PT38D': CDS_PINID='PT38D';
NET_NAME
'SGPIO_DI_0'
 '@S9S_MB_2U_LIB.S9S_MB_2U(SCH_1):SGPIO_DI_0':
 C_SIGNAL='@s9s_mb_2u_lib.s9s_mb_2u(sch_1):sgpio_di_0';
NODE_NAME     R1753 1
 '@S9S_MB_2U_LIB.S9S_MB_2U(SCH_1):PAGE211_I84@PURE_QUANTA.Q_RES(CHIPS)':
 'A': CDS_PINID='A';
NODE_NAME     J41 B31
 '@S9S_MB_2U_LIB.S9S_MB_2U(SCH_1):PAGE227_I173@PURE_QUANTA.SCONN168_ME1016810202011(CHIPS)':
 'PETP4': CDS_PINID='PETP4';
NET_NAME
'SGPIO_DI_1'
 '@S9S_MB_2U_LIB.S9S_MB_2U(SCH_1):SGPIO_DI_1':
 C_SIGNAL='@s9s_mb_2u_lib.s9s_mb_2u(sch_1):sgpio_di_1';
NODE_NAME     R1757 1
 '@S9S_MB_2U_LIB.S9S_MB_2U(SCH_1):PAGE211_I99@PURE_QUANTA.Q_RES(CHIPS)':
 'A': CDS_PINID='A';
NODE_NAME     J41 B36
 '@S9S_MB_2U_LIB.S9S_MB_2U(SCH_1):PAGE227_I173@PURE_QUANTA.SCONN168_ME1016810202011(CHIPS)':
 'PETN6': CDS_PINID='PETN6';
NET_NAME
'SGPIO_DO_0'
 '@S9S_MB_2U_LIB.S9S_MB_2U(SCH_1):SGPIO_DO_0':
 C_SIGNAL='@s9s_mb_2u_lib.s9s_mb_2u(sch_1):sgpio_do_0';
NODE_NAME     R1751 1
 '@S9S_MB_2U_LIB.S9S_MB_2U(SCH_1):PAGE211_I81@PURE_QUANTA.Q_RES(CHIPS)':
 'A': CDS_PINID='A';
NODE_NAME     J41 B29
 '@S9S_MB_2U_LIB.S9S_MB_2U(SCH_1):PAGE227_I173@PURE_QUANTA.SCONN168_ME1016810202011(CHIPS)':
 'GND_B29': CDS_PINID='GND_B29';
NET_NAME
'SGPIO_DO_1'
 '@S9S_MB_2U_LIB.S9S_MB_2U(SCH_1):SGPIO_DO_1':
 C_SIGNAL='@s9s_mb_2u_lib.s9s_mb_2u(sch_1):sgpio_do_1';
NODE_NAME     R1755 1
 '@S9S_MB_2U_LIB.S9S_MB_2U(SCH_1):PAGE211_I96@PURE_QUANTA.Q_RES(CHIPS)':
 'A': CDS_PINID='A';
NODE_NAME     J41 B34
 '@S9S_MB_2U_LIB.S9S_MB_2U(SCH_1):PAGE227_I173@PURE_QUANTA.SCONN168_ME1016810202011(CHIPS)':
 'PETP5': CDS_PINID='PETP5';
NET_NAME
'SGPIO_LD_0'
 '@S9S_MB_2U_LIB.S9S_MB_2U(SCH_1):SGPIO_LD_0':
 C_SIGNAL='@s9s_mb_2u_lib.s9s_mb_2u(sch_1):sgpio_ld_0';
NODE_NAME     R1754 1
 '@S9S_MB_2U_LIB.S9S_MB_2U(SCH_1):PAGE211_I88@PURE_QUANTA.Q_RES(CHIPS)':
 'A': CDS_PINID='A';
NODE_NAME     J41 B32
 '@S9S_MB_2U_LIB.S9S_MB_2U(SCH_1):PAGE227_I173@PURE_QUANTA.SCONN168_ME1016810202011(CHIPS)':
 'GND_B32': CDS_PINID='GND_B32';
NET_NAME
'SGPIO_LD_1'
 '@S9S_MB_2U_LIB.S9S_MB_2U(SCH_1):SGPIO_LD_1':
 C_SIGNAL='@s9s_mb_2u_lib.s9s_mb_2u(sch_1):sgpio_ld_1';
NODE_NAME     R1758 1
 '@S9S_MB_2U_LIB.S9S_MB_2U(SCH_1):PAGE211_I91@PURE_QUANTA.Q_RES(CHIPS)':
 'A': CDS_PINID='A';
NODE_NAME     J41 B37
 '@S9S_MB_2U_LIB.S9S_MB_2U(SCH_1):PAGE227_I173@PURE_QUANTA.SCONN168_ME1016810202011(CHIPS)':
 'PETP6': CDS_PINID='PETP6';
NET_NAME
'SGPIO_OCP_SFF_CLK'
 '@S9S_MB_2U_LIB.S9S_MB_2U(SCH_1):SGPIO_OCP_SFF_CLK':
 C_SIGNAL='@s9s_mb_2u_lib.s9s_mb_2u(sch_1):sgpio_ocp_sff_clk';
NODE_NAME     J37 OB6
 '@S9S_MB_2U_LIB.S9S_MB_2U(SCH_1):PAGE150_I199@PURE_QUANTA.SCONN168_ME1016810202011(CHIPS)':
 'CLK': CDS_PINID='CLK';
NODE_NAME     R423 1
 '@S9S_MB_2U_LIB.S9S_MB_2U(SCH_1):PAGE150_I212@PURE_QUANTA.Q_RES(CHIPS)':
 'A': CDS_PINID='A';
NODE_NAME     U249 B17
 '@S9S_MB_2U_LIB.S9S_MB_2U(SCH_1):PAGE314_I188@PURE_QUANTA.LCMXO3LF9400C5BG484C(CHIPS)':
 'PT39B': CDS_PINID='PT39B';
NET_NAME
'SGPIO_OCP_SFF_DATAIN'
 '@S9S_MB_2U_LIB.S9S_MB_2U(SCH_1):SGPIO_OCP_SFF_DATAIN':
 C_SIGNAL='@s9s_mb_2u_lib.s9s_mb_2u(sch_1):sgpio_ocp_sff_datain';
NODE_NAME     J37 OB4
 '@S9S_MB_2U_LIB.S9S_MB_2U(SCH_1):PAGE150_I199@PURE_QUANTA.SCONN168_ME1016810202011(CHIPS)':
 'DATA_IN': CDS_PINID='DATA_IN';
NODE_NAME     R421 1
 '@S9S_MB_2U_LIB.S9S_MB_2U(SCH_1):PAGE150_I217@PURE_QUANTA.Q_RES(CHIPS)':
 'A': CDS_PINID='A';
NODE_NAME     U249 C17
 '@S9S_MB_2U_LIB.S9S_MB_2U(SCH_1):PAGE314_I188@PURE_QUANTA.LCMXO3LF9400C5BG484C(CHIPS)':
 'PT39C': CDS_PINID='PT39C';
NET_NAME
'SGPIO_OCP_SFF_DATAOUT'
 '@S9S_MB_2U_LIB.S9S_MB_2U(SCH_1):SGPIO_OCP_SFF_DATAOUT':
 C_SIGNAL='@s9s_mb_2u_lib.s9s_mb_2u(sch_1):sgpio_ocp_sff_dataout';
NODE_NAME     J37 OB5
 '@S9S_MB_2U_LIB.S9S_MB_2U(SCH_1):PAGE150_I199@PURE_QUANTA.SCONN168_ME1016810202011(CHIPS)':
 'DATA_OUT': CDS_PINID='DATA_OUT';
NODE_NAME     R422 1
 '@S9S_MB_2U_LIB.S9S_MB_2U(SCH_1):PAGE150_I215@PURE_QUANTA.Q_RES(CHIPS)':
 'A': CDS_PINID='A';
NODE_NAME     U249 A16
 '@S9S_MB_2U_LIB.S9S_MB_2U(SCH_1):PAGE314_I188@PURE_QUANTA.LCMXO3LF9400C5BG484C(CHIPS)':
 'PT39A': CDS_PINID='PT39A';
NET_NAME
'SGPIO_OCP_SFF_LD_N'
 '@S9S_MB_2U_LIB.S9S_MB_2U(SCH_1):SGPIO_OCP_SFF_LD_N':
 C_SIGNAL='@s9s_mb_2u_lib.s9s_mb_2u(sch_1):sgpio_ocp_sff_ld_n';
NODE_NAME     J37 OB3
 '@S9S_MB_2U_LIB.S9S_MB_2U(SCH_1):PAGE150_I199@PURE_QUANTA.SCONN168_ME1016810202011(CHIPS)':
 'LD#': CDS_PINID='\ld#\';
NODE_NAME     R420 1
 '@S9S_MB_2U_LIB.S9S_MB_2U(SCH_1):PAGE150_I218@PURE_QUANTA.Q_RES(CHIPS)':
 'A': CDS_PINID='A';
NODE_NAME     U249 D16
 '@S9S_MB_2U_LIB.S9S_MB_2U(SCH_1):PAGE314_I188@PURE_QUANTA.LCMXO3LF9400C5BG484C(CHIPS)':
 'PT39D': CDS_PINID='PT39D';
NET_NAME
'SGPIO_OCP_V3_2_CLK'
 '@S9S_MB_2U_LIB.S9S_MB_2U(SCH_1):SGPIO_OCP_V3_2_CLK':
 C_SIGNAL='@s9s_mb_2u_lib.s9s_mb_2u(sch_1):sgpio_ocp_v3_2_clk';
NODE_NAME     J35 OB6
 '@S9S_MB_2U_LIB.S9S_MB_2U(SCH_1):PAGE146_I303@PURE_QUANTA.SCONN168_ME1016810202011(CHIPS)':
 'CLK': CDS_PINID='CLK';
NODE_NAME     R3176 1
 '@S9S_MB_2U_LIB.S9S_MB_2U(SCH_1):PAGE146_I336@PURE_QUANTA.Q_RES(CHIPS)':
 'A': CDS_PINID='A';
NODE_NAME     U249 B18
 '@S9S_MB_2U_LIB.S9S_MB_2U(SCH_1):PAGE314_I188@PURE_QUANTA.LCMXO3LF9400C5BG484C(CHIPS)':
 'PT40B': CDS_PINID='PT40B';
NET_NAME
'SGPIO_OCP_V3_2_DATAIN'
 '@S9S_MB_2U_LIB.S9S_MB_2U(SCH_1):SGPIO_OCP_V3_2_DATAIN':
 C_SIGNAL='@s9s_mb_2u_lib.s9s_mb_2u(sch_1):sgpio_ocp_v3_2_datain';
NODE_NAME     J35 OB4
 '@S9S_MB_2U_LIB.S9S_MB_2U(SCH_1):PAGE146_I303@PURE_QUANTA.SCONN168_ME1016810202011(CHIPS)':
 'DATA_IN': CDS_PINID='DATA_IN';
NODE_NAME     R3174 1
 '@S9S_MB_2U_LIB.S9S_MB_2U(SCH_1):PAGE146_I333@PURE_QUANTA.Q_RES(CHIPS)':
 'A': CDS_PINID='A';
NODE_NAME     U249 E16
 '@S9S_MB_2U_LIB.S9S_MB_2U(SCH_1):PAGE314_I188@PURE_QUANTA.LCMXO3LF9400C5BG484C(CHIPS)':
 'PT40C': CDS_PINID='PT40C';
NET_NAME
'SGPIO_OCP_V3_2_DATAOUT'
 '@S9S_MB_2U_LIB.S9S_MB_2U(SCH_1):SGPIO_OCP_V3_2_DATAOUT':
 C_SIGNAL='@s9s_mb_2u_lib.s9s_mb_2u(sch_1):sgpio_ocp_v3_2_dataout';
NODE_NAME     J35 OB5
 '@S9S_MB_2U_LIB.S9S_MB_2U(SCH_1):PAGE146_I303@PURE_QUANTA.SCONN168_ME1016810202011(CHIPS)':
 'DATA_OUT': CDS_PINID='DATA_OUT';
NODE_NAME     R3175 1
 '@S9S_MB_2U_LIB.S9S_MB_2U(SCH_1):PAGE146_I334@PURE_QUANTA.Q_RES(CHIPS)':
 'A': CDS_PINID='A';
NODE_NAME     U249 A17
 '@S9S_MB_2U_LIB.S9S_MB_2U(SCH_1):PAGE314_I188@PURE_QUANTA.LCMXO3LF9400C5BG484C(CHIPS)':
 'PT40A': CDS_PINID='PT40A';
NET_NAME
'SGPIO_OCP_V3_2_LD_N'
 '@S9S_MB_2U_LIB.S9S_MB_2U(SCH_1):SGPIO_OCP_V3_2_LD_N':
 C_SIGNAL='@s9s_mb_2u_lib.s9s_mb_2u(sch_1):sgpio_ocp_v3_2_ld_n';
NODE_NAME     R3173 1
 '@S9S_MB_2U_LIB.S9S_MB_2U(SCH_1):PAGE146_I165@PURE_QUANTA.Q_RES(CHIPS)':
 'A': CDS_PINID='A';
NODE_NAME     J35 OB3
 '@S9S_MB_2U_LIB.S9S_MB_2U(SCH_1):PAGE146_I303@PURE_QUANTA.SCONN168_ME1016810202011(CHIPS)':
 'LD#': CDS_PINID='\ld#\';
NODE_NAME     U249 D17
 '@S9S_MB_2U_LIB.S9S_MB_2U(SCH_1):PAGE314_I188@PURE_QUANTA.LCMXO3LF9400C5BG484C(CHIPS)':
 'PT40D': CDS_PINID='PT40D';
NET_NAME
'SH_P1V05_PCH_AUX_N'
 '@S9S_MB_2U_LIB.S9S_MB_2U(SCH_1):SH_P1V05_PCH_AUX_N':
 C_SIGNAL='@s9s_mb_2u_lib.s9s_mb_2u(sch_1):sh_p1v05_pch_aux_n';
NODE_NAME     PR187 2
 '@S9S_MB_2U_LIB.S9S_MB_2U(SCH_1):PAGE248_I34@PURE_QUANTA.Q_RES(CHIPS)':
 'B': CDS_PINID='B';
NODE_NAME     PC2279 2
 '@S9S_MB_2U_LIB.S9S_MB_2U(SCH_1):PAGE248_I37@PURE_QUANTA.Q_CAP(CHIPS)':
 'B': CDS_PINID='B';
NODE_NAME     PJ63 1
 '@S9S_MB_2U_LIB.S9S_MB_2U(SCH_1):PAGE248_I42@PURE_QUANTA.Q_SHORT(CHIPS)':
 '1': CDS_PINID='\1\';
NODE_NAME     PU73 6
 '@S9S_MB_2U_LIB.S9S_MB_2U(SCH_1):PAGE248_I11@PURE_QUANTA.RS53319LR(CHIPS)':
 'RTN': CDS_PINID='RTN';
NODE_NAME     PC1221 2
 '@S9S_MB_2U_LIB.S9S_MB_2U(SCH_1):PAGE248_I16@PURE_QUANTA.Q_CAP(CHIPS)':
 'B': CDS_PINID='B';
NET_NAME
'SH_P1V05_PCH_AUX_P'
 '@S9S_MB_2U_LIB.S9S_MB_2U(SCH_1):SH_P1V05_PCH_AUX_P':
 C_SIGNAL='@s9s_mb_2u_lib.s9s_mb_2u(sch_1):sh_p1v05_pch_aux_p';
NODE_NAME     PC1223 2
 '@S9S_MB_2U_LIB.S9S_MB_2U(SCH_1):PAGE248_I35@PURE_QUANTA.Q_CAP(CHIPS)':
 'B': CDS_PINID='B';
NODE_NAME     PR1328 2
 '@S9S_MB_2U_LIB.S9S_MB_2U(SCH_1):PAGE248_I36@PURE_QUANTA.Q_RES(CHIPS)':
 'B': CDS_PINID='B';
NODE_NAME     PC2279 1
 '@S9S_MB_2U_LIB.S9S_MB_2U(SCH_1):PAGE248_I37@PURE_QUANTA.Q_CAP(CHIPS)':
 'A': CDS_PINID='A';
NODE_NAME     PJ62 1
 '@S9S_MB_2U_LIB.S9S_MB_2U(SCH_1):PAGE248_I43@PURE_QUANTA.Q_SHORT(CHIPS)':
 '1': CDS_PINID='\1\';
NET_NAME
'SH_PVCCD_HV_CPU0'
 '@S9S_MB_2U_LIB.S9S_MB_2U(SCH_1):SH_PVCCD_HV_CPU0':
 C_SIGNAL='@s9s_mb_2u_lib.s9s_mb_2u(sch_1):sh_pvccd_hv_cpu0';
NODE_NAME     PJ54 2
 '@S9S_MB_2U_LIB.S9S_MB_2U(SCH_1):PAGE264_I32@PURE_QUANTA.Q_SHORT(CHIPS)':
 '2': CDS_PINID='\2\';
NODE_NAME     PR371 1
 '@S9S_MB_2U_LIB.S9S_MB_2U(SCH_1):PAGE264_I36@PURE_QUANTA.Q_RES(CHIPS)':
 'A': CDS_PINID='A';
NET_NAME
'SH_PVCCD_HV_CPU0_R'
 '@S9S_MB_2U_LIB.S9S_MB_2U(SCH_1):SH_PVCCD_HV_CPU0_R':
 C_SIGNAL='@s9s_mb_2u_lib.s9s_mb_2u(sch_1):sh_pvccd_hv_cpu0_r';
NODE_NAME     PU35 21
 '@S9S_MB_2U_LIB.S9S_MB_2U(SCH_1):PAGE264_I53@PURE_QUANTA.ISL69260IRAZT(CHIPS)':
 'VSEN0': CDS_PINID='VSEN0';
NODE_NAME     PR371 2
 '@S9S_MB_2U_LIB.S9S_MB_2U(SCH_1):PAGE264_I36@PURE_QUANTA.Q_RES(CHIPS)':
 'B': CDS_PINID='B';
NODE_NAME     PC627 1
 '@S9S_MB_2U_LIB.S9S_MB_2U(SCH_1):PAGE264_I37@PURE_QUANTA.Q_CAP(CHIPS)':
 'A': CDS_PINID='A';
NET_NAME
'SH_PVCCD_HV_CPU1'
 '@S9S_MB_2U_LIB.S9S_MB_2U(SCH_1):SH_PVCCD_HV_CPU1':
 C_SIGNAL='@s9s_mb_2u_lib.s9s_mb_2u(sch_1):sh_pvccd_hv_cpu1';
NODE_NAME     PR216 1
 '@S9S_MB_2U_LIB.S9S_MB_2U(SCH_1):PAGE282_I21@PURE_QUANTA.Q_RES(CHIPS)':
 'A': CDS_PINID='A';
NODE_NAME     PJ48 2
 '@S9S_MB_2U_LIB.S9S_MB_2U(SCH_1):PAGE282_I16@PURE_QUANTA.Q_SHORT(CHIPS)':
 '2': CDS_PINID='\2\';
NET_NAME
'SH_PVCCD_HV_CPU1_R'
 '@S9S_MB_2U_LIB.S9S_MB_2U(SCH_1):SH_PVCCD_HV_CPU1_R':
 C_SIGNAL='@s9s_mb_2u_lib.s9s_mb_2u(sch_1):sh_pvccd_hv_cpu1_r';
NODE_NAME     PU18 21
 '@S9S_MB_2U_LIB.S9S_MB_2U(SCH_1):PAGE282_I53@PURE_QUANTA.ISL69260IRAZT(CHIPS)':
 'VSEN0': CDS_PINID='VSEN0';
NODE_NAME     PR216 2
 '@S9S_MB_2U_LIB.S9S_MB_2U(SCH_1):PAGE282_I21@PURE_QUANTA.Q_RES(CHIPS)':
 'B': CDS_PINID='B';
NODE_NAME     PC389 1
 '@S9S_MB_2U_LIB.S9S_MB_2U(SCH_1):PAGE282_I22@PURE_QUANTA.Q_CAP(CHIPS)':
 'A': CDS_PINID='A';
NET_NAME
'SH_PVCCFA_EHV_CPU0'
 '@S9S_MB_2U_LIB.S9S_MB_2U(SCH_1):SH_PVCCFA_EHV_CPU0':
 C_SIGNAL='@s9s_mb_2u_lib.s9s_mb_2u(sch_1):sh_pvccfa_ehv_cpu0';
NODE_NAME     PJ46 2
 '@S9S_MB_2U_LIB.S9S_MB_2U(SCH_1):PAGE260_I39@PURE_QUANTA.Q_SHORT(CHIPS)':
 '2': CDS_PINID='\2\';
NODE_NAME     PR121 1
 '@S9S_MB_2U_LIB.S9S_MB_2U(SCH_1):PAGE260_I47@PURE_QUANTA.Q_RES(CHIPS)':
 'A': CDS_PINID='A';
NET_NAME
'SH_PVCCFA_EHV_CPU0_R'
 '@S9S_MB_2U_LIB.S9S_MB_2U(SCH_1):SH_PVCCFA_EHV_CPU0_R':
 C_SIGNAL='@s9s_mb_2u_lib.s9s_mb_2u(sch_1):sh_pvccfa_ehv_cpu0_r';
NODE_NAME     PU5 32
 '@S9S_MB_2U_LIB.S9S_MB_2U(SCH_1):PAGE260_I65@PURE_QUANTA.ISL69260IRAZT(CHIPS)':
 'VSEN1': CDS_PINID='VSEN1';
NODE_NAME     PC216 1
 '@S9S_MB_2U_LIB.S9S_MB_2U(SCH_1):PAGE260_I48@PURE_QUANTA.Q_CAP(CHIPS)':
 'A': CDS_PINID='A';
NODE_NAME     PR121 2
 '@S9S_MB_2U_LIB.S9S_MB_2U(SCH_1):PAGE260_I47@PURE_QUANTA.Q_RES(CHIPS)':
 'B': CDS_PINID='B';
NET_NAME
'SH_PVCCFA_EHV_CPU1'
 '@S9S_MB_2U_LIB.S9S_MB_2U(SCH_1):SH_PVCCFA_EHV_CPU1':
 C_SIGNAL='@s9s_mb_2u_lib.s9s_mb_2u(sch_1):sh_pvccfa_ehv_cpu1';
NODE_NAME     PR274 1
 '@S9S_MB_2U_LIB.S9S_MB_2U(SCH_1):PAGE278_I52@PURE_QUANTA.Q_RES(CHIPS)':
 'A': CDS_PINID='A';
NODE_NAME     PJ51 2
 '@S9S_MB_2U_LIB.S9S_MB_2U(SCH_1):PAGE278_I44@PURE_QUANTA.Q_SHORT(CHIPS)':
 '2': CDS_PINID='\2\';
NET_NAME
'SH_PVCCFA_EHV_CPU1_R'
 '@S9S_MB_2U_LIB.S9S_MB_2U(SCH_1):SH_PVCCFA_EHV_CPU1_R':
 C_SIGNAL='@s9s_mb_2u_lib.s9s_mb_2u(sch_1):sh_pvccfa_ehv_cpu1_r';
NODE_NAME     PC469 1
 '@S9S_MB_2U_LIB.S9S_MB_2U(SCH_1):PAGE278_I51@PURE_QUANTA.Q_CAP(CHIPS)':
 'A': CDS_PINID='A';
NODE_NAME     PR274 2
 '@S9S_MB_2U_LIB.S9S_MB_2U(SCH_1):PAGE278_I52@PURE_QUANTA.Q_RES(CHIPS)':
 'B': CDS_PINID='B';
NODE_NAME     PU22 32
 '@S9S_MB_2U_LIB.S9S_MB_2U(SCH_1):PAGE278_I38@PURE_QUANTA.ISL69260IRAZT(CHIPS)':
 'VSEN1': CDS_PINID='VSEN1';
NET_NAME
'SH_PVCCFA_EHV_FIVRA_CPU0'
 '@S9S_MB_2U_LIB.S9S_MB_2U(SCH_1):SH_PVCCFA_EHV_FIVRA_CPU0':
 C_SIGNAL='@s9s_mb_2u_lib.s9s_mb_2u(sch_1):sh_pvccfa_ehv_fivra_cpu0';
NODE_NAME     PJ53 2
 '@S9S_MB_2U_LIB.S9S_MB_2U(SCH_1):PAGE252_I24@PURE_QUANTA.Q_SHORT(CHIPS)':
 '2': CDS_PINID='\2\';
NODE_NAME     PR345 1
 '@S9S_MB_2U_LIB.S9S_MB_2U(SCH_1):PAGE252_I68@PURE_QUANTA.Q_RES(CHIPS)':
 'A': CDS_PINID='A';
NET_NAME
'SH_PVCCFA_EHV_FIVRA_CPU0_R'
 '@S9S_MB_2U_LIB.S9S_MB_2U(SCH_1):SH_PVCCFA_EHV_FIVRA_CPU0_R':
 C_SIGNAL='@s9s_mb_2u_lib.s9s_mb_2u(sch_1):sh_pvccfa_ehv_fivra_cpu0_r';
NODE_NAME     PU14 40
 '@S9S_MB_2U_LIB.S9S_MB_2U(SCH_1):PAGE252_I63@PURE_QUANTA.RAA229126GNPHA0(CHIPS)':
 'VSEN1': CDS_PINID='VSEN1';
NODE_NAME     PC594 1
 '@S9S_MB_2U_LIB.S9S_MB_2U(SCH_1):PAGE252_I67@PURE_QUANTA.Q_CAP(CHIPS)':
 'A': CDS_PINID='A';
NODE_NAME     PR345 2
 '@S9S_MB_2U_LIB.S9S_MB_2U(SCH_1):PAGE252_I68@PURE_QUANTA.Q_RES(CHIPS)':
 'B': CDS_PINID='B';
NET_NAME
'SH_PVCCFA_EHV_FIVRA_CPU1'
 '@S9S_MB_2U_LIB.S9S_MB_2U(SCH_1):SH_PVCCFA_EHV_FIVRA_CPU1':
 C_SIGNAL='@s9s_mb_2u_lib.s9s_mb_2u(sch_1):sh_pvccfa_ehv_fivra_cpu1';
NODE_NAME     PJ49 2
 '@S9S_MB_2U_LIB.S9S_MB_2U(SCH_1):PAGE270_I22@PURE_QUANTA.Q_SHORT(CHIPS)':
 '2': CDS_PINID='\2\';
NODE_NAME     PR242 1
 '@S9S_MB_2U_LIB.S9S_MB_2U(SCH_1):PAGE270_I37@PURE_QUANTA.Q_RES(CHIPS)':
 'A': CDS_PINID='A';
NET_NAME
'SH_PVCCFA_EHV_FIVRA_CPU1_R'
 '@S9S_MB_2U_LIB.S9S_MB_2U(SCH_1):SH_PVCCFA_EHV_FIVRA_CPU1_R':
 C_SIGNAL='@s9s_mb_2u_lib.s9s_mb_2u(sch_1):sh_pvccfa_ehv_fivra_cpu1_r';
NODE_NAME     PC422 1
 '@S9S_MB_2U_LIB.S9S_MB_2U(SCH_1):PAGE270_I38@PURE_QUANTA.Q_CAP(CHIPS)':
 'A': CDS_PINID='A';
NODE_NAME     PU29 40
 '@S9S_MB_2U_LIB.S9S_MB_2U(SCH_1):PAGE270_I33@PURE_QUANTA.RAA229126GNPHA0(CHIPS)':
 'VSEN1': CDS_PINID='VSEN1';
NODE_NAME     PR242 2
 '@S9S_MB_2U_LIB.S9S_MB_2U(SCH_1):PAGE270_I37@PURE_QUANTA.Q_RES(CHIPS)':
 'B': CDS_PINID='B';
NET_NAME
'SH_PVCCINFAON_CPU0'
 '@S9S_MB_2U_LIB.S9S_MB_2U(SCH_1):SH_PVCCINFAON_CPU0':
 C_SIGNAL='@s9s_mb_2u_lib.s9s_mb_2u(sch_1):sh_pvccinfaon_cpu0';
NODE_NAME     PJ45 2
 '@S9S_MB_2U_LIB.S9S_MB_2U(SCH_1):PAGE260_I43@PURE_QUANTA.Q_SHORT(CHIPS)':
 '2': CDS_PINID='\2\';
NODE_NAME     PR120 1
 '@S9S_MB_2U_LIB.S9S_MB_2U(SCH_1):PAGE260_I49@PURE_QUANTA.Q_RES(CHIPS)':
 'A': CDS_PINID='A';
NET_NAME
'SH_PVCCINFAON_CPU0_R'
 '@S9S_MB_2U_LIB.S9S_MB_2U(SCH_1):SH_PVCCINFAON_CPU0_R':
 C_SIGNAL='@s9s_mb_2u_lib.s9s_mb_2u(sch_1):sh_pvccinfaon_cpu0_r';
NODE_NAME     PU5 21
 '@S9S_MB_2U_LIB.S9S_MB_2U(SCH_1):PAGE260_I65@PURE_QUANTA.ISL69260IRAZT(CHIPS)':
 'VSEN0': CDS_PINID='VSEN0';
NODE_NAME     PC215 1
 '@S9S_MB_2U_LIB.S9S_MB_2U(SCH_1):PAGE260_I50@PURE_QUANTA.Q_CAP(CHIPS)':
 'A': CDS_PINID='A';
NODE_NAME     PR120 2
 '@S9S_MB_2U_LIB.S9S_MB_2U(SCH_1):PAGE260_I49@PURE_QUANTA.Q_RES(CHIPS)':
 'B': CDS_PINID='B';
NET_NAME
'SH_PVCCINFAON_CPU1'
 '@S9S_MB_2U_LIB.S9S_MB_2U(SCH_1):SH_PVCCINFAON_CPU1':
 C_SIGNAL='@s9s_mb_2u_lib.s9s_mb_2u(sch_1):sh_pvccinfaon_cpu1';
NODE_NAME     PJ50 2
 '@S9S_MB_2U_LIB.S9S_MB_2U(SCH_1):PAGE278_I54@PURE_QUANTA.Q_SHORT(CHIPS)':
 '2': CDS_PINID='\2\';
NODE_NAME     PR273 1
 '@S9S_MB_2U_LIB.S9S_MB_2U(SCH_1):PAGE278_I62@PURE_QUANTA.Q_RES(CHIPS)':
 'A': CDS_PINID='A';
NET_NAME
'SH_PVCCINFAON_CPU1_R'
 '@S9S_MB_2U_LIB.S9S_MB_2U(SCH_1):SH_PVCCINFAON_CPU1_R':
 C_SIGNAL='@s9s_mb_2u_lib.s9s_mb_2u(sch_1):sh_pvccinfaon_cpu1_r';
NODE_NAME     PC468 1
 '@S9S_MB_2U_LIB.S9S_MB_2U(SCH_1):PAGE278_I53@PURE_QUANTA.Q_CAP(CHIPS)':
 'A': CDS_PINID='A';
NODE_NAME     PR273 2
 '@S9S_MB_2U_LIB.S9S_MB_2U(SCH_1):PAGE278_I62@PURE_QUANTA.Q_RES(CHIPS)':
 'B': CDS_PINID='B';
NODE_NAME     PU22 21
 '@S9S_MB_2U_LIB.S9S_MB_2U(SCH_1):PAGE278_I38@PURE_QUANTA.ISL69260IRAZT(CHIPS)':
 'VSEN0': CDS_PINID='VSEN0';
NET_NAME
'SH_PVCCIN_CPU0'
 '@S9S_MB_2U_LIB.S9S_MB_2U(SCH_1):SH_PVCCIN_CPU0':
 C_SIGNAL='@s9s_mb_2u_lib.s9s_mb_2u(sch_1):sh_pvccin_cpu0';
NODE_NAME     PJ47 2
 '@S9S_MB_2U_LIB.S9S_MB_2U(SCH_1):PAGE252_I37@PURE_QUANTA.Q_SHORT(CHIPS)':
 '2': CDS_PINID='\2\';
NODE_NAME     PR170 1
 '@S9S_MB_2U_LIB.S9S_MB_2U(SCH_1):PAGE252_I77@PURE_QUANTA.Q_RES(CHIPS)':
 'A': CDS_PINID='A';
NET_NAME
'SH_PVCCIN_CPU0_R'
 '@S9S_MB_2U_LIB.S9S_MB_2U(SCH_1):SH_PVCCIN_CPU0_R':
 C_SIGNAL='@s9s_mb_2u_lib.s9s_mb_2u(sch_1):sh_pvccin_cpu0_r';
NODE_NAME     PU14 25
 '@S9S_MB_2U_LIB.S9S_MB_2U(SCH_1):PAGE252_I63@PURE_QUANTA.RAA229126GNPHA0(CHIPS)':
 'VSEN0': CDS_PINID='VSEN0';
NODE_NAME     PC331 1
 '@S9S_MB_2U_LIB.S9S_MB_2U(SCH_1):PAGE252_I79@PURE_QUANTA.Q_CAP(CHIPS)':
 'A': CDS_PINID='A';
NODE_NAME     PR170 2
 '@S9S_MB_2U_LIB.S9S_MB_2U(SCH_1):PAGE252_I77@PURE_QUANTA.Q_RES(CHIPS)':
 'B': CDS_PINID='B';
NET_NAME
'SH_PVCCIN_CPU1'
 '@S9S_MB_2U_LIB.S9S_MB_2U(SCH_1):SH_PVCCIN_CPU1':
 C_SIGNAL='@s9s_mb_2u_lib.s9s_mb_2u(sch_1):sh_pvccin_cpu1';
NODE_NAME     PR317 1
 '@S9S_MB_2U_LIB.S9S_MB_2U(SCH_1):PAGE270_I63@PURE_QUANTA.Q_RES(CHIPS)':
 'A': CDS_PINID='A';
NODE_NAME     PJ52 2
 '@S9S_MB_2U_LIB.S9S_MB_2U(SCH_1):PAGE270_I46@PURE_QUANTA.Q_SHORT(CHIPS)':
 '2': CDS_PINID='\2\';
NET_NAME
'SH_PVCCIN_CPU1_R'
 '@S9S_MB_2U_LIB.S9S_MB_2U(SCH_1):SH_PVCCIN_CPU1_R':
 C_SIGNAL='@s9s_mb_2u_lib.s9s_mb_2u(sch_1):sh_pvccin_cpu1_r';
NODE_NAME     PR317 2
 '@S9S_MB_2U_LIB.S9S_MB_2U(SCH_1):PAGE270_I63@PURE_QUANTA.Q_RES(CHIPS)':
 'B': CDS_PINID='B';
NODE_NAME     PC549 1
 '@S9S_MB_2U_LIB.S9S_MB_2U(SCH_1):PAGE270_I64@PURE_QUANTA.Q_CAP(CHIPS)':
 'A': CDS_PINID='A';
NODE_NAME     PU29 25
 '@S9S_MB_2U_LIB.S9S_MB_2U(SCH_1):PAGE270_I33@PURE_QUANTA.RAA229126GNPHA0(CHIPS)':
 'VSEN0': CDS_PINID='VSEN0';
NET_NAME
'SH_PVPP_HBM_CPU0_N'
 '@S9S_MB_2U_LIB.S9S_MB_2U(SCH_1):SH_PVPP_HBM_CPU0_N':
 C_SIGNAL='@s9s_mb_2u_lib.s9s_mb_2u(sch_1):sh_pvpp_hbm_cpu0_n';
NODE_NAME     PR1310 2
 '@S9S_MB_2U_LIB.S9S_MB_2U(SCH_1):PAGE267_I26@PURE_QUANTA.Q_RES(CHIPS)':
 'B': CDS_PINID='B';
NODE_NAME     PJ65 1
 '@S9S_MB_2U_LIB.S9S_MB_2U(SCH_1):PAGE267_I33@PURE_QUANTA.Q_SHORT(CHIPS)':
 '1': CDS_PINID='\1\';
NODE_NAME     PU173 S
 '@S9S_MB_2U_LIB.S9S_MB_2U(SCH_1):PAGE267_I31@PURE_QUANTA.MOSFET_N(CHIPS)':
 'SOURCE': CDS_PINID='SOURCE';
NODE_NAME     PU79 6
 '@S9S_MB_2U_LIB.S9S_MB_2U(SCH_1):PAGE267_I19@PURE_QUANTA.RS53318LR(CHIPS)':
 'RTN': CDS_PINID='RTN';
NODE_NAME     PC1251 2
 '@S9S_MB_2U_LIB.S9S_MB_2U(SCH_1):PAGE267_I25@PURE_QUANTA.Q_CAP(CHIPS)':
 'B': CDS_PINID='B';
NODE_NAME     PC1421 2
 '@S9S_MB_2U_LIB.S9S_MB_2U(SCH_1):PAGE267_I40@PURE_QUANTA.Q_CAP(CHIPS)':
 'B': CDS_PINID='B';
NET_NAME
'SH_PVPP_HBM_CPU0_P'
 '@S9S_MB_2U_LIB.S9S_MB_2U(SCH_1):SH_PVPP_HBM_CPU0_P':
 C_SIGNAL='@s9s_mb_2u_lib.s9s_mb_2u(sch_1):sh_pvpp_hbm_cpu0_p';
NODE_NAME     PR1337 2
 '@S9S_MB_2U_LIB.S9S_MB_2U(SCH_1):PAGE267_I36@PURE_QUANTA.Q_RES(CHIPS)':
 'B': CDS_PINID='B';
NODE_NAME     PC1253 2
 '@S9S_MB_2U_LIB.S9S_MB_2U(SCH_1):PAGE267_I35@PURE_QUANTA.Q_CAP(CHIPS)':
 'B': CDS_PINID='B';
NODE_NAME     PC1421 1
 '@S9S_MB_2U_LIB.S9S_MB_2U(SCH_1):PAGE267_I40@PURE_QUANTA.Q_CAP(CHIPS)':
 'A': CDS_PINID='A';
NODE_NAME     PJ64 1
 '@S9S_MB_2U_LIB.S9S_MB_2U(SCH_1):PAGE267_I41@PURE_QUANTA.Q_SHORT(CHIPS)':
 '1': CDS_PINID='\1\';
NET_NAME
'SH_PVPP_HBM_CPU1_N'
 '@S9S_MB_2U_LIB.S9S_MB_2U(SCH_1):SH_PVPP_HBM_CPU1_N':
 C_SIGNAL='@s9s_mb_2u_lib.s9s_mb_2u(sch_1):sh_pvpp_hbm_cpu1_n';
NODE_NAME     PC2282 2
 '@S9S_MB_2U_LIB.S9S_MB_2U(SCH_1):PAGE285_I32@PURE_QUANTA.Q_CAP(CHIPS)':
 'B': CDS_PINID='B';
NODE_NAME     PR1314 2
 '@S9S_MB_2U_LIB.S9S_MB_2U(SCH_1):PAGE285_I28@PURE_QUANTA.Q_RES(CHIPS)':
 'B': CDS_PINID='B';
NODE_NAME     PJ67 1
 '@S9S_MB_2U_LIB.S9S_MB_2U(SCH_1):PAGE285_I44@PURE_QUANTA.Q_SHORT(CHIPS)':
 '1': CDS_PINID='\1\';
NODE_NAME     PU80 6
 '@S9S_MB_2U_LIB.S9S_MB_2U(SCH_1):PAGE285_I25@PURE_QUANTA.RS53318LR(CHIPS)':
 'RTN': CDS_PINID='RTN';
NODE_NAME     PC1264 2
 '@S9S_MB_2U_LIB.S9S_MB_2U(SCH_1):PAGE285_I24@PURE_QUANTA.Q_CAP(CHIPS)':
 'B': CDS_PINID='B';
NODE_NAME     PU174 S
 '@S9S_MB_2U_LIB.S9S_MB_2U(SCH_1):PAGE285_I29@PURE_QUANTA.MOSFET_N(CHIPS)':
 'SOURCE': CDS_PINID='SOURCE';
NET_NAME
'SH_PVPP_HBM_CPU1_P'
 '@S9S_MB_2U_LIB.S9S_MB_2U(SCH_1):SH_PVPP_HBM_CPU1_P':
 C_SIGNAL='@s9s_mb_2u_lib.s9s_mb_2u(sch_1):sh_pvpp_hbm_cpu1_p';
NODE_NAME     PC2282 1
 '@S9S_MB_2U_LIB.S9S_MB_2U(SCH_1):PAGE285_I32@PURE_QUANTA.Q_CAP(CHIPS)':
 'A': CDS_PINID='A';
NODE_NAME     PR1340 2
 '@S9S_MB_2U_LIB.S9S_MB_2U(SCH_1):PAGE285_I34@PURE_QUANTA.Q_RES(CHIPS)':
 'B': CDS_PINID='B';
NODE_NAME     PJ66 1
 '@S9S_MB_2U_LIB.S9S_MB_2U(SCH_1):PAGE285_I46@PURE_QUANTA.Q_SHORT(CHIPS)':
 '1': CDS_PINID='\1\';
NODE_NAME     PC1266 2
 '@S9S_MB_2U_LIB.S9S_MB_2U(SCH_1):PAGE285_I35@PURE_QUANTA.Q_CAP(CHIPS)':
 'B': CDS_PINID='B';
NET_NAME
'SMB_1_BMC_GPU_BUF_R_SCL'
 '@S9S_MB_2U_LIB.S9S_MB_2U(SCH_1):SMB_1_BMC_GPU_BUF_R_SCL':
 C_SIGNAL='@s9s_mb_2u_lib.s9s_mb_2u(sch_1):smb_1_bmc_gpu_buf_r_scl';
NODE_NAME     R2893 2
 '@S9S_MB_2U_LIB.S9S_MB_2U(SCH_1):PAGE222_I38@PURE_QUANTA.Q_RES(CHIPS)':
 'B': CDS_PINID='B';
NODE_NAME     U194 2
 '@S9S_MB_2U_LIB.S9S_MB_2U(SCH_1):PAGE222_I63@PURE_QUANTA.LTC4307CMS8(CHIPS)':
 'SCL_OUT': CDS_PINID='SCL_OUT';
NODE_NAME     R2897 1
 '@S9S_MB_2U_LIB.S9S_MB_2U(SCH_1):PAGE222_I78@PURE_QUANTA.Q_RES(CHIPS)':
 'A': CDS_PINID='A';
NODE_NAME     R3523 2
 '@S9S_MB_2U_LIB.S9S_MB_2U(SCH_1):PAGE222_I80@PURE_QUANTA.Q_RES(CHIPS)':
 'B': CDS_PINID='B';
NET_NAME
'SMB_1_BMC_GPU_BUF_R_SDA'
 '@S9S_MB_2U_LIB.S9S_MB_2U(SCH_1):SMB_1_BMC_GPU_BUF_R_SDA':
 C_SIGNAL='@s9s_mb_2u_lib.s9s_mb_2u(sch_1):smb_1_bmc_gpu_buf_r_sda';
NODE_NAME     R2894 2
 '@S9S_MB_2U_LIB.S9S_MB_2U(SCH_1):PAGE222_I33@PURE_QUANTA.Q_RES(CHIPS)':
 'B': CDS_PINID='B';
NODE_NAME     U194 7
 '@S9S_MB_2U_LIB.S9S_MB_2U(SCH_1):PAGE222_I63@PURE_QUANTA.LTC4307CMS8(CHIPS)':
 'SDA_OUT': CDS_PINID='SDA_OUT';
NODE_NAME     R2898 1
 '@S9S_MB_2U_LIB.S9S_MB_2U(SCH_1):PAGE222_I79@PURE_QUANTA.Q_RES(CHIPS)':
 'A': CDS_PINID='A';
NODE_NAME     R3524 2
 '@S9S_MB_2U_LIB.S9S_MB_2U(SCH_1):PAGE222_I81@PURE_QUANTA.Q_RES(CHIPS)':
 'B': CDS_PINID='B';
NET_NAME
'SMB_1_BMC_GPU_BUF_SCL'
 '@S9S_MB_2U_LIB.S9S_MB_2U(SCH_1):SMB_1_BMC_GPU_BUF_SCL':
 C_SIGNAL='@s9s_mb_2u_lib.s9s_mb_2u(sch_1):smb_1_bmc_gpu_buf_scl';
NODE_NAME     J112 Q4
 '@S9S_MB_2U_LIB.S9S_MB_2U(SCH_1):PAGE149_I76@PURE_QUANTA.CONN160_10131762101LF(CHIPS)':
 'Q4': CDS_PINID='Q4';
NODE_NAME     R2897 2
 '@S9S_MB_2U_LIB.S9S_MB_2U(SCH_1):PAGE222_I78@PURE_QUANTA.Q_RES(CHIPS)':
 'B': CDS_PINID='B';
NET_NAME
'SMB_1_BMC_GPU_BUF_SDA'
 '@S9S_MB_2U_LIB.S9S_MB_2U(SCH_1):SMB_1_BMC_GPU_BUF_SDA':
 C_SIGNAL='@s9s_mb_2u_lib.s9s_mb_2u(sch_1):smb_1_bmc_gpu_buf_sda';
NODE_NAME     J112 R4
 '@S9S_MB_2U_LIB.S9S_MB_2U(SCH_1):PAGE149_I76@PURE_QUANTA.CONN160_10131762101LF(CHIPS)':
 'R4': CDS_PINID='R4';
NODE_NAME     R2898 2
 '@S9S_MB_2U_LIB.S9S_MB_2U(SCH_1):PAGE222_I79@PURE_QUANTA.Q_RES(CHIPS)':
 'B': CDS_PINID='B';
NET_NAME
'SMB_1_BMC_GPU_R_SCL'
 '@S9S_MB_2U_LIB.S9S_MB_2U(SCH_1):SMB_1_BMC_GPU_R_SCL':
 C_SIGNAL='@s9s_mb_2u_lib.s9s_mb_2u(sch_1):smb_1_bmc_gpu_r_scl';
NODE_NAME     R2893 1
 '@S9S_MB_2U_LIB.S9S_MB_2U(SCH_1):PAGE222_I38@PURE_QUANTA.Q_RES(CHIPS)':
 'A': CDS_PINID='A';
NODE_NAME     R3109 2
 '@S9S_MB_2U_LIB.S9S_MB_2U(SCH_1):PAGE222_I51@PURE_QUANTA.Q_RES(CHIPS)':
 'B': CDS_PINID='B';
NODE_NAME     U194 3
 '@S9S_MB_2U_LIB.S9S_MB_2U(SCH_1):PAGE222_I63@PURE_QUANTA.LTC4307CMS8(CHIPS)':
 'SCL_IN': CDS_PINID='SCL_IN';
NET_NAME
'SMB_1_BMC_GPU_R_SDA'
 '@S9S_MB_2U_LIB.S9S_MB_2U(SCH_1):SMB_1_BMC_GPU_R_SDA':
 C_SIGNAL='@s9s_mb_2u_lib.s9s_mb_2u(sch_1):smb_1_bmc_gpu_r_sda';
NODE_NAME     R2894 1
 '@S9S_MB_2U_LIB.S9S_MB_2U(SCH_1):PAGE222_I33@PURE_QUANTA.Q_RES(CHIPS)':
 'A': CDS_PINID='A';
NODE_NAME     R3110 2
 '@S9S_MB_2U_LIB.S9S_MB_2U(SCH_1):PAGE222_I52@PURE_QUANTA.Q_RES(CHIPS)':
 'B': CDS_PINID='B';
NODE_NAME     U194 6
 '@S9S_MB_2U_LIB.S9S_MB_2U(SCH_1):PAGE222_I63@PURE_QUANTA.LTC4307CMS8(CHIPS)':
 'SDA_IN': CDS_PINID='SDA_IN';
NET_NAME
'SMB_1_BMC_GPU_SCL'
 '@S9S_MB_2U_LIB.S9S_MB_2U(SCH_1):SMB_1_BMC_GPU_SCL':
 C_SIGNAL='@s9s_mb_2u_lib.s9s_mb_2u(sch_1):smb_1_bmc_gpu_scl';
NODE_NAME     R3226 1
 '@S9S_MB_2U_LIB.S9S_MB_2U(SCH_1):PAGE228_I251@PURE_QUANTA.Q_RES(CHIPS)':
 'A': CDS_PINID='A';
NODE_NAME     R3109 1
 '@S9S_MB_2U_LIB.S9S_MB_2U(SCH_1):PAGE222_I51@PURE_QUANTA.Q_RES(CHIPS)':
 'A': CDS_PINID='A';
NODE_NAME     R2415 1
 '@S9S_MB_2U_LIB.S9S_MB_2U(SCH_1):PAGE227_I25@PURE_QUANTA.Q_RES(CHIPS)':
 'A': CDS_PINID='A';
NET_NAME
'SMB_1_BMC_GPU_SDA'
 '@S9S_MB_2U_LIB.S9S_MB_2U(SCH_1):SMB_1_BMC_GPU_SDA':
 C_SIGNAL='@s9s_mb_2u_lib.s9s_mb_2u(sch_1):smb_1_bmc_gpu_sda';
NODE_NAME     R3227 1
 '@S9S_MB_2U_LIB.S9S_MB_2U(SCH_1):PAGE228_I250@PURE_QUANTA.Q_RES(CHIPS)':
 'A': CDS_PINID='A';
NODE_NAME     R3110 1
 '@S9S_MB_2U_LIB.S9S_MB_2U(SCH_1):PAGE222_I52@PURE_QUANTA.Q_RES(CHIPS)':
 'A': CDS_PINID='A';
NODE_NAME     R2416 1
 '@S9S_MB_2U_LIB.S9S_MB_2U(SCH_1):PAGE227_I24@PURE_QUANTA.Q_RES(CHIPS)':
 'A': CDS_PINID='A';
NET_NAME
'SMB_1_PLD_3V3AUX_SCL'
 '@S9S_MB_2U_LIB.S9S_MB_2U(SCH_1):SMB_1_PLD_3V3AUX_SCL':
 C_SIGNAL='@s9s_mb_2u_lib.s9s_mb_2u(sch_1):smb_1_pld_3v3aux_scl';
NODE_NAME     R4149 1
 '@S9S_MB_2U_LIB.S9S_MB_2U(SCH_1):PAGE228_I272@PURE_QUANTA.Q_RES(CHIPS)':
 'A': CDS_PINID='A';
NODE_NAME     R4151 1
 '@S9S_MB_2U_LIB.S9S_MB_2U(SCH_1):PAGE228_I274@PURE_QUANTA.Q_RES(CHIPS)':
 'A': CDS_PINID='A';
NODE_NAME     R4508 1
 '@S9S_MB_2U_LIB.S9S_MB_2U(SCH_1):PAGE227_I87@PURE_QUANTA.Q_RES(CHIPS)':
 'A': CDS_PINID='A';
NET_NAME
'SMB_1_PLD_3V3AUX_SCL_R1'
 '@S9S_MB_2U_LIB.S9S_MB_2U(SCH_1):SMB_1_PLD_3V3AUX_SCL_R1':
 C_SIGNAL='@s9s_mb_2u_lib.s9s_mb_2u(sch_1):smb_1_pld_3v3aux_scl_r1';
NODE_NAME     R4149 2
 '@S9S_MB_2U_LIB.S9S_MB_2U(SCH_1):PAGE228_I272@PURE_QUANTA.Q_RES(CHIPS)':
 'B': CDS_PINID='B';
NODE_NAME     R1467 2
 '@S9S_MB_2U_LIB.S9S_MB_2U(SCH_1):PAGE314_I178@PURE_QUANTA.Q_RES(CHIPS)':
 'B': CDS_PINID='B';
NODE_NAME     U249 B12
 '@S9S_MB_2U_LIB.S9S_MB_2U(SCH_1):PAGE314_I188@PURE_QUANTA.LCMXO3LF9400C5BG484C(CHIPS)':
 'PT27C||SCL||PCLKT0_0': CDS_PINID='\pt27c||scl||pclkt0_0\';
NET_NAME
'SMB_1_PLD_3V3AUX_SCL_R3'
 '@S9S_MB_2U_LIB.S9S_MB_2U(SCH_1):SMB_1_PLD_3V3AUX_SCL_R3':
 C_SIGNAL='@s9s_mb_2u_lib.s9s_mb_2u(sch_1):smb_1_pld_3v3aux_scl_r3';
NODE_NAME     R4508 2
 '@S9S_MB_2U_LIB.S9S_MB_2U(SCH_1):PAGE227_I87@PURE_QUANTA.Q_RES(CHIPS)':
 'B': CDS_PINID='B';
NODE_NAME     J41 A27
 '@S9S_MB_2U_LIB.S9S_MB_2U(SCH_1):PAGE227_I173@PURE_QUANTA.SCONN168_ME1016810202011(CHIPS)':
 'PERP3': CDS_PINID='PERP3';
NET_NAME
'SMB_1_PLD_3V3AUX_SDA'
 '@S9S_MB_2U_LIB.S9S_MB_2U(SCH_1):SMB_1_PLD_3V3AUX_SDA':
 C_SIGNAL='@s9s_mb_2u_lib.s9s_mb_2u(sch_1):smb_1_pld_3v3aux_sda';
NODE_NAME     R4150 1
 '@S9S_MB_2U_LIB.S9S_MB_2U(SCH_1):PAGE228_I271@PURE_QUANTA.Q_RES(CHIPS)':
 'A': CDS_PINID='A';
NODE_NAME     R4152 1
 '@S9S_MB_2U_LIB.S9S_MB_2U(SCH_1):PAGE228_I273@PURE_QUANTA.Q_RES(CHIPS)':
 'A': CDS_PINID='A';
NODE_NAME     R4509 1
 '@S9S_MB_2U_LIB.S9S_MB_2U(SCH_1):PAGE227_I88@PURE_QUANTA.Q_RES(CHIPS)':
 'A': CDS_PINID='A';
NET_NAME
'SMB_1_PLD_3V3AUX_SDA_R1'
 '@S9S_MB_2U_LIB.S9S_MB_2U(SCH_1):SMB_1_PLD_3V3AUX_SDA_R1':
 C_SIGNAL='@s9s_mb_2u_lib.s9s_mb_2u(sch_1):smb_1_pld_3v3aux_sda_r1';
NODE_NAME     R4150 2
 '@S9S_MB_2U_LIB.S9S_MB_2U(SCH_1):PAGE228_I271@PURE_QUANTA.Q_RES(CHIPS)':
 'B': CDS_PINID='B';
NODE_NAME     R1551 2
 '@S9S_MB_2U_LIB.S9S_MB_2U(SCH_1):PAGE314_I179@PURE_QUANTA.Q_RES(CHIPS)':
 'B': CDS_PINID='B';
NODE_NAME     U249 A12
 '@S9S_MB_2U_LIB.S9S_MB_2U(SCH_1):PAGE314_I188@PURE_QUANTA.LCMXO3LF9400C5BG484C(CHIPS)':
 'PT27D||SDA||PCLKC0_0': CDS_PINID='\pt27d||sda||pclkc0_0\';
NET_NAME
'SMB_1_PLD_3V3AUX_SDA_R3'
 '@S9S_MB_2U_LIB.S9S_MB_2U(SCH_1):SMB_1_PLD_3V3AUX_SDA_R3':
 C_SIGNAL='@s9s_mb_2u_lib.s9s_mb_2u(sch_1):smb_1_pld_3v3aux_sda_r3';
NODE_NAME     R4509 2
 '@S9S_MB_2U_LIB.S9S_MB_2U(SCH_1):PAGE227_I88@PURE_QUANTA.Q_RES(CHIPS)':
 'B': CDS_PINID='B';
NODE_NAME     J41 A28
 '@S9S_MB_2U_LIB.S9S_MB_2U(SCH_1):PAGE227_I173@PURE_QUANTA.SCONN168_ME1016810202011(CHIPS)':
 'GND_A28': CDS_PINID='GND_A28';
NET_NAME
'SMB_2_BMC_GPU_BUF_R_SCL'
 '@S9S_MB_2U_LIB.S9S_MB_2U(SCH_1):SMB_2_BMC_GPU_BUF_R_SCL':
 C_SIGNAL='@s9s_mb_2u_lib.s9s_mb_2u(sch_1):smb_2_bmc_gpu_buf_r_scl';
NODE_NAME     U200 2
 '@S9S_MB_2U_LIB.S9S_MB_2U(SCH_1):PAGE222_I11@PURE_QUANTA.LTC4307CMS8(CHIPS)':
 'SCL_OUT': CDS_PINID='SCL_OUT';
NODE_NAME     R2986 2
 '@S9S_MB_2U_LIB.S9S_MB_2U(SCH_1):PAGE222_I13@PURE_QUANTA.Q_RES(CHIPS)':
 'B': CDS_PINID='B';
NODE_NAME     R3521 2
 '@S9S_MB_2U_LIB.S9S_MB_2U(SCH_1):PAGE222_I23@PURE_QUANTA.Q_RES(CHIPS)':
 'B': CDS_PINID='B';
NODE_NAME     R2990 1
 '@S9S_MB_2U_LIB.S9S_MB_2U(SCH_1):PAGE222_I26@PURE_QUANTA.Q_RES(CHIPS)':
 'A': CDS_PINID='A';
NET_NAME
'SMB_2_BMC_GPU_BUF_R_SDA'
 '@S9S_MB_2U_LIB.S9S_MB_2U(SCH_1):SMB_2_BMC_GPU_BUF_R_SDA':
 C_SIGNAL='@s9s_mb_2u_lib.s9s_mb_2u(sch_1):smb_2_bmc_gpu_buf_r_sda';
NODE_NAME     R2987 2
 '@S9S_MB_2U_LIB.S9S_MB_2U(SCH_1):PAGE222_I12@PURE_QUANTA.Q_RES(CHIPS)':
 'B': CDS_PINID='B';
NODE_NAME     U200 7
 '@S9S_MB_2U_LIB.S9S_MB_2U(SCH_1):PAGE222_I11@PURE_QUANTA.LTC4307CMS8(CHIPS)':
 'SDA_OUT': CDS_PINID='SDA_OUT';
NODE_NAME     R3522 2
 '@S9S_MB_2U_LIB.S9S_MB_2U(SCH_1):PAGE222_I25@PURE_QUANTA.Q_RES(CHIPS)':
 'B': CDS_PINID='B';
NODE_NAME     R2991 1
 '@S9S_MB_2U_LIB.S9S_MB_2U(SCH_1):PAGE222_I27@PURE_QUANTA.Q_RES(CHIPS)':
 'A': CDS_PINID='A';
NET_NAME
'SMB_2_BMC_GPU_BUF_SCL'
 '@S9S_MB_2U_LIB.S9S_MB_2U(SCH_1):SMB_2_BMC_GPU_BUF_SCL':
 C_SIGNAL='@s9s_mb_2u_lib.s9s_mb_2u(sch_1):smb_2_bmc_gpu_buf_scl';
NODE_NAME     J112 R3
 '@S9S_MB_2U_LIB.S9S_MB_2U(SCH_1):PAGE149_I76@PURE_QUANTA.CONN160_10131762101LF(CHIPS)':
 'R3': CDS_PINID='R3';
NODE_NAME     R2990 2
 '@S9S_MB_2U_LIB.S9S_MB_2U(SCH_1):PAGE222_I26@PURE_QUANTA.Q_RES(CHIPS)':
 'B': CDS_PINID='B';
NET_NAME
'SMB_2_BMC_GPU_BUF_SDA'
 '@S9S_MB_2U_LIB.S9S_MB_2U(SCH_1):SMB_2_BMC_GPU_BUF_SDA':
 C_SIGNAL='@s9s_mb_2u_lib.s9s_mb_2u(sch_1):smb_2_bmc_gpu_buf_sda';
NODE_NAME     J112 S3
 '@S9S_MB_2U_LIB.S9S_MB_2U(SCH_1):PAGE149_I76@PURE_QUANTA.CONN160_10131762101LF(CHIPS)':
 'S3': CDS_PINID='S3';
NODE_NAME     R2991 2
 '@S9S_MB_2U_LIB.S9S_MB_2U(SCH_1):PAGE222_I27@PURE_QUANTA.Q_RES(CHIPS)':
 'B': CDS_PINID='B';
NET_NAME
'SMB_2_BMC_GPU_R_SCL'
 '@S9S_MB_2U_LIB.S9S_MB_2U(SCH_1):SMB_2_BMC_GPU_R_SCL':
 C_SIGNAL='@s9s_mb_2u_lib.s9s_mb_2u(sch_1):smb_2_bmc_gpu_r_scl';
NODE_NAME     R3107 2
 '@S9S_MB_2U_LIB.S9S_MB_2U(SCH_1):PAGE222_I8@PURE_QUANTA.Q_RES(CHIPS)':
 'B': CDS_PINID='B';
NODE_NAME     U200 3
 '@S9S_MB_2U_LIB.S9S_MB_2U(SCH_1):PAGE222_I11@PURE_QUANTA.LTC4307CMS8(CHIPS)':
 'SCL_IN': CDS_PINID='SCL_IN';
NODE_NAME     R2986 1
 '@S9S_MB_2U_LIB.S9S_MB_2U(SCH_1):PAGE222_I13@PURE_QUANTA.Q_RES(CHIPS)':
 'A': CDS_PINID='A';
NET_NAME
'SMB_2_BMC_GPU_R_SDA'
 '@S9S_MB_2U_LIB.S9S_MB_2U(SCH_1):SMB_2_BMC_GPU_R_SDA':
 C_SIGNAL='@s9s_mb_2u_lib.s9s_mb_2u(sch_1):smb_2_bmc_gpu_r_sda';
NODE_NAME     R2987 1
 '@S9S_MB_2U_LIB.S9S_MB_2U(SCH_1):PAGE222_I12@PURE_QUANTA.Q_RES(CHIPS)':
 'A': CDS_PINID='A';
NODE_NAME     R3108 2
 '@S9S_MB_2U_LIB.S9S_MB_2U(SCH_1):PAGE222_I7@PURE_QUANTA.Q_RES(CHIPS)':
 'B': CDS_PINID='B';
NODE_NAME     U200 6
 '@S9S_MB_2U_LIB.S9S_MB_2U(SCH_1):PAGE222_I11@PURE_QUANTA.LTC4307CMS8(CHIPS)':
 'SDA_IN': CDS_PINID='SDA_IN';
NET_NAME
'SMB_2_BMC_GPU_SCL'
 '@S9S_MB_2U_LIB.S9S_MB_2U(SCH_1):SMB_2_BMC_GPU_SCL':
 C_SIGNAL='@s9s_mb_2u_lib.s9s_mb_2u(sch_1):smb_2_bmc_gpu_scl';
NODE_NAME     R2999 1
 '@S9S_MB_2U_LIB.S9S_MB_2U(SCH_1):PAGE228_I231@PURE_QUANTA.Q_RES(CHIPS)':
 'A': CDS_PINID='A';
NODE_NAME     R3107 1
 '@S9S_MB_2U_LIB.S9S_MB_2U(SCH_1):PAGE222_I8@PURE_QUANTA.Q_RES(CHIPS)':
 'A': CDS_PINID='A';
NODE_NAME     R2413 1
 '@S9S_MB_2U_LIB.S9S_MB_2U(SCH_1):PAGE227_I86@PURE_QUANTA.Q_RES(CHIPS)':
 'A': CDS_PINID='A';
NET_NAME
'SMB_2_BMC_GPU_SDA'
 '@S9S_MB_2U_LIB.S9S_MB_2U(SCH_1):SMB_2_BMC_GPU_SDA':
 C_SIGNAL='@s9s_mb_2u_lib.s9s_mb_2u(sch_1):smb_2_bmc_gpu_sda';
NODE_NAME     R3004 1
 '@S9S_MB_2U_LIB.S9S_MB_2U(SCH_1):PAGE228_I230@PURE_QUANTA.Q_RES(CHIPS)':
 'A': CDS_PINID='A';
NODE_NAME     R3108 1
 '@S9S_MB_2U_LIB.S9S_MB_2U(SCH_1):PAGE222_I7@PURE_QUANTA.Q_RES(CHIPS)':
 'A': CDS_PINID='A';
NODE_NAME     R2414 1
 '@S9S_MB_2U_LIB.S9S_MB_2U(SCH_1):PAGE227_I85@PURE_QUANTA.Q_RES(CHIPS)':
 'A': CDS_PINID='A';
NET_NAME
'SMB_2_PLD_3V3AUX_SCL_R1'
 '@S9S_MB_2U_LIB.S9S_MB_2U(SCH_1):SMB_2_PLD_3V3AUX_SCL_R1':
 C_SIGNAL='@s9s_mb_2u_lib.s9s_mb_2u(sch_1):smb_2_pld_3v3aux_scl_r1';
NODE_NAME     U249 M22
 '@S9S_MB_2U_LIB.S9S_MB_2U(SCH_1):PAGE313_I1@PURE_QUANTA.LCMXO3LF9400C5BG484C(CHIPS)':
 'PR17A||PCLKT1_0': CDS_PINID='\pr17a||pclkt1_0\';
NODE_NAME     R4151 2
 '@S9S_MB_2U_LIB.S9S_MB_2U(SCH_1):PAGE228_I274@PURE_QUANTA.Q_RES(CHIPS)':
 'B': CDS_PINID='B';
NET_NAME
'SMB_2_PLD_3V3AUX_SDA_R1'
 '@S9S_MB_2U_LIB.S9S_MB_2U(SCH_1):SMB_2_PLD_3V3AUX_SDA_R1':
 C_SIGNAL='@s9s_mb_2u_lib.s9s_mb_2u(sch_1):smb_2_pld_3v3aux_sda_r1';
NODE_NAME     U249 M21
 '@S9S_MB_2U_LIB.S9S_MB_2U(SCH_1):PAGE313_I1@PURE_QUANTA.LCMXO3LF9400C5BG484C(CHIPS)':
 'PR17B||PCLKC1_0': CDS_PINID='\pr17b||pclkc1_0\';
NODE_NAME     R4152 2
 '@S9S_MB_2U_LIB.S9S_MB_2U(SCH_1):PAGE228_I273@PURE_QUANTA.Q_RES(CHIPS)':
 'B': CDS_PINID='B';
NET_NAME
'SMB_BMC_GPU_EN'
 '@S9S_MB_2U_LIB.S9S_MB_2U(SCH_1):SMB_BMC_GPU_EN':
 C_SIGNAL='@s9s_mb_2u_lib.s9s_mb_2u(sch_1):smb_bmc_gpu_en';
NODE_NAME     U249 G8
 '@S9S_MB_2U_LIB.S9S_MB_2U(SCH_1):PAGE314_I188@PURE_QUANTA.LCMXO3LF9400C5BG484C(CHIPS)':
 'PT11D': CDS_PINID='PT11D';
NODE_NAME     R2992 1
 '@S9S_MB_2U_LIB.S9S_MB_2U(SCH_1):PAGE222_I9@PURE_QUANTA.Q_RES(CHIPS)':
 'A': CDS_PINID='A';
NODE_NAME     R4603 1
 '@S9S_MB_2U_LIB.S9S_MB_2U(SCH_1):PAGE222_I48@PURE_QUANTA.Q_RES(CHIPS)':
 'A': CDS_PINID='A';
NODE_NAME     R2899 1
 '@S9S_MB_2U_LIB.S9S_MB_2U(SCH_1):PAGE222_I53@PURE_QUANTA.Q_RES(CHIPS)':
 'A': CDS_PINID='A';
NET_NAME
'SMB_BMC_GPU_EN_R1'
 '@S9S_MB_2U_LIB.S9S_MB_2U(SCH_1):SMB_BMC_GPU_EN_R1':
 C_SIGNAL='@s9s_mb_2u_lib.s9s_mb_2u(sch_1):smb_bmc_gpu_en_r1';
NODE_NAME     R2899 2
 '@S9S_MB_2U_LIB.S9S_MB_2U(SCH_1):PAGE222_I53@PURE_QUANTA.Q_RES(CHIPS)':
 'B': CDS_PINID='B';
NODE_NAME     U194 1
 '@S9S_MB_2U_LIB.S9S_MB_2U(SCH_1):PAGE222_I63@PURE_QUANTA.LTC4307CMS8(CHIPS)':
 'ENABLE': CDS_PINID='ENABLE';
NET_NAME
'SMB_BMC_GPU_EN_R3'
 '@S9S_MB_2U_LIB.S9S_MB_2U(SCH_1):SMB_BMC_GPU_EN_R3':
 C_SIGNAL='@s9s_mb_2u_lib.s9s_mb_2u(sch_1):smb_bmc_gpu_en_r3';
NODE_NAME     R2992 2
 '@S9S_MB_2U_LIB.S9S_MB_2U(SCH_1):PAGE222_I9@PURE_QUANTA.Q_RES(CHIPS)':
 'B': CDS_PINID='B';
NODE_NAME     U200 1
 '@S9S_MB_2U_LIB.S9S_MB_2U(SCH_1):PAGE222_I11@PURE_QUANTA.LTC4307CMS8(CHIPS)':
 'ENABLE': CDS_PINID='ENABLE';
NET_NAME
'SMB_BMC_SWB_BUF_R_SCL'
 '@S9S_MB_2U_LIB.S9S_MB_2U(SCH_1):SMB_BMC_SWB_BUF_R_SCL':
 C_SIGNAL='@s9s_mb_2u_lib.s9s_mb_2u(sch_1):smb_bmc_swb_buf_r_scl';
NODE_NAME     R2705 2
 '@S9S_MB_2U_LIB.S9S_MB_2U(SCH_1):PAGE222_I55@PURE_QUANTA.Q_RES(CHIPS)':
 'B': CDS_PINID='B';
NODE_NAME     R2671 1
 '@S9S_MB_2U_LIB.S9S_MB_2U(SCH_1):PAGE222_I65@PURE_QUANTA.Q_RES(CHIPS)':
 'A': CDS_PINID='A';
NODE_NAME     U175 2
 '@S9S_MB_2U_LIB.S9S_MB_2U(SCH_1):PAGE222_I50@PURE_QUANTA.LTC4307CMS8(CHIPS)':
 'SCL_OUT': CDS_PINID='SCL_OUT';
NODE_NAME     R2667 2
 '@S9S_MB_2U_LIB.S9S_MB_2U(SCH_1):PAGE222_I59@PURE_QUANTA.Q_RES(CHIPS)':
 'B': CDS_PINID='B';
NET_NAME
'SMB_BMC_SWB_BUF_R_SDA'
 '@S9S_MB_2U_LIB.S9S_MB_2U(SCH_1):SMB_BMC_SWB_BUF_R_SDA':
 C_SIGNAL='@s9s_mb_2u_lib.s9s_mb_2u(sch_1):smb_bmc_swb_buf_r_sda';
NODE_NAME     R2724 2
 '@S9S_MB_2U_LIB.S9S_MB_2U(SCH_1):PAGE222_I54@PURE_QUANTA.Q_RES(CHIPS)':
 'B': CDS_PINID='B';
NODE_NAME     U175 7
 '@S9S_MB_2U_LIB.S9S_MB_2U(SCH_1):PAGE222_I50@PURE_QUANTA.LTC4307CMS8(CHIPS)':
 'SDA_OUT': CDS_PINID='SDA_OUT';
NODE_NAME     R2669 2
 '@S9S_MB_2U_LIB.S9S_MB_2U(SCH_1):PAGE222_I61@PURE_QUANTA.Q_RES(CHIPS)':
 'B': CDS_PINID='B';
NODE_NAME     R2672 1
 '@S9S_MB_2U_LIB.S9S_MB_2U(SCH_1):PAGE222_I64@PURE_QUANTA.Q_RES(CHIPS)':
 'A': CDS_PINID='A';
NET_NAME
'SMB_BMC_SWB_BUF_SCL'
 '@S9S_MB_2U_LIB.S9S_MB_2U(SCH_1):SMB_BMC_SWB_BUF_SCL':
 C_SIGNAL='@s9s_mb_2u_lib.s9s_mb_2u(sch_1):smb_bmc_swb_buf_scl';
NODE_NAME     R2671 2
 '@S9S_MB_2U_LIB.S9S_MB_2U(SCH_1):PAGE222_I65@PURE_QUANTA.Q_RES(CHIPS)':
 'B': CDS_PINID='B';
NODE_NAME     J109 A5
 '@S9S_MB_2U_LIB.S9S_MB_2U(SCH_1):PAGE319_I76@PURE_QUANTA.CONN112_10137002101LF(CHIPS)':
 'A5': CDS_PINID='A5';
NET_NAME
'SMB_BMC_SWB_BUF_SDA'
 '@S9S_MB_2U_LIB.S9S_MB_2U(SCH_1):SMB_BMC_SWB_BUF_SDA':
 C_SIGNAL='@s9s_mb_2u_lib.s9s_mb_2u(sch_1):smb_bmc_swb_buf_sda';
NODE_NAME     J109 A7
 '@S9S_MB_2U_LIB.S9S_MB_2U(SCH_1):PAGE319_I76@PURE_QUANTA.CONN112_10137002101LF(CHIPS)':
 'A7': CDS_PINID='A7';
NODE_NAME     R2672 2
 '@S9S_MB_2U_LIB.S9S_MB_2U(SCH_1):PAGE222_I64@PURE_QUANTA.Q_RES(CHIPS)':
 'B': CDS_PINID='B';
NET_NAME
'SMB_BMC_SWB_EN'
 '@S9S_MB_2U_LIB.S9S_MB_2U(SCH_1):SMB_BMC_SWB_EN':
 C_SIGNAL='@s9s_mb_2u_lib.s9s_mb_2u(sch_1):smb_bmc_swb_en';
NODE_NAME     R2666 1
 '@S9S_MB_2U_LIB.S9S_MB_2U(SCH_1):PAGE222_I16@PURE_QUANTA.Q_RES(CHIPS)':
 'A': CDS_PINID='A';
NODE_NAME     U249 A4
 '@S9S_MB_2U_LIB.S9S_MB_2U(SCH_1):PAGE314_I188@PURE_QUANTA.LCMXO3LF9400C5BG484C(CHIPS)':
 'PT11B': CDS_PINID='PT11B';
NODE_NAME     R2676 1
 '@S9S_MB_2U_LIB.S9S_MB_2U(SCH_1):PAGE222_I19@PURE_QUANTA.Q_RES(CHIPS)':
 'A': CDS_PINID='A';
NODE_NAME     R2707 1
 '@S9S_MB_2U_LIB.S9S_MB_2U(SCH_1):PAGE222_I44@PURE_QUANTA.Q_RES(CHIPS)':
 'A': CDS_PINID='A';
NET_NAME
'SMB_BMC_SWB_EN_R'
 '@S9S_MB_2U_LIB.S9S_MB_2U(SCH_1):SMB_BMC_SWB_EN_R':
 C_SIGNAL='@s9s_mb_2u_lib.s9s_mb_2u(sch_1):smb_bmc_swb_en_r';
NODE_NAME     R2707 2
 '@S9S_MB_2U_LIB.S9S_MB_2U(SCH_1):PAGE222_I44@PURE_QUANTA.Q_RES(CHIPS)':
 'B': CDS_PINID='B';
NODE_NAME     U175 1
 '@S9S_MB_2U_LIB.S9S_MB_2U(SCH_1):PAGE222_I50@PURE_QUANTA.LTC4307CMS8(CHIPS)':
 'ENABLE': CDS_PINID='ENABLE';
NET_NAME
'SMB_BMC_SWB_EN_R2'
 '@S9S_MB_2U_LIB.S9S_MB_2U(SCH_1):SMB_BMC_SWB_EN_R2':
 C_SIGNAL='@s9s_mb_2u_lib.s9s_mb_2u(sch_1):smb_bmc_swb_en_r2';
NODE_NAME     R2676 2
 '@S9S_MB_2U_LIB.S9S_MB_2U(SCH_1):PAGE222_I19@PURE_QUANTA.Q_RES(CHIPS)':
 'B': CDS_PINID='B';
NODE_NAME     U176 1
 '@S9S_MB_2U_LIB.S9S_MB_2U(SCH_1):PAGE222_I31@PURE_QUANTA.LTC4307CMS8(CHIPS)':
 'ENABLE': CDS_PINID='ENABLE';
NET_NAME
'SMB_BMC_SWB_R_SCL'
 '@S9S_MB_2U_LIB.S9S_MB_2U(SCH_1):SMB_BMC_SWB_R_SCL':
 C_SIGNAL='@s9s_mb_2u_lib.s9s_mb_2u(sch_1):smb_bmc_swb_r_scl';
NODE_NAME     R2705 1
 '@S9S_MB_2U_LIB.S9S_MB_2U(SCH_1):PAGE222_I55@PURE_QUANTA.Q_RES(CHIPS)':
 'A': CDS_PINID='A';
NODE_NAME     R3105 2
 '@S9S_MB_2U_LIB.S9S_MB_2U(SCH_1):PAGE222_I43@PURE_QUANTA.Q_RES(CHIPS)':
 'B': CDS_PINID='B';
NODE_NAME     U175 3
 '@S9S_MB_2U_LIB.S9S_MB_2U(SCH_1):PAGE222_I50@PURE_QUANTA.LTC4307CMS8(CHIPS)':
 'SCL_IN': CDS_PINID='SCL_IN';
NET_NAME
'SMB_BMC_SWB_R_SDA'
 '@S9S_MB_2U_LIB.S9S_MB_2U(SCH_1):SMB_BMC_SWB_R_SDA':
 C_SIGNAL='@s9s_mb_2u_lib.s9s_mb_2u(sch_1):smb_bmc_swb_r_sda';
NODE_NAME     R2724 1
 '@S9S_MB_2U_LIB.S9S_MB_2U(SCH_1):PAGE222_I54@PURE_QUANTA.Q_RES(CHIPS)':
 'A': CDS_PINID='A';
NODE_NAME     R3106 2
 '@S9S_MB_2U_LIB.S9S_MB_2U(SCH_1):PAGE222_I42@PURE_QUANTA.Q_RES(CHIPS)':
 'B': CDS_PINID='B';
NODE_NAME     U175 6
 '@S9S_MB_2U_LIB.S9S_MB_2U(SCH_1):PAGE222_I50@PURE_QUANTA.LTC4307CMS8(CHIPS)':
 'SDA_IN': CDS_PINID='SDA_IN';
NET_NAME
'SMB_BMC_SWB_SCL'
 '@S9S_MB_2U_LIB.S9S_MB_2U(SCH_1):SMB_BMC_SWB_SCL':
 C_SIGNAL='@s9s_mb_2u_lib.s9s_mb_2u(sch_1):smb_bmc_swb_scl';
NODE_NAME     R3105 1
 '@S9S_MB_2U_LIB.S9S_MB_2U(SCH_1):PAGE222_I43@PURE_QUANTA.Q_RES(CHIPS)':
 'A': CDS_PINID='A';
NODE_NAME     R2984 2
 '@S9S_MB_2U_LIB.S9S_MB_2U(SCH_1):PAGE219_I25@PURE_QUANTA.Q_RES(CHIPS)':
 'B': CDS_PINID='B';
NODE_NAME     R2703 2
 '@S9S_MB_2U_LIB.S9S_MB_2U(SCH_1):PAGE219_I63@PURE_QUANTA.Q_RES(CHIPS)':
 'B': CDS_PINID='B';
NET_NAME
'SMB_BMC_SWB_SCL_R4'
 '@S9S_MB_2U_LIB.S9S_MB_2U(SCH_1):SMB_BMC_SWB_SCL_R4':
 C_SIGNAL='@s9s_mb_2u_lib.s9s_mb_2u(sch_1):smb_bmc_swb_scl_r4';
NODE_NAME     U36 14
 '@S9S_MB_2U_LIB.S9S_MB_2U(SCH_1):PAGE219_I45@PURE_QUANTA.TCA9548APWR(CHIPS)':
 'SC4': CDS_PINID='SC4';
NODE_NAME     R2703 1
 '@S9S_MB_2U_LIB.S9S_MB_2U(SCH_1):PAGE219_I63@PURE_QUANTA.Q_RES(CHIPS)':
 'A': CDS_PINID='A';
NET_NAME
'SMB_BMC_SWB_SDA'
 '@S9S_MB_2U_LIB.S9S_MB_2U(SCH_1):SMB_BMC_SWB_SDA':
 C_SIGNAL='@s9s_mb_2u_lib.s9s_mb_2u(sch_1):smb_bmc_swb_sda';
NODE_NAME     R3106 1
 '@S9S_MB_2U_LIB.S9S_MB_2U(SCH_1):PAGE222_I42@PURE_QUANTA.Q_RES(CHIPS)':
 'A': CDS_PINID='A';
NODE_NAME     R2985 2
 '@S9S_MB_2U_LIB.S9S_MB_2U(SCH_1):PAGE219_I24@PURE_QUANTA.Q_RES(CHIPS)':
 'B': CDS_PINID='B';
NODE_NAME     R2704 2
 '@S9S_MB_2U_LIB.S9S_MB_2U(SCH_1):PAGE219_I64@PURE_QUANTA.Q_RES(CHIPS)':
 'B': CDS_PINID='B';
NET_NAME
'SMB_BMC_SWB_SDA_R4'
 '@S9S_MB_2U_LIB.S9S_MB_2U(SCH_1):SMB_BMC_SWB_SDA_R4':
 C_SIGNAL='@s9s_mb_2u_lib.s9s_mb_2u(sch_1):smb_bmc_swb_sda_r4';
NODE_NAME     U36 13
 '@S9S_MB_2U_LIB.S9S_MB_2U(SCH_1):PAGE219_I45@PURE_QUANTA.TCA9548APWR(CHIPS)':
 'SD4': CDS_PINID='SD4';
NODE_NAME     R2704 1
 '@S9S_MB_2U_LIB.S9S_MB_2U(SCH_1):PAGE219_I64@PURE_QUANTA.Q_RES(CHIPS)':
 'A': CDS_PINID='A';
NET_NAME
'SMB_CLK_PVCCD_HV_CPU0'
 '@S9S_MB_2U_LIB.S9S_MB_2U(SCH_1):SMB_CLK_PVCCD_HV_CPU0':
 C_SIGNAL='@s9s_mb_2u_lib.s9s_mb_2u(sch_1):smb_clk_pvccd_hv_cpu0';
NODE_NAME     PU35 10
 '@S9S_MB_2U_LIB.S9S_MB_2U(SCH_1):PAGE264_I53@PURE_QUANTA.ISL69260IRAZT(CHIPS)':
 'PMSCL': CDS_PINID='PMSCL';
NODE_NAME     R2402 2
 '@S9S_MB_2U_LIB.S9S_MB_2U(SCH_1):PAGE264_I39@PURE_QUANTA.Q_RES(CHIPS)':
 'B': CDS_PINID='B';
NET_NAME
'SMB_CLK_PVCCD_HV_CPU1'
 '@S9S_MB_2U_LIB.S9S_MB_2U(SCH_1):SMB_CLK_PVCCD_HV_CPU1':
 C_SIGNAL='@s9s_mb_2u_lib.s9s_mb_2u(sch_1):smb_clk_pvccd_hv_cpu1';
NODE_NAME     PU18 10
 '@S9S_MB_2U_LIB.S9S_MB_2U(SCH_1):PAGE282_I53@PURE_QUANTA.ISL69260IRAZT(CHIPS)':
 'PMSCL': CDS_PINID='PMSCL';
NODE_NAME     R4595 2
 '@S9S_MB_2U_LIB.S9S_MB_2U(SCH_1):PAGE282_I39@PURE_QUANTA.Q_RES(CHIPS)':
 'B': CDS_PINID='B';
NET_NAME
'SMB_CLK_PVCCINFAON_CPU0'
 '@S9S_MB_2U_LIB.S9S_MB_2U(SCH_1):SMB_CLK_PVCCINFAON_CPU0':
 C_SIGNAL='@s9s_mb_2u_lib.s9s_mb_2u(sch_1):smb_clk_pvccinfaon_cpu0';
NODE_NAME     PU5 10
 '@S9S_MB_2U_LIB.S9S_MB_2U(SCH_1):PAGE260_I65@PURE_QUANTA.ISL69260IRAZT(CHIPS)':
 'PMSCL': CDS_PINID='PMSCL';
NODE_NAME     R2390 2
 '@S9S_MB_2U_LIB.S9S_MB_2U(SCH_1):PAGE260_I53@PURE_QUANTA.Q_RES(CHIPS)':
 'B': CDS_PINID='B';
NET_NAME
'SMB_CLK_PVCCINFAON_CPU1'
 '@S9S_MB_2U_LIB.S9S_MB_2U(SCH_1):SMB_CLK_PVCCINFAON_CPU1':
 C_SIGNAL='@s9s_mb_2u_lib.s9s_mb_2u(sch_1):smb_clk_pvccinfaon_cpu1';
NODE_NAME     PU22 10
 '@S9S_MB_2U_LIB.S9S_MB_2U(SCH_1):PAGE278_I38@PURE_QUANTA.ISL69260IRAZT(CHIPS)':
 'PMSCL': CDS_PINID='PMSCL';
NODE_NAME     R4594 2
 '@S9S_MB_2U_LIB.S9S_MB_2U(SCH_1):PAGE278_I58@PURE_QUANTA.Q_RES(CHIPS)':
 'B': CDS_PINID='B';
NET_NAME
'SMB_CLK_PVCCIN_CPU0'
 '@S9S_MB_2U_LIB.S9S_MB_2U(SCH_1):SMB_CLK_PVCCIN_CPU0':
 C_SIGNAL='@s9s_mb_2u_lib.s9s_mb_2u(sch_1):smb_clk_pvccin_cpu0';
NODE_NAME     PU14 14
 '@S9S_MB_2U_LIB.S9S_MB_2U(SCH_1):PAGE252_I63@PURE_QUANTA.RAA229126GNPHA0(CHIPS)':
 'PMSCL': CDS_PINID='PMSCL';
NODE_NAME     R2371 2
 '@S9S_MB_2U_LIB.S9S_MB_2U(SCH_1):PAGE252_I80@PURE_QUANTA.Q_RES(CHIPS)':
 'B': CDS_PINID='B';
NET_NAME
'SMB_CLK_PVCCIN_CPU1'
 '@S9S_MB_2U_LIB.S9S_MB_2U(SCH_1):SMB_CLK_PVCCIN_CPU1':
 C_SIGNAL='@s9s_mb_2u_lib.s9s_mb_2u(sch_1):smb_clk_pvccin_cpu1';
NODE_NAME     R2520 2
 '@S9S_MB_2U_LIB.S9S_MB_2U(SCH_1):PAGE270_I65@PURE_QUANTA.Q_RES(CHIPS)':
 'B': CDS_PINID='B';
NODE_NAME     PU29 14
 '@S9S_MB_2U_LIB.S9S_MB_2U(SCH_1):PAGE270_I33@PURE_QUANTA.RAA229126GNPHA0(CHIPS)':
 'PMSCL': CDS_PINID='PMSCL';
NET_NAME
'SMB_DIO_PVCCD_HV_CPU0'
 '@S9S_MB_2U_LIB.S9S_MB_2U(SCH_1):SMB_DIO_PVCCD_HV_CPU0':
 C_SIGNAL='@s9s_mb_2u_lib.s9s_mb_2u(sch_1):smb_dio_pvccd_hv_cpu0';
NODE_NAME     R2403 2
 '@S9S_MB_2U_LIB.S9S_MB_2U(SCH_1):PAGE264_I38@PURE_QUANTA.Q_RES(CHIPS)':
 'B': CDS_PINID='B';
NODE_NAME     PU35 9
 '@S9S_MB_2U_LIB.S9S_MB_2U(SCH_1):PAGE264_I53@PURE_QUANTA.ISL69260IRAZT(CHIPS)':
 'PMSDA': CDS_PINID='PMSDA';
NET_NAME
'SMB_DIO_PVCCD_HV_CPU1'
 '@S9S_MB_2U_LIB.S9S_MB_2U(SCH_1):SMB_DIO_PVCCD_HV_CPU1':
 C_SIGNAL='@s9s_mb_2u_lib.s9s_mb_2u(sch_1):smb_dio_pvccd_hv_cpu1';
NODE_NAME     R2582 2
 '@S9S_MB_2U_LIB.S9S_MB_2U(SCH_1):PAGE282_I38@PURE_QUANTA.Q_RES(CHIPS)':
 'B': CDS_PINID='B';
NODE_NAME     PU18 9
 '@S9S_MB_2U_LIB.S9S_MB_2U(SCH_1):PAGE282_I53@PURE_QUANTA.ISL69260IRAZT(CHIPS)':
 'PMSDA': CDS_PINID='PMSDA';
NET_NAME
'SMB_DIO_PVCCINFAON_CPU0'
 '@S9S_MB_2U_LIB.S9S_MB_2U(SCH_1):SMB_DIO_PVCCINFAON_CPU0':
 C_SIGNAL='@s9s_mb_2u_lib.s9s_mb_2u(sch_1):smb_dio_pvccinfaon_cpu0';
NODE_NAME     PU5 9
 '@S9S_MB_2U_LIB.S9S_MB_2U(SCH_1):PAGE260_I65@PURE_QUANTA.ISL69260IRAZT(CHIPS)':
 'PMSDA': CDS_PINID='PMSDA';
NODE_NAME     R2391 2
 '@S9S_MB_2U_LIB.S9S_MB_2U(SCH_1):PAGE260_I51@PURE_QUANTA.Q_RES(CHIPS)':
 'B': CDS_PINID='B';
NET_NAME
'SMB_DIO_PVCCINFAON_CPU1'
 '@S9S_MB_2U_LIB.S9S_MB_2U(SCH_1):SMB_DIO_PVCCINFAON_CPU1':
 C_SIGNAL='@s9s_mb_2u_lib.s9s_mb_2u(sch_1):smb_dio_pvccinfaon_cpu1';
NODE_NAME     R2563 2
 '@S9S_MB_2U_LIB.S9S_MB_2U(SCH_1):PAGE278_I57@PURE_QUANTA.Q_RES(CHIPS)':
 'B': CDS_PINID='B';
NODE_NAME     PU22 9
 '@S9S_MB_2U_LIB.S9S_MB_2U(SCH_1):PAGE278_I38@PURE_QUANTA.ISL69260IRAZT(CHIPS)':
 'PMSDA': CDS_PINID='PMSDA';
NET_NAME
'SMB_DIO_PVCCIN_CPU0'
 '@S9S_MB_2U_LIB.S9S_MB_2U(SCH_1):SMB_DIO_PVCCIN_CPU0':
 C_SIGNAL='@s9s_mb_2u_lib.s9s_mb_2u(sch_1):smb_dio_pvccin_cpu0';
NODE_NAME     PU14 13
 '@S9S_MB_2U_LIB.S9S_MB_2U(SCH_1):PAGE252_I63@PURE_QUANTA.RAA229126GNPHA0(CHIPS)':
 'PMSDA': CDS_PINID='PMSDA';
NODE_NAME     R2372 2
 '@S9S_MB_2U_LIB.S9S_MB_2U(SCH_1):PAGE252_I78@PURE_QUANTA.Q_RES(CHIPS)':
 'B': CDS_PINID='B';
NET_NAME
'SMB_DIO_PVCCIN_CPU1'
 '@S9S_MB_2U_LIB.S9S_MB_2U(SCH_1):SMB_DIO_PVCCIN_CPU1':
 C_SIGNAL='@s9s_mb_2u_lib.s9s_mb_2u(sch_1):smb_dio_pvccin_cpu1';
NODE_NAME     R2521 2
 '@S9S_MB_2U_LIB.S9S_MB_2U(SCH_1):PAGE270_I66@PURE_QUANTA.Q_RES(CHIPS)':
 'B': CDS_PINID='B';
NODE_NAME     PU29 13
 '@S9S_MB_2U_LIB.S9S_MB_2U(SCH_1):PAGE270_I33@PURE_QUANTA.RAA229126GNPHA0(CHIPS)':
 'PMSDA': CDS_PINID='PMSDA';
NET_NAME
'SMB_E1S_3V3AUX_ISO_SCL'
 '@S9S_MB_2U_LIB.S9S_MB_2U(SCH_1):SMB_E1S_3V3AUX_ISO_SCL':
 C_SIGNAL='@s9s_mb_2u_lib.s9s_mb_2u(sch_1):smb_e1s_3v3aux_iso_scl';
NODE_NAME     R3533 2
 '@S9S_MB_2U_LIB.S9S_MB_2U(SCH_1):PAGE183_I76@PURE_QUANTA.Q_RES(CHIPS)':
 'B': CDS_PINID='B';
NODE_NAME     J90 A7
 '@S9S_MB_2U_LIB.S9S_MB_2U(SCH_1):PAGE297_I318@PURE_QUANTA.SCONN56_123276793(CHIPS)':
 'SMBCLK': CDS_PINID='SMBCLK';
NET_NAME
'SMB_E1S_3V3AUX_ISO_SCL_R'
 '@S9S_MB_2U_LIB.S9S_MB_2U(SCH_1):SMB_E1S_3V3AUX_ISO_SCL_R':
 C_SIGNAL='@s9s_mb_2u_lib.s9s_mb_2u(sch_1):smb_e1s_3v3aux_iso_scl_r';
NODE_NAME     R3533 1
 '@S9S_MB_2U_LIB.S9S_MB_2U(SCH_1):PAGE183_I76@PURE_QUANTA.Q_RES(CHIPS)':
 'A': CDS_PINID='A';
NODE_NAME     R3530 2
 '@S9S_MB_2U_LIB.S9S_MB_2U(SCH_1):PAGE183_I80@PURE_QUANTA.Q_RES(CHIPS)':
 'B': CDS_PINID='B';
NODE_NAME     U279 2
 '@S9S_MB_2U_LIB.S9S_MB_2U(SCH_1):PAGE183_I93@PURE_QUANTA.PCA9617ADP(CHIPS)':
 'SCLA': CDS_PINID='SCLA';
NET_NAME
'SMB_E1S_3V3AUX_ISO_SDA'
 '@S9S_MB_2U_LIB.S9S_MB_2U(SCH_1):SMB_E1S_3V3AUX_ISO_SDA':
 C_SIGNAL='@s9s_mb_2u_lib.s9s_mb_2u(sch_1):smb_e1s_3v3aux_iso_sda';
NODE_NAME     R3534 2
 '@S9S_MB_2U_LIB.S9S_MB_2U(SCH_1):PAGE183_I77@PURE_QUANTA.Q_RES(CHIPS)':
 'B': CDS_PINID='B';
NODE_NAME     J90 A8
 '@S9S_MB_2U_LIB.S9S_MB_2U(SCH_1):PAGE297_I318@PURE_QUANTA.SCONN56_123276793(CHIPS)':
 'SMBDAT': CDS_PINID='SMBDAT';
NET_NAME
'SMB_E1S_3V3AUX_ISO_SDA_R'
 '@S9S_MB_2U_LIB.S9S_MB_2U(SCH_1):SMB_E1S_3V3AUX_ISO_SDA_R':
 C_SIGNAL='@s9s_mb_2u_lib.s9s_mb_2u(sch_1):smb_e1s_3v3aux_iso_sda_r';
NODE_NAME     R3534 1
 '@S9S_MB_2U_LIB.S9S_MB_2U(SCH_1):PAGE183_I77@PURE_QUANTA.Q_RES(CHIPS)':
 'A': CDS_PINID='A';
NODE_NAME     R3532 2
 '@S9S_MB_2U_LIB.S9S_MB_2U(SCH_1):PAGE183_I78@PURE_QUANTA.Q_RES(CHIPS)':
 'B': CDS_PINID='B';
NODE_NAME     U279 3
 '@S9S_MB_2U_LIB.S9S_MB_2U(SCH_1):PAGE183_I93@PURE_QUANTA.PCA9617ADP(CHIPS)':
 'SDAA': CDS_PINID='SDAA';
NET_NAME
'SMB_FAN_3V3AUX_BUF_R_SCL'
 '@S9S_MB_2U_LIB.S9S_MB_2U(SCH_1):SMB_FAN_3V3AUX_BUF_R_SCL':
 C_SIGNAL='@s9s_mb_2u_lib.s9s_mb_2u(sch_1):smb_fan_3v3aux_buf_r_scl';
NODE_NAME     J45 C1
 '@S9S_MB_2U_LIB.S9S_MB_2U(SCH_1):PAGE233_I12@PURE_QUANTA.CONN60_101062636003K02LF(CHIPS)':
 'C1': CDS_PINID='C1';
NODE_NAME     R2811 2
 '@S9S_MB_2U_LIB.S9S_MB_2U(SCH_1):PAGE233_I21@PURE_QUANTA.Q_RES(CHIPS)':
 'B': CDS_PINID='B';
NET_NAME
'SMB_FAN_3V3AUX_BUF_R_SDA'
 '@S9S_MB_2U_LIB.S9S_MB_2U(SCH_1):SMB_FAN_3V3AUX_BUF_R_SDA':
 C_SIGNAL='@s9s_mb_2u_lib.s9s_mb_2u(sch_1):smb_fan_3v3aux_buf_r_sda';
NODE_NAME     J45 C2
 '@S9S_MB_2U_LIB.S9S_MB_2U(SCH_1):PAGE233_I12@PURE_QUANTA.CONN60_101062636003K02LF(CHIPS)':
 'C2': CDS_PINID='C2';
NODE_NAME     R2812 2
 '@S9S_MB_2U_LIB.S9S_MB_2U(SCH_1):PAGE233_I20@PURE_QUANTA.Q_RES(CHIPS)':
 'B': CDS_PINID='B';
NET_NAME
'SMB_FAN_3V3AUX_BUF_SCL'
 '@S9S_MB_2U_LIB.S9S_MB_2U(SCH_1):SMB_FAN_3V3AUX_BUF_SCL':
 C_SIGNAL='@s9s_mb_2u_lib.s9s_mb_2u(sch_1):smb_fan_3v3aux_buf_scl';
NODE_NAME     R2800 2
 '@S9S_MB_2U_LIB.S9S_MB_2U(SCH_1):PAGE233_I15@PURE_QUANTA.Q_RES(CHIPS)':
 'B': CDS_PINID='B';
NODE_NAME     U192 2
 '@S9S_MB_2U_LIB.S9S_MB_2U(SCH_1):PAGE233_I16@PURE_QUANTA.LTC4307CMS8(CHIPS)':
 'SCL_OUT': CDS_PINID='SCL_OUT';
NODE_NAME     R2811 1
 '@S9S_MB_2U_LIB.S9S_MB_2U(SCH_1):PAGE233_I21@PURE_QUANTA.Q_RES(CHIPS)':
 'A': CDS_PINID='A';
NODE_NAME     R2805 2
 '@S9S_MB_2U_LIB.S9S_MB_2U(SCH_1):PAGE233_I22@PURE_QUANTA.Q_RES(CHIPS)':
 'B': CDS_PINID='B';
NET_NAME
'SMB_FAN_3V3AUX_BUF_SDA'
 '@S9S_MB_2U_LIB.S9S_MB_2U(SCH_1):SMB_FAN_3V3AUX_BUF_SDA':
 C_SIGNAL='@s9s_mb_2u_lib.s9s_mb_2u(sch_1):smb_fan_3v3aux_buf_sda';
NODE_NAME     R2801 2
 '@S9S_MB_2U_LIB.S9S_MB_2U(SCH_1):PAGE233_I14@PURE_QUANTA.Q_RES(CHIPS)':
 'B': CDS_PINID='B';
NODE_NAME     U192 7
 '@S9S_MB_2U_LIB.S9S_MB_2U(SCH_1):PAGE233_I16@PURE_QUANTA.LTC4307CMS8(CHIPS)':
 'SDA_OUT': CDS_PINID='SDA_OUT';
NODE_NAME     R2812 1
 '@S9S_MB_2U_LIB.S9S_MB_2U(SCH_1):PAGE233_I20@PURE_QUANTA.Q_RES(CHIPS)':
 'A': CDS_PINID='A';
NODE_NAME     R2807 2
 '@S9S_MB_2U_LIB.S9S_MB_2U(SCH_1):PAGE233_I24@PURE_QUANTA.Q_RES(CHIPS)':
 'B': CDS_PINID='B';
NET_NAME
'SMB_FAN_3V3AUX_R_SCL'
 '@S9S_MB_2U_LIB.S9S_MB_2U(SCH_1):SMB_FAN_3V3AUX_R_SCL':
 C_SIGNAL='@s9s_mb_2u_lib.s9s_mb_2u(sch_1):smb_fan_3v3aux_r_scl';
NODE_NAME     R3113 2
 '@S9S_MB_2U_LIB.S9S_MB_2U(SCH_1):PAGE233_I9@PURE_QUANTA.Q_RES(CHIPS)':
 'B': CDS_PINID='B';
NODE_NAME     R2800 1
 '@S9S_MB_2U_LIB.S9S_MB_2U(SCH_1):PAGE233_I15@PURE_QUANTA.Q_RES(CHIPS)':
 'A': CDS_PINID='A';
NODE_NAME     U192 3
 '@S9S_MB_2U_LIB.S9S_MB_2U(SCH_1):PAGE233_I16@PURE_QUANTA.LTC4307CMS8(CHIPS)':
 'SCL_IN': CDS_PINID='SCL_IN';
NET_NAME
'SMB_FAN_3V3AUX_R_SDA'
 '@S9S_MB_2U_LIB.S9S_MB_2U(SCH_1):SMB_FAN_3V3AUX_R_SDA':
 C_SIGNAL='@s9s_mb_2u_lib.s9s_mb_2u(sch_1):smb_fan_3v3aux_r_sda';
NODE_NAME     R3114 2
 '@S9S_MB_2U_LIB.S9S_MB_2U(SCH_1):PAGE233_I8@PURE_QUANTA.Q_RES(CHIPS)':
 'B': CDS_PINID='B';
NODE_NAME     R2801 1
 '@S9S_MB_2U_LIB.S9S_MB_2U(SCH_1):PAGE233_I14@PURE_QUANTA.Q_RES(CHIPS)':
 'A': CDS_PINID='A';
NODE_NAME     U192 6
 '@S9S_MB_2U_LIB.S9S_MB_2U(SCH_1):PAGE233_I16@PURE_QUANTA.LTC4307CMS8(CHIPS)':
 'SDA_IN': CDS_PINID='SDA_IN';
NET_NAME
'SMB_FAN_3V3AUX_SCL'
 '@S9S_MB_2U_LIB.S9S_MB_2U(SCH_1):SMB_FAN_3V3AUX_SCL':
 C_SIGNAL='@s9s_mb_2u_lib.s9s_mb_2u(sch_1):smb_fan_3v3aux_scl';
NODE_NAME     R592 1
 '@S9S_MB_2U_LIB.S9S_MB_2U(SCH_1):PAGE228_I173@PURE_QUANTA.Q_RES(CHIPS)':
 'A': CDS_PINID='A';
NODE_NAME     R3113 1
 '@S9S_MB_2U_LIB.S9S_MB_2U(SCH_1):PAGE233_I9@PURE_QUANTA.Q_RES(CHIPS)':
 'A': CDS_PINID='A';
NODE_NAME     J41 A29
 '@S9S_MB_2U_LIB.S9S_MB_2U(SCH_1):PAGE227_I173@PURE_QUANTA.SCONN168_ME1016810202011(CHIPS)':
 'GND_A29': CDS_PINID='GND_A29';
NET_NAME
'SMB_FAN_3V3AUX_SDA'
 '@S9S_MB_2U_LIB.S9S_MB_2U(SCH_1):SMB_FAN_3V3AUX_SDA':
 C_SIGNAL='@s9s_mb_2u_lib.s9s_mb_2u(sch_1):smb_fan_3v3aux_sda';
NODE_NAME     R601 1
 '@S9S_MB_2U_LIB.S9S_MB_2U(SCH_1):PAGE228_I172@PURE_QUANTA.Q_RES(CHIPS)':
 'A': CDS_PINID='A';
NODE_NAME     R3114 1
 '@S9S_MB_2U_LIB.S9S_MB_2U(SCH_1):PAGE233_I8@PURE_QUANTA.Q_RES(CHIPS)':
 'A': CDS_PINID='A';
NODE_NAME     J41 A30
 '@S9S_MB_2U_LIB.S9S_MB_2U(SCH_1):PAGE227_I173@PURE_QUANTA.SCONN168_ME1016810202011(CHIPS)':
 'PERN4': CDS_PINID='PERN4';
NET_NAME
'SMB_FRU_3V3AUX_SCL'
 '@S9S_MB_2U_LIB.S9S_MB_2U(SCH_1):SMB_FRU_3V3AUX_SCL':
 C_SIGNAL='@s9s_mb_2u_lib.s9s_mb_2u(sch_1):smb_fru_3v3aux_scl';
NODE_NAME     U64 6
 '@S9S_MB_2U_LIB.S9S_MB_2U(SCH_1):PAGE231_I35@PURE_QUANTA.M24128BWMN6TP(CHIPS)':
 'SCL': CDS_PINID='SCL';
NODE_NAME     R1331 2
 '@S9S_MB_2U_LIB.S9S_MB_2U(SCH_1):PAGE231_I95@PURE_QUANTA.Q_RES(CHIPS)':
 'B': CDS_PINID='B';
NODE_NAME     R651 2
 '@S9S_MB_2U_LIB.S9S_MB_2U(SCH_1):PAGE219_I22@PURE_QUANTA.Q_RES(CHIPS)':
 'B': CDS_PINID='B';
NODE_NAME     R2565 2
 '@S9S_MB_2U_LIB.S9S_MB_2U(SCH_1):PAGE219_I61@PURE_QUANTA.Q_RES(CHIPS)':
 'B': CDS_PINID='B';
NET_NAME
'SMB_FRU_3V3AUX_SCL_R'
 '@S9S_MB_2U_LIB.S9S_MB_2U(SCH_1):SMB_FRU_3V3AUX_SCL_R':
 C_SIGNAL='@s9s_mb_2u_lib.s9s_mb_2u(sch_1):smb_fru_3v3aux_scl_r';
NODE_NAME     U36 16
 '@S9S_MB_2U_LIB.S9S_MB_2U(SCH_1):PAGE219_I45@PURE_QUANTA.TCA9548APWR(CHIPS)':
 'SC5': CDS_PINID='SC5';
NODE_NAME     R2565 1
 '@S9S_MB_2U_LIB.S9S_MB_2U(SCH_1):PAGE219_I61@PURE_QUANTA.Q_RES(CHIPS)':
 'A': CDS_PINID='A';
NET_NAME
'SMB_FRU_3V3AUX_SDA'
 '@S9S_MB_2U_LIB.S9S_MB_2U(SCH_1):SMB_FRU_3V3AUX_SDA':
 C_SIGNAL='@s9s_mb_2u_lib.s9s_mb_2u(sch_1):smb_fru_3v3aux_sda';
NODE_NAME     U64 5
 '@S9S_MB_2U_LIB.S9S_MB_2U(SCH_1):PAGE231_I35@PURE_QUANTA.M24128BWMN6TP(CHIPS)':
 'SDA': CDS_PINID='SDA';
NODE_NAME     R1332 2
 '@S9S_MB_2U_LIB.S9S_MB_2U(SCH_1):PAGE231_I93@PURE_QUANTA.Q_RES(CHIPS)':
 'B': CDS_PINID='B';
NODE_NAME     R652 2
 '@S9S_MB_2U_LIB.S9S_MB_2U(SCH_1):PAGE219_I23@PURE_QUANTA.Q_RES(CHIPS)':
 'B': CDS_PINID='B';
NODE_NAME     R2566 2
 '@S9S_MB_2U_LIB.S9S_MB_2U(SCH_1):PAGE219_I62@PURE_QUANTA.Q_RES(CHIPS)':
 'B': CDS_PINID='B';
NET_NAME
'SMB_FRU_3V3AUX_SDA_R'
 '@S9S_MB_2U_LIB.S9S_MB_2U(SCH_1):SMB_FRU_3V3AUX_SDA_R':
 C_SIGNAL='@s9s_mb_2u_lib.s9s_mb_2u(sch_1):smb_fru_3v3aux_sda_r';
NODE_NAME     U36 15
 '@S9S_MB_2U_LIB.S9S_MB_2U(SCH_1):PAGE219_I45@PURE_QUANTA.TCA9548APWR(CHIPS)':
 'SD5': CDS_PINID='SD5';
NODE_NAME     R2566 1
 '@S9S_MB_2U_LIB.S9S_MB_2U(SCH_1):PAGE219_I62@PURE_QUANTA.Q_RES(CHIPS)':
 'A': CDS_PINID='A';
NET_NAME
'SMB_HOST_3V3AUX_PLD_SCL'
 '@S9S_MB_2U_LIB.S9S_MB_2U(SCH_1):SMB_HOST_3V3AUX_PLD_SCL':
 C_SIGNAL='@s9s_mb_2u_lib.s9s_mb_2u(sch_1):smb_host_3v3aux_pld_scl';
NODE_NAME     U249 A10
 '@S9S_MB_2U_LIB.S9S_MB_2U(SCH_1):PAGE314_I188@PURE_QUANTA.LCMXO3LF9400C5BG484C(CHIPS)':
 'PT23B||PCLKC0_1': CDS_PINID='\pt23b||pclkc0_1\';
NODE_NAME     R4715 2
 '@S9S_MB_2U_LIB.S9S_MB_2U(SCH_1):PAGE314_I198@PURE_QUANTA.Q_RES(CHIPS)':
 'B': CDS_PINID='B';
NET_NAME
'SMB_HOST_3V3AUX_PLD_SDA'
 '@S9S_MB_2U_LIB.S9S_MB_2U(SCH_1):SMB_HOST_3V3AUX_PLD_SDA':
 C_SIGNAL='@s9s_mb_2u_lib.s9s_mb_2u(sch_1):smb_host_3v3aux_pld_sda';
NODE_NAME     U249 B10
 '@S9S_MB_2U_LIB.S9S_MB_2U(SCH_1):PAGE314_I188@PURE_QUANTA.LCMXO3LF9400C5BG484C(CHIPS)':
 'PT23A||PCLKT0_1': CDS_PINID='\pt23a||pclkt0_1\';
NODE_NAME     R4714 2
 '@S9S_MB_2U_LIB.S9S_MB_2U(SCH_1):PAGE314_I197@PURE_QUANTA.Q_RES(CHIPS)':
 'B': CDS_PINID='B';
NET_NAME
'SMB_HOST_3V3AUX_SCL'
 '@S9S_MB_2U_LIB.S9S_MB_2U(SCH_1):SMB_HOST_3V3AUX_SCL':
 C_SIGNAL='@s9s_mb_2u_lib.s9s_mb_2u(sch_1):smb_host_3v3aux_scl';
NODE_NAME     R1319 1
 '@S9S_MB_2U_LIB.S9S_MB_2U(SCH_1):PAGE228_I2@PURE_QUANTA.Q_RES(CHIPS)':
 'A': CDS_PINID='A';
NODE_NAME     R4510 1
 '@S9S_MB_2U_LIB.S9S_MB_2U(SCH_1):PAGE228_I285@PURE_QUANTA.Q_RES(CHIPS)':
 'A': CDS_PINID='A';
NODE_NAME     R4512 1
 '@S9S_MB_2U_LIB.S9S_MB_2U(SCH_1):PAGE228_I305@PURE_QUANTA.Q_RES(CHIPS)':
 'A': CDS_PINID='A';
NODE_NAME     R2419 1
 '@S9S_MB_2U_LIB.S9S_MB_2U(SCH_1):PAGE227_I100@PURE_QUANTA.Q_RES(CHIPS)':
 'A': CDS_PINID='A';
NET_NAME
'SMB_HOST_3V3AUX_SCL_R'
 '@S9S_MB_2U_LIB.S9S_MB_2U(SCH_1):SMB_HOST_3V3AUX_SCL_R':
 C_SIGNAL='@s9s_mb_2u_lib.s9s_mb_2u(sch_1):smb_host_3v3aux_scl_r';
NODE_NAME     R1525 1
 '@S9S_MB_2U_LIB.S9S_MB_2U(SCH_1):PAGE228_I40@PURE_QUANTA.Q_RES(CHIPS)':
 'A': CDS_PINID='A';
NODE_NAME     R107 1
 '@S9S_MB_2U_LIB.S9S_MB_2U(SCH_1):PAGE228_I43@PURE_QUANTA.Q_RES(CHIPS)':
 'A': CDS_PINID='A';
NODE_NAME     R577 2
 '@S9S_MB_2U_LIB.S9S_MB_2U(SCH_1):PAGE228_I303@PURE_QUANTA.Q_RES(CHIPS)':
 'B': CDS_PINID='B';
NET_NAME
'SMB_HOST_3V3AUX_SCL_R0'
 '@S9S_MB_2U_LIB.S9S_MB_2U(SCH_1):SMB_HOST_3V3AUX_SCL_R0':
 C_SIGNAL='@s9s_mb_2u_lib.s9s_mb_2u(sch_1):smb_host_3v3aux_scl_r0';
NODE_NAME     R2419 2
 '@S9S_MB_2U_LIB.S9S_MB_2U(SCH_1):PAGE227_I100@PURE_QUANTA.Q_RES(CHIPS)':
 'B': CDS_PINID='B';
NODE_NAME     J41 A3
 '@S9S_MB_2U_LIB.S9S_MB_2U(SCH_1):PAGE227_I173@PURE_QUANTA.SCONN168_ME1016810202011(CHIPS)':
 'GND_A3': CDS_PINID='GND_A3';
NET_NAME
'SMB_HOST_3V3AUX_SCL_R4'
 '@S9S_MB_2U_LIB.S9S_MB_2U(SCH_1):SMB_HOST_3V3AUX_SCL_R4':
 C_SIGNAL='@s9s_mb_2u_lib.s9s_mb_2u(sch_1):smb_host_3v3aux_scl_r4';
NODE_NAME     R4502 1
 '@S9S_MB_2U_LIB.S9S_MB_2U(SCH_1):PAGE133_I148@PURE_QUANTA.Q_RES(CHIPS)':
 'A': CDS_PINID='A';
NODE_NAME     R4510 2
 '@S9S_MB_2U_LIB.S9S_MB_2U(SCH_1):PAGE228_I285@PURE_QUANTA.Q_RES(CHIPS)':
 'B': CDS_PINID='B';
NODE_NAME     R577 1
 '@S9S_MB_2U_LIB.S9S_MB_2U(SCH_1):PAGE228_I303@PURE_QUANTA.Q_RES(CHIPS)':
 'A': CDS_PINID='A';
NODE_NAME     R4715 1
 '@S9S_MB_2U_LIB.S9S_MB_2U(SCH_1):PAGE314_I198@PURE_QUANTA.Q_RES(CHIPS)':
 'A': CDS_PINID='A';
NET_NAME
'SMB_HOST_3V3AUX_SCL_R5'
 '@S9S_MB_2U_LIB.S9S_MB_2U(SCH_1):SMB_HOST_3V3AUX_SCL_R5':
 C_SIGNAL='@s9s_mb_2u_lib.s9s_mb_2u(sch_1):smb_host_3v3aux_scl_r5';
NODE_NAME     R579 1
 '@S9S_MB_2U_LIB.S9S_MB_2U(SCH_1):PAGE228_I38@PURE_QUANTA.Q_RES(CHIPS)':
 'A': CDS_PINID='A';
NODE_NAME     R3052 1
 '@S9S_MB_2U_LIB.S9S_MB_2U(SCH_1):PAGE215_I13@PURE_QUANTA.Q_RES(CHIPS)':
 'A': CDS_PINID='A';
NODE_NAME     R4512 2
 '@S9S_MB_2U_LIB.S9S_MB_2U(SCH_1):PAGE228_I305@PURE_QUANTA.Q_RES(CHIPS)':
 'B': CDS_PINID='B';
NET_NAME
'SMB_HOST_3V3AUX_SDA'
 '@S9S_MB_2U_LIB.S9S_MB_2U(SCH_1):SMB_HOST_3V3AUX_SDA':
 C_SIGNAL='@s9s_mb_2u_lib.s9s_mb_2u(sch_1):smb_host_3v3aux_sda';
NODE_NAME     R3062 1
 '@S9S_MB_2U_LIB.S9S_MB_2U(SCH_1):PAGE228_I3@PURE_QUANTA.Q_RES(CHIPS)':
 'A': CDS_PINID='A';
NODE_NAME     R4511 1
 '@S9S_MB_2U_LIB.S9S_MB_2U(SCH_1):PAGE228_I284@PURE_QUANTA.Q_RES(CHIPS)':
 'A': CDS_PINID='A';
NODE_NAME     R4513 1
 '@S9S_MB_2U_LIB.S9S_MB_2U(SCH_1):PAGE228_I306@PURE_QUANTA.Q_RES(CHIPS)':
 'A': CDS_PINID='A';
NODE_NAME     R2420 1
 '@S9S_MB_2U_LIB.S9S_MB_2U(SCH_1):PAGE227_I98@PURE_QUANTA.Q_RES(CHIPS)':
 'A': CDS_PINID='A';
NET_NAME
'SMB_HOST_3V3AUX_SDA_R'
 '@S9S_MB_2U_LIB.S9S_MB_2U(SCH_1):SMB_HOST_3V3AUX_SDA_R':
 C_SIGNAL='@s9s_mb_2u_lib.s9s_mb_2u(sch_1):smb_host_3v3aux_sda_r';
NODE_NAME     R1526 1
 '@S9S_MB_2U_LIB.S9S_MB_2U(SCH_1):PAGE228_I41@PURE_QUANTA.Q_RES(CHIPS)':
 'A': CDS_PINID='A';
NODE_NAME     R108 1
 '@S9S_MB_2U_LIB.S9S_MB_2U(SCH_1):PAGE228_I42@PURE_QUANTA.Q_RES(CHIPS)':
 'A': CDS_PINID='A';
NODE_NAME     R578 2
 '@S9S_MB_2U_LIB.S9S_MB_2U(SCH_1):PAGE228_I304@PURE_QUANTA.Q_RES(CHIPS)':
 'B': CDS_PINID='B';
NET_NAME
'SMB_HOST_3V3AUX_SDA_R0'
 '@S9S_MB_2U_LIB.S9S_MB_2U(SCH_1):SMB_HOST_3V3AUX_SDA_R0':
 C_SIGNAL='@s9s_mb_2u_lib.s9s_mb_2u(sch_1):smb_host_3v3aux_sda_r0';
NODE_NAME     R2420 2
 '@S9S_MB_2U_LIB.S9S_MB_2U(SCH_1):PAGE227_I98@PURE_QUANTA.Q_RES(CHIPS)':
 'B': CDS_PINID='B';
NODE_NAME     J41 A4
 '@S9S_MB_2U_LIB.S9S_MB_2U(SCH_1):PAGE227_I173@PURE_QUANTA.SCONN168_ME1016810202011(CHIPS)':
 'GND_A4': CDS_PINID='GND_A4';
NET_NAME
'SMB_HOST_3V3AUX_SDA_R4'
 '@S9S_MB_2U_LIB.S9S_MB_2U(SCH_1):SMB_HOST_3V3AUX_SDA_R4':
 C_SIGNAL='@s9s_mb_2u_lib.s9s_mb_2u(sch_1):smb_host_3v3aux_sda_r4';
NODE_NAME     R4503 1
 '@S9S_MB_2U_LIB.S9S_MB_2U(SCH_1):PAGE133_I153@PURE_QUANTA.Q_RES(CHIPS)':
 'A': CDS_PINID='A';
NODE_NAME     R4511 2
 '@S9S_MB_2U_LIB.S9S_MB_2U(SCH_1):PAGE228_I284@PURE_QUANTA.Q_RES(CHIPS)':
 'B': CDS_PINID='B';
NODE_NAME     R578 1
 '@S9S_MB_2U_LIB.S9S_MB_2U(SCH_1):PAGE228_I304@PURE_QUANTA.Q_RES(CHIPS)':
 'A': CDS_PINID='A';
NODE_NAME     R4714 1
 '@S9S_MB_2U_LIB.S9S_MB_2U(SCH_1):PAGE314_I197@PURE_QUANTA.Q_RES(CHIPS)':
 'A': CDS_PINID='A';
NET_NAME
'SMB_HOST_3V3AUX_SDA_R5'
 '@S9S_MB_2U_LIB.S9S_MB_2U(SCH_1):SMB_HOST_3V3AUX_SDA_R5':
 C_SIGNAL='@s9s_mb_2u_lib.s9s_mb_2u(sch_1):smb_host_3v3aux_sda_r5';
NODE_NAME     R580 1
 '@S9S_MB_2U_LIB.S9S_MB_2U(SCH_1):PAGE228_I39@PURE_QUANTA.Q_RES(CHIPS)':
 'A': CDS_PINID='A';
NODE_NAME     R3053 1
 '@S9S_MB_2U_LIB.S9S_MB_2U(SCH_1):PAGE215_I12@PURE_QUANTA.Q_RES(CHIPS)':
 'A': CDS_PINID='A';
NODE_NAME     R4513 2
 '@S9S_MB_2U_LIB.S9S_MB_2U(SCH_1):PAGE228_I306@PURE_QUANTA.Q_RES(CHIPS)':
 'B': CDS_PINID='B';
NET_NAME
'SMB_HOST_3V3AUX_XDP_R_SCL'
 '@S9S_MB_2U_LIB.S9S_MB_2U(SCH_1):SMB_HOST_3V3AUX_XDP_R_SCL':
 C_SIGNAL='@s9s_mb_2u_lib.s9s_mb_2u(sch_1):smb_host_3v3aux_xdp_r_scl';
NODE_NAME     J42 48
 '@S9S_MB_2U_LIB.S9S_MB_2U(SCH_1):PAGE133_I44@PURE_QUANTA.SCONN60_ASP21410801(CHIPS)':
 '48': CDS_PINID='\48\';
NODE_NAME     R4502 2
 '@S9S_MB_2U_LIB.S9S_MB_2U(SCH_1):PAGE133_I148@PURE_QUANTA.Q_RES(CHIPS)':
 'B': CDS_PINID='B';
NET_NAME
'SMB_HOST_3V3AUX_XDP_R_SDA'
 '@S9S_MB_2U_LIB.S9S_MB_2U(SCH_1):SMB_HOST_3V3AUX_XDP_R_SDA':
 C_SIGNAL='@s9s_mb_2u_lib.s9s_mb_2u(sch_1):smb_host_3v3aux_xdp_r_sda';
NODE_NAME     J42 50
 '@S9S_MB_2U_LIB.S9S_MB_2U(SCH_1):PAGE133_I44@PURE_QUANTA.SCONN60_ASP21410801(CHIPS)':
 '50': CDS_PINID='\50\';
NODE_NAME     R4503 2
 '@S9S_MB_2U_LIB.S9S_MB_2U(SCH_1):PAGE133_I153@PURE_QUANTA.Q_RES(CHIPS)':
 'B': CDS_PINID='B';
NET_NAME
'SMB_HOST_9ZXL045_3V3AUX_SCL'
 '@S9S_MB_2U_LIB.S9S_MB_2U(SCH_1):SMB_HOST_9ZXL045_3V3AUX_SCL':
 C_SIGNAL='@s9s_mb_2u_lib.s9s_mb_2u(sch_1):smb_host_9zxl045_3v3aux_scl';
NODE_NAME     U314 7
 '@S9S_MB_2U_LIB.S9S_MB_2U(SCH_1):PAGE200_I1@PURE_QUANTA.9ZXL0451EKILFT(CHIPS)':
 'SMBCLK': CDS_PINID='SMBCLK';
NODE_NAME     R4480 2
 '@S9S_MB_2U_LIB.S9S_MB_2U(SCH_1):PAGE225_I24@PURE_QUANTA.Q_RES(CHIPS)':
 'B': CDS_PINID='B';
NET_NAME
'SMB_HOST_9ZXL045_3V3AUX_SDA'
 '@S9S_MB_2U_LIB.S9S_MB_2U(SCH_1):SMB_HOST_9ZXL045_3V3AUX_SDA':
 C_SIGNAL='@s9s_mb_2u_lib.s9s_mb_2u(sch_1):smb_host_9zxl045_3v3aux_sda';
NODE_NAME     U314 6
 '@S9S_MB_2U_LIB.S9S_MB_2U(SCH_1):PAGE200_I1@PURE_QUANTA.9ZXL0451EKILFT(CHIPS)':
 'SMBDAT': CDS_PINID='SMBDAT';
NODE_NAME     R4481 2
 '@S9S_MB_2U_LIB.S9S_MB_2U(SCH_1):PAGE225_I25@PURE_QUANTA.Q_RES(CHIPS)':
 'B': CDS_PINID='B';
NET_NAME
'SMB_HOST_BMC_3V3AUX_SCL'
 '@S9S_MB_2U_LIB.S9S_MB_2U(SCH_1):SMB_HOST_BMC_3V3AUX_SCL':
 C_SIGNAL='@s9s_mb_2u_lib.s9s_mb_2u(sch_1):smb_host_bmc_3v3aux_scl';
NODE_NAME     U4 AF2
 '@S9S_MB_2U_LIB.S9S_MB_2U(SCH_1):PAGE175_I93@PURE_QUANTA.EMMITSBURG_REV0P9(CHIPS)':
 'GPP_D_0_HS_SMBCLK_DMA_SMBCLK': CDS_PINID='GPP_D_0_HS_SMBCLK_DMA_SMBCLK';
NODE_NAME     R579 2
 '@S9S_MB_2U_LIB.S9S_MB_2U(SCH_1):PAGE228_I38@PURE_QUANTA.Q_RES(CHIPS)':
 'B': CDS_PINID='B';
NET_NAME
'SMB_HOST_BMC_3V3AUX_SDA'
 '@S9S_MB_2U_LIB.S9S_MB_2U(SCH_1):SMB_HOST_BMC_3V3AUX_SDA':
 C_SIGNAL='@s9s_mb_2u_lib.s9s_mb_2u(sch_1):smb_host_bmc_3v3aux_sda';
NODE_NAME     U4 AE1
 '@S9S_MB_2U_LIB.S9S_MB_2U(SCH_1):PAGE175_I93@PURE_QUANTA.EMMITSBURG_REV0P9(CHIPS)':
 'GPP_D_1_HS_SMBDATA_DMA_SMBDATA': CDS_PINID='GPP_D_1_HS_SMBDATA_DMA_SMBDATA';
NODE_NAME     R580 2
 '@S9S_MB_2U_LIB.S9S_MB_2U(SCH_1):PAGE228_I39@PURE_QUANTA.Q_RES(CHIPS)':
 'B': CDS_PINID='B';
NET_NAME
'SMB_HOST_CLK_3V3AUX_SCL'
 '@S9S_MB_2U_LIB.S9S_MB_2U(SCH_1):SMB_HOST_CLK_3V3AUX_SCL':
 C_SIGNAL='@s9s_mb_2u_lib.s9s_mb_2u(sch_1):smb_host_clk_3v3aux_scl';
NODE_NAME     U13 A10
 '@S9S_MB_2U_LIB.S9S_MB_2U(SCH_1):PAGE197_I180@PURE_QUANTA.9SQ440NQQI8(CHIPS)':
 'SCLK': CDS_PINID='SCLK';
NODE_NAME     R1525 2
 '@S9S_MB_2U_LIB.S9S_MB_2U(SCH_1):PAGE228_I40@PURE_QUANTA.Q_RES(CHIPS)':
 'B': CDS_PINID='B';
NODE_NAME     R3340 1
 '@S9S_MB_2U_LIB.S9S_MB_2U(SCH_1):PAGE228_I268@PURE_QUANTA.Q_RES(CHIPS)':
 'A': CDS_PINID='A';
NET_NAME
'SMB_HOST_CLK_3V3AUX_SDA'
 '@S9S_MB_2U_LIB.S9S_MB_2U(SCH_1):SMB_HOST_CLK_3V3AUX_SDA':
 C_SIGNAL='@s9s_mb_2u_lib.s9s_mb_2u(sch_1):smb_host_clk_3v3aux_sda';
NODE_NAME     U13 B8
 '@S9S_MB_2U_LIB.S9S_MB_2U(SCH_1):PAGE197_I180@PURE_QUANTA.9SQ440NQQI8(CHIPS)':
 'SMBDATTA': CDS_PINID='SMBDATTA';
NODE_NAME     R1526 2
 '@S9S_MB_2U_LIB.S9S_MB_2U(SCH_1):PAGE228_I41@PURE_QUANTA.Q_RES(CHIPS)':
 'B': CDS_PINID='B';
NODE_NAME     R3341 1
 '@S9S_MB_2U_LIB.S9S_MB_2U(SCH_1):PAGE228_I264@PURE_QUANTA.Q_RES(CHIPS)':
 'A': CDS_PINID='A';
NET_NAME
'SMB_HOST_CLK_BUF_3V3AUX_SCL'
 '@S9S_MB_2U_LIB.S9S_MB_2U(SCH_1):SMB_HOST_CLK_BUF_3V3AUX_SCL':
 C_SIGNAL='@s9s_mb_2u_lib.s9s_mb_2u(sch_1):smb_host_clk_buf_3v3aux_scl';
NODE_NAME     R107 2
 '@S9S_MB_2U_LIB.S9S_MB_2U(SCH_1):PAGE228_I43@PURE_QUANTA.Q_RES(CHIPS)':
 'B': CDS_PINID='B';
NODE_NAME     U315 2
 '@S9S_MB_2U_LIB.S9S_MB_2U(SCH_1):PAGE225_I17@PURE_QUANTA.PCA9617ADP(CHIPS)':
 'SCLA': CDS_PINID='SCLA';
NET_NAME
'SMB_HOST_CLK_BUF_3V3AUX_SDA'
 '@S9S_MB_2U_LIB.S9S_MB_2U(SCH_1):SMB_HOST_CLK_BUF_3V3AUX_SDA':
 C_SIGNAL='@s9s_mb_2u_lib.s9s_mb_2u(sch_1):smb_host_clk_buf_3v3aux_sda';
NODE_NAME     R108 2
 '@S9S_MB_2U_LIB.S9S_MB_2U(SCH_1):PAGE228_I42@PURE_QUANTA.Q_RES(CHIPS)':
 'B': CDS_PINID='B';
NODE_NAME     U315 3
 '@S9S_MB_2U_LIB.S9S_MB_2U(SCH_1):PAGE225_I17@PURE_QUANTA.PCA9617ADP(CHIPS)':
 'SDAA': CDS_PINID='SDAA';
NET_NAME
'SMB_HOST_CLK_BUF_ISO_3V3AUX_SCL'
 '@S9S_MB_2U_LIB.S9S_MB_2U(SCH_1):SMB_HOST_CLK_BUF_ISO_3V3AUX_SCL':
 C_SIGNAL='@s9s_mb_2u_lib.s9s_mb_2u(sch_1):smb_host_clk_buf_iso_3v3aux_scl';
NODE_NAME     R4480 1
 '@S9S_MB_2U_LIB.S9S_MB_2U(SCH_1):PAGE225_I24@PURE_QUANTA.Q_RES(CHIPS)':
 'A': CDS_PINID='A';
NODE_NAME     R4496 1
 '@S9S_MB_2U_LIB.S9S_MB_2U(SCH_1):PAGE225_I27@PURE_QUANTA.Q_RES(CHIPS)':
 'A': CDS_PINID='A';
NODE_NAME     R4540 2
 '@S9S_MB_2U_LIB.S9S_MB_2U(SCH_1):PAGE225_I33@PURE_QUANTA.Q_RES(CHIPS)':
 'B': CDS_PINID='B';
NET_NAME
'SMB_HOST_CLK_BUF_ISO_3V3AUX_SDA'
 '@S9S_MB_2U_LIB.S9S_MB_2U(SCH_1):SMB_HOST_CLK_BUF_ISO_3V3AUX_SDA':
 C_SIGNAL='@s9s_mb_2u_lib.s9s_mb_2u(sch_1):smb_host_clk_buf_iso_3v3aux_sda';
NODE_NAME     R4481 1
 '@S9S_MB_2U_LIB.S9S_MB_2U(SCH_1):PAGE225_I25@PURE_QUANTA.Q_RES(CHIPS)':
 'A': CDS_PINID='A';
NODE_NAME     R4497 1
 '@S9S_MB_2U_LIB.S9S_MB_2U(SCH_1):PAGE225_I26@PURE_QUANTA.Q_RES(CHIPS)':
 'A': CDS_PINID='A';
NODE_NAME     R4541 2
 '@S9S_MB_2U_LIB.S9S_MB_2U(SCH_1):PAGE225_I34@PURE_QUANTA.Q_RES(CHIPS)':
 'B': CDS_PINID='B';
NET_NAME
'SMB_HOST_CLK_BUF_ISO_3V3AUX_S_1'
 '@S9S_MB_2U_LIB.S9S_MB_2U(SCH_1):SMB_HOST_CLK_BUF_ISO_3V3AUX_SCL_R':
 C_SIGNAL='@s9s_mb_2u_lib.s9s_mb_2u(sch_1):smb_host_clk_buf_iso_3v3aux_scl_r';
NODE_NAME     R4498 2
 '@S9S_MB_2U_LIB.S9S_MB_2U(SCH_1):PAGE225_I11@PURE_QUANTA.Q_RES(CHIPS)':
 'B': CDS_PINID='B';
NODE_NAME     U315 7
 '@S9S_MB_2U_LIB.S9S_MB_2U(SCH_1):PAGE225_I17@PURE_QUANTA.PCA9617ADP(CHIPS)':
 'SCLB': CDS_PINID='SCLB';
NODE_NAME     R4540 1
 '@S9S_MB_2U_LIB.S9S_MB_2U(SCH_1):PAGE225_I33@PURE_QUANTA.Q_RES(CHIPS)':
 'A': CDS_PINID='A';
NET_NAME
'SMB_HOST_CLK_BUF_ISO_3V3AUX_S_2'
 '@S9S_MB_2U_LIB.S9S_MB_2U(SCH_1):SMB_HOST_CLK_BUF_ISO_3V3AUX_SDA_R':
 C_SIGNAL='@s9s_mb_2u_lib.s9s_mb_2u(sch_1):smb_host_clk_buf_iso_3v3aux_sda_r';
NODE_NAME     R4499 2
 '@S9S_MB_2U_LIB.S9S_MB_2U(SCH_1):PAGE225_I12@PURE_QUANTA.Q_RES(CHIPS)':
 'B': CDS_PINID='B';
NODE_NAME     U315 6
 '@S9S_MB_2U_LIB.S9S_MB_2U(SCH_1):PAGE225_I17@PURE_QUANTA.PCA9617ADP(CHIPS)':
 'SDAB': CDS_PINID='SDAB';
NODE_NAME     R4541 1
 '@S9S_MB_2U_LIB.S9S_MB_2U(SCH_1):PAGE225_I34@PURE_QUANTA.Q_RES(CHIPS)':
 'A': CDS_PINID='A';
NET_NAME
'SMB_HOST_CLK_GEN2_3V3AUX_SCL'
 '@S9S_MB_2U_LIB.S9S_MB_2U(SCH_1):SMB_HOST_CLK_GEN2_3V3AUX_SCL':
 C_SIGNAL='@s9s_mb_2u_lib.s9s_mb_2u(sch_1):smb_host_clk_gen2_3v3aux_scl';
NODE_NAME     R3340 2
 '@S9S_MB_2U_LIB.S9S_MB_2U(SCH_1):PAGE228_I268@PURE_QUANTA.Q_RES(CHIPS)':
 'B': CDS_PINID='B';
NODE_NAME     U247 8
 '@S9S_MB_2U_LIB.S9S_MB_2U(SCH_1):PAGE201_I167@PURE_QUANTA.9FGL0251DKILFT(CHIPS)':
 'SCLK_3.3': CDS_PINID='\sclk_3.3\';
NET_NAME
'SMB_HOST_CLK_GEN2_3V3AUX_SDA'
 '@S9S_MB_2U_LIB.S9S_MB_2U(SCH_1):SMB_HOST_CLK_GEN2_3V3AUX_SDA':
 C_SIGNAL='@s9s_mb_2u_lib.s9s_mb_2u(sch_1):smb_host_clk_gen2_3v3aux_sda';
NODE_NAME     R3341 2
 '@S9S_MB_2U_LIB.S9S_MB_2U(SCH_1):PAGE228_I264@PURE_QUANTA.Q_RES(CHIPS)':
 'B': CDS_PINID='B';
NODE_NAME     U247 9
 '@S9S_MB_2U_LIB.S9S_MB_2U(SCH_1):PAGE201_I167@PURE_QUANTA.9FGL0251DKILFT(CHIPS)':
 'SDATA_3.3': CDS_PINID='\sdata_3.3\';
NET_NAME
'SMB_HOST_DB2000_3V3AUX_SCL'
 '@S9S_MB_2U_LIB.S9S_MB_2U(SCH_1):SMB_HOST_DB2000_3V3AUX_SCL':
 C_SIGNAL='@s9s_mb_2u_lib.s9s_mb_2u(sch_1):smb_host_db2000_3v3aux_scl';
NODE_NAME     U38 L5
 '@S9S_MB_2U_LIB.S9S_MB_2U(SCH_1):PAGE195_I119@PURE_QUANTA.9QXL2001BNHGI8(CHIPS)':
 'SMBCLK': CDS_PINID='SMBCLK';
NODE_NAME     R4496 2
 '@S9S_MB_2U_LIB.S9S_MB_2U(SCH_1):PAGE225_I27@PURE_QUANTA.Q_RES(CHIPS)':
 'B': CDS_PINID='B';
NET_NAME
'SMB_HOST_DB2000_3V3AUX_SDA'
 '@S9S_MB_2U_LIB.S9S_MB_2U(SCH_1):SMB_HOST_DB2000_3V3AUX_SDA':
 C_SIGNAL='@s9s_mb_2u_lib.s9s_mb_2u(sch_1):smb_host_db2000_3v3aux_sda';
NODE_NAME     U38 L4
 '@S9S_MB_2U_LIB.S9S_MB_2U(SCH_1):PAGE195_I119@PURE_QUANTA.9QXL2001BNHGI8(CHIPS)':
 'SMBDAT': CDS_PINID='SMBDAT';
NODE_NAME     R4497 2
 '@S9S_MB_2U_LIB.S9S_MB_2U(SCH_1):PAGE225_I26@PURE_QUANTA.Q_RES(CHIPS)':
 'B': CDS_PINID='B';
NET_NAME
'SMB_HOST_ME_SCL'
 '@S9S_MB_2U_LIB.S9S_MB_2U(SCH_1):SMB_HOST_ME_SCL':
 C_SIGNAL='@s9s_mb_2u_lib.s9s_mb_2u(sch_1):smb_host_me_scl';
NODE_NAME     R3052 2
 '@S9S_MB_2U_LIB.S9S_MB_2U(SCH_1):PAGE215_I13@PURE_QUANTA.Q_RES(CHIPS)':
 'B': CDS_PINID='B';
NODE_NAME     J100 11
 '@S9S_MB_2U_LIB.S9S_MB_2U(SCH_1):PAGE215_I32@PURE_QUANTA.SCONN20_513860200CV01(CHIPS)':
 '11': CDS_PINID='\11\';
NET_NAME
'SMB_HOST_ME_SDA'
 '@S9S_MB_2U_LIB.S9S_MB_2U(SCH_1):SMB_HOST_ME_SDA':
 C_SIGNAL='@s9s_mb_2u_lib.s9s_mb_2u(sch_1):smb_host_me_sda';
NODE_NAME     R3053 2
 '@S9S_MB_2U_LIB.S9S_MB_2U(SCH_1):PAGE215_I12@PURE_QUANTA.Q_RES(CHIPS)':
 'B': CDS_PINID='B';
NODE_NAME     J100 13
 '@S9S_MB_2U_LIB.S9S_MB_2U(SCH_1):PAGE215_I32@PURE_QUANTA.SCONN20_513860200CV01(CHIPS)':
 '13': CDS_PINID='\13\';
NET_NAME
'SMB_HSC_TYPE_ADC_SCL'
 '@S9S_MB_2U_LIB.S9S_MB_2U(SCH_1):SMB_HSC_TYPE_ADC_SCL':
 C_SIGNAL='@s9s_mb_2u_lib.s9s_mb_2u(sch_1):smb_hsc_type_adc_scl';
NODE_NAME     R4689 2
 '@S9S_MB_2U_LIB.S9S_MB_2U(SCH_1):PAGE240_I38@PURE_QUANTA.Q_RES(CHIPS)':
 'B': CDS_PINID='B';
NODE_NAME     U331 5
 '@S9S_MB_2U_LIB.S9S_MB_2U(SCH_1):PAGE240_I39@PURE_QUANTA.INA230AIRGTR(CHIPS)':
 'SCL': CDS_PINID='SCL';
NET_NAME
'SMB_HSC_TYPE_ADC_SDA'
 '@S9S_MB_2U_LIB.S9S_MB_2U(SCH_1):SMB_HSC_TYPE_ADC_SDA':
 C_SIGNAL='@s9s_mb_2u_lib.s9s_mb_2u(sch_1):smb_hsc_type_adc_sda';
NODE_NAME     R4691 2
 '@S9S_MB_2U_LIB.S9S_MB_2U(SCH_1):PAGE240_I16@PURE_QUANTA.Q_RES(CHIPS)':
 'B': CDS_PINID='B';
NODE_NAME     R4690 2
 '@S9S_MB_2U_LIB.S9S_MB_2U(SCH_1):PAGE240_I37@PURE_QUANTA.Q_RES(CHIPS)':
 'B': CDS_PINID='B';
NODE_NAME     U331 4
 '@S9S_MB_2U_LIB.S9S_MB_2U(SCH_1):PAGE240_I39@PURE_QUANTA.INA230AIRGTR(CHIPS)':
 'SDA': CDS_PINID='SDA';
NET_NAME
'SMB_INA230_1_3V3AUX_SCL_R'
 '@S9S_MB_2U_LIB.S9S_MB_2U(SCH_1):SMB_INA230_1_3V3AUX_SCL_R':
 C_SIGNAL='@s9s_mb_2u_lib.s9s_mb_2u(sch_1):smb_ina230_1_3v3aux_scl_r';
NODE_NAME     R3586 2
 '@S9S_MB_2U_LIB.S9S_MB_2U(SCH_1):PAGE220_I4@PURE_QUANTA.Q_RES(CHIPS)':
 'B': CDS_PINID='B';
NODE_NAME     R3600 1
 '@S9S_MB_2U_LIB.S9S_MB_2U(SCH_1):PAGE295_I38@PURE_QUANTA.Q_RES(CHIPS)':
 'A': CDS_PINID='A';
NET_NAME
'SMB_INA230_1_3V3AUX_SCL_R1'
 '@S9S_MB_2U_LIB.S9S_MB_2U(SCH_1):SMB_INA230_1_3V3AUX_SCL_R1':
 C_SIGNAL='@s9s_mb_2u_lib.s9s_mb_2u(sch_1):smb_ina230_1_3v3aux_scl_r1';
NODE_NAME     U266 5
 '@S9S_MB_2U_LIB.S9S_MB_2U(SCH_1):PAGE295_I30@PURE_QUANTA.INA230AIRGTR(CHIPS)':
 'SCL': CDS_PINID='SCL';
NODE_NAME     R3600 2
 '@S9S_MB_2U_LIB.S9S_MB_2U(SCH_1):PAGE295_I38@PURE_QUANTA.Q_RES(CHIPS)':
 'B': CDS_PINID='B';
NET_NAME
'SMB_INA230_1_3V3AUX_SDA_R'
 '@S9S_MB_2U_LIB.S9S_MB_2U(SCH_1):SMB_INA230_1_3V3AUX_SDA_R':
 C_SIGNAL='@s9s_mb_2u_lib.s9s_mb_2u(sch_1):smb_ina230_1_3v3aux_sda_r';
NODE_NAME     R3587 2
 '@S9S_MB_2U_LIB.S9S_MB_2U(SCH_1):PAGE220_I3@PURE_QUANTA.Q_RES(CHIPS)':
 'B': CDS_PINID='B';
NODE_NAME     R3601 1
 '@S9S_MB_2U_LIB.S9S_MB_2U(SCH_1):PAGE295_I39@PURE_QUANTA.Q_RES(CHIPS)':
 'A': CDS_PINID='A';
NET_NAME
'SMB_INA230_1_3V3AUX_SDA_R1'
 '@S9S_MB_2U_LIB.S9S_MB_2U(SCH_1):SMB_INA230_1_3V3AUX_SDA_R1':
 C_SIGNAL='@s9s_mb_2u_lib.s9s_mb_2u(sch_1):smb_ina230_1_3v3aux_sda_r1';
NODE_NAME     U266 4
 '@S9S_MB_2U_LIB.S9S_MB_2U(SCH_1):PAGE295_I30@PURE_QUANTA.INA230AIRGTR(CHIPS)':
 'SDA': CDS_PINID='SDA';
NODE_NAME     R3601 2
 '@S9S_MB_2U_LIB.S9S_MB_2U(SCH_1):PAGE295_I39@PURE_QUANTA.Q_RES(CHIPS)':
 'B': CDS_PINID='B';
NET_NAME
'SMB_INA230_2_3V3AUX_SCL_R'
 '@S9S_MB_2U_LIB.S9S_MB_2U(SCH_1):SMB_INA230_2_3V3AUX_SCL_R':
 C_SIGNAL='@s9s_mb_2u_lib.s9s_mb_2u(sch_1):smb_ina230_2_3v3aux_scl_r';
NODE_NAME     R3588 2
 '@S9S_MB_2U_LIB.S9S_MB_2U(SCH_1):PAGE220_I16@PURE_QUANTA.Q_RES(CHIPS)':
 'B': CDS_PINID='B';
NODE_NAME     R3754 1
 '@S9S_MB_2U_LIB.S9S_MB_2U(SCH_1):PAGE295_I130@PURE_QUANTA.Q_RES(CHIPS)':
 'A': CDS_PINID='A';
NET_NAME
'SMB_INA230_2_3V3AUX_SCL_R1'
 '@S9S_MB_2U_LIB.S9S_MB_2U(SCH_1):SMB_INA230_2_3V3AUX_SCL_R1':
 C_SIGNAL='@s9s_mb_2u_lib.s9s_mb_2u(sch_1):smb_ina230_2_3v3aux_scl_r1';
NODE_NAME     U276 5
 '@S9S_MB_2U_LIB.S9S_MB_2U(SCH_1):PAGE295_I129@PURE_QUANTA.INA230AIRGTR(CHIPS)':
 'SCL': CDS_PINID='SCL';
NODE_NAME     R3754 2
 '@S9S_MB_2U_LIB.S9S_MB_2U(SCH_1):PAGE295_I130@PURE_QUANTA.Q_RES(CHIPS)':
 'B': CDS_PINID='B';
NET_NAME
'SMB_INA230_2_3V3AUX_SDA_R'
 '@S9S_MB_2U_LIB.S9S_MB_2U(SCH_1):SMB_INA230_2_3V3AUX_SDA_R':
 C_SIGNAL='@s9s_mb_2u_lib.s9s_mb_2u(sch_1):smb_ina230_2_3v3aux_sda_r';
NODE_NAME     R3589 2
 '@S9S_MB_2U_LIB.S9S_MB_2U(SCH_1):PAGE220_I11@PURE_QUANTA.Q_RES(CHIPS)':
 'B': CDS_PINID='B';
NODE_NAME     R3756 1
 '@S9S_MB_2U_LIB.S9S_MB_2U(SCH_1):PAGE295_I131@PURE_QUANTA.Q_RES(CHIPS)':
 'A': CDS_PINID='A';
NET_NAME
'SMB_INA230_2_3V3AUX_SDA_R1'
 '@S9S_MB_2U_LIB.S9S_MB_2U(SCH_1):SMB_INA230_2_3V3AUX_SDA_R1':
 C_SIGNAL='@s9s_mb_2u_lib.s9s_mb_2u(sch_1):smb_ina230_2_3v3aux_sda_r1';
NODE_NAME     U276 4
 '@S9S_MB_2U_LIB.S9S_MB_2U(SCH_1):PAGE295_I129@PURE_QUANTA.INA230AIRGTR(CHIPS)':
 'SDA': CDS_PINID='SDA';
NODE_NAME     R3756 2
 '@S9S_MB_2U_LIB.S9S_MB_2U(SCH_1):PAGE295_I131@PURE_QUANTA.Q_RES(CHIPS)':
 'B': CDS_PINID='B';
NODE_NAME     R3751 2
 '@S9S_MB_2U_LIB.S9S_MB_2U(SCH_1):PAGE295_I146@PURE_QUANTA.Q_RES(CHIPS)':
 'B': CDS_PINID='B';
NET_NAME
'SMB_INA230_3V3AUX_SCL'
 '@S9S_MB_2U_LIB.S9S_MB_2U(SCH_1):SMB_INA230_3V3AUX_SCL':
 C_SIGNAL='@s9s_mb_2u_lib.s9s_mb_2u(sch_1):smb_ina230_3v3aux_scl';
NODE_NAME     R3586 1
 '@S9S_MB_2U_LIB.S9S_MB_2U(SCH_1):PAGE220_I4@PURE_QUANTA.Q_RES(CHIPS)':
 'A': CDS_PINID='A';
NODE_NAME     R3588 1
 '@S9S_MB_2U_LIB.S9S_MB_2U(SCH_1):PAGE220_I16@PURE_QUANTA.Q_RES(CHIPS)':
 'A': CDS_PINID='A';
NODE_NAME     R3590 1
 '@S9S_MB_2U_LIB.S9S_MB_2U(SCH_1):PAGE220_I17@PURE_QUANTA.Q_RES(CHIPS)':
 'A': CDS_PINID='A';
NODE_NAME     R3592 1
 '@S9S_MB_2U_LIB.S9S_MB_2U(SCH_1):PAGE220_I20@PURE_QUANTA.Q_RES(CHIPS)':
 'A': CDS_PINID='A';
NODE_NAME     R3594 1
 '@S9S_MB_2U_LIB.S9S_MB_2U(SCH_1):PAGE220_I21@PURE_QUANTA.Q_RES(CHIPS)':
 'A': CDS_PINID='A';
NODE_NAME     R3395 2
 '@S9S_MB_2U_LIB.S9S_MB_2U(SCH_1):PAGE219_I54@PURE_QUANTA.Q_RES(CHIPS)':
 'B': CDS_PINID='B';
NODE_NAME     R3580 2
 '@S9S_MB_2U_LIB.S9S_MB_2U(SCH_1):PAGE219_I59@PURE_QUANTA.Q_RES(CHIPS)':
 'B': CDS_PINID='B';
NET_NAME
'SMB_INA230_3V3AUX_SCL_R'
 '@S9S_MB_2U_LIB.S9S_MB_2U(SCH_1):SMB_INA230_3V3AUX_SCL_R':
 C_SIGNAL='@s9s_mb_2u_lib.s9s_mb_2u(sch_1):smb_ina230_3v3aux_scl_r';
NODE_NAME     U36 18
 '@S9S_MB_2U_LIB.S9S_MB_2U(SCH_1):PAGE219_I45@PURE_QUANTA.TCA9548APWR(CHIPS)':
 'SC6': CDS_PINID='SC6';
NODE_NAME     R3580 1
 '@S9S_MB_2U_LIB.S9S_MB_2U(SCH_1):PAGE219_I59@PURE_QUANTA.Q_RES(CHIPS)':
 'A': CDS_PINID='A';
NET_NAME
'SMB_INA230_3V3AUX_SDA'
 '@S9S_MB_2U_LIB.S9S_MB_2U(SCH_1):SMB_INA230_3V3AUX_SDA':
 C_SIGNAL='@s9s_mb_2u_lib.s9s_mb_2u(sch_1):smb_ina230_3v3aux_sda';
NODE_NAME     R3587 1
 '@S9S_MB_2U_LIB.S9S_MB_2U(SCH_1):PAGE220_I3@PURE_QUANTA.Q_RES(CHIPS)':
 'A': CDS_PINID='A';
NODE_NAME     R3589 1
 '@S9S_MB_2U_LIB.S9S_MB_2U(SCH_1):PAGE220_I11@PURE_QUANTA.Q_RES(CHIPS)':
 'A': CDS_PINID='A';
NODE_NAME     R3591 1
 '@S9S_MB_2U_LIB.S9S_MB_2U(SCH_1):PAGE220_I18@PURE_QUANTA.Q_RES(CHIPS)':
 'A': CDS_PINID='A';
NODE_NAME     R3593 1
 '@S9S_MB_2U_LIB.S9S_MB_2U(SCH_1):PAGE220_I19@PURE_QUANTA.Q_RES(CHIPS)':
 'A': CDS_PINID='A';
NODE_NAME     R3595 1
 '@S9S_MB_2U_LIB.S9S_MB_2U(SCH_1):PAGE220_I26@PURE_QUANTA.Q_RES(CHIPS)':
 'A': CDS_PINID='A';
NODE_NAME     R3396 2
 '@S9S_MB_2U_LIB.S9S_MB_2U(SCH_1):PAGE219_I53@PURE_QUANTA.Q_RES(CHIPS)':
 'B': CDS_PINID='B';
NODE_NAME     R3581 2
 '@S9S_MB_2U_LIB.S9S_MB_2U(SCH_1):PAGE219_I60@PURE_QUANTA.Q_RES(CHIPS)':
 'B': CDS_PINID='B';
NET_NAME
'SMB_INA230_3V3AUX_SDA_R'
 '@S9S_MB_2U_LIB.S9S_MB_2U(SCH_1):SMB_INA230_3V3AUX_SDA_R':
 C_SIGNAL='@s9s_mb_2u_lib.s9s_mb_2u(sch_1):smb_ina230_3v3aux_sda_r';
NODE_NAME     U36 17
 '@S9S_MB_2U_LIB.S9S_MB_2U(SCH_1):PAGE219_I45@PURE_QUANTA.TCA9548APWR(CHIPS)':
 'SD6': CDS_PINID='SD6';
NODE_NAME     R3581 1
 '@S9S_MB_2U_LIB.S9S_MB_2U(SCH_1):PAGE219_I60@PURE_QUANTA.Q_RES(CHIPS)':
 'A': CDS_PINID='A';
NET_NAME
'SMB_INA230_3_3V3AUX_SCL_R'
 '@S9S_MB_2U_LIB.S9S_MB_2U(SCH_1):SMB_INA230_3_3V3AUX_SCL_R':
 C_SIGNAL='@s9s_mb_2u_lib.s9s_mb_2u(sch_1):smb_ina230_3_3v3aux_scl_r';
NODE_NAME     R3590 2
 '@S9S_MB_2U_LIB.S9S_MB_2U(SCH_1):PAGE220_I17@PURE_QUANTA.Q_RES(CHIPS)':
 'B': CDS_PINID='B';
NODE_NAME     R3568 1
 '@S9S_MB_2U_LIB.S9S_MB_2U(SCH_1):PAGE163_I101@PURE_QUANTA.Q_RES(CHIPS)':
 'A': CDS_PINID='A';
NET_NAME
'SMB_INA230_3_3V3AUX_SCL_R1'
 '@S9S_MB_2U_LIB.S9S_MB_2U(SCH_1):SMB_INA230_3_3V3AUX_SCL_R1':
 C_SIGNAL='@s9s_mb_2u_lib.s9s_mb_2u(sch_1):smb_ina230_3_3v3aux_scl_r1';
NODE_NAME     U263 5
 '@S9S_MB_2U_LIB.S9S_MB_2U(SCH_1):PAGE163_I94@PURE_QUANTA.INA230AIRGTR(CHIPS)':
 'SCL': CDS_PINID='SCL';
NODE_NAME     R3620 2
 '@S9S_MB_2U_LIB.S9S_MB_2U(SCH_1):PAGE163_I100@PURE_QUANTA.Q_RES(CHIPS)':
 'B': CDS_PINID='B';
NODE_NAME     R3568 2
 '@S9S_MB_2U_LIB.S9S_MB_2U(SCH_1):PAGE163_I101@PURE_QUANTA.Q_RES(CHIPS)':
 'B': CDS_PINID='B';
NET_NAME
'SMB_INA230_3_3V3AUX_SDA_R'
 '@S9S_MB_2U_LIB.S9S_MB_2U(SCH_1):SMB_INA230_3_3V3AUX_SDA_R':
 C_SIGNAL='@s9s_mb_2u_lib.s9s_mb_2u(sch_1):smb_ina230_3_3v3aux_sda_r';
NODE_NAME     R3591 2
 '@S9S_MB_2U_LIB.S9S_MB_2U(SCH_1):PAGE220_I18@PURE_QUANTA.Q_RES(CHIPS)':
 'B': CDS_PINID='B';
NODE_NAME     R3569 1
 '@S9S_MB_2U_LIB.S9S_MB_2U(SCH_1):PAGE163_I102@PURE_QUANTA.Q_RES(CHIPS)':
 'A': CDS_PINID='A';
NET_NAME
'SMB_INA230_3_3V3AUX_SDA_R1'
 '@S9S_MB_2U_LIB.S9S_MB_2U(SCH_1):SMB_INA230_3_3V3AUX_SDA_R1':
 C_SIGNAL='@s9s_mb_2u_lib.s9s_mb_2u(sch_1):smb_ina230_3_3v3aux_sda_r1';
NODE_NAME     U263 4
 '@S9S_MB_2U_LIB.S9S_MB_2U(SCH_1):PAGE163_I94@PURE_QUANTA.INA230AIRGTR(CHIPS)':
 'SDA': CDS_PINID='SDA';
NODE_NAME     R3569 2
 '@S9S_MB_2U_LIB.S9S_MB_2U(SCH_1):PAGE163_I102@PURE_QUANTA.Q_RES(CHIPS)':
 'B': CDS_PINID='B';
NET_NAME
'SMB_INA230_4_3V3AUX_SCL_R'
 '@S9S_MB_2U_LIB.S9S_MB_2U(SCH_1):SMB_INA230_4_3V3AUX_SCL_R':
 C_SIGNAL='@s9s_mb_2u_lib.s9s_mb_2u(sch_1):smb_ina230_4_3v3aux_scl_r';
NODE_NAME     R3594 2
 '@S9S_MB_2U_LIB.S9S_MB_2U(SCH_1):PAGE220_I21@PURE_QUANTA.Q_RES(CHIPS)':
 'B': CDS_PINID='B';
NODE_NAME     R3572 1
 '@S9S_MB_2U_LIB.S9S_MB_2U(SCH_1):PAGE163_I38@PURE_QUANTA.Q_RES(CHIPS)':
 'A': CDS_PINID='A';
NET_NAME
'SMB_INA230_4_3V3AUX_SCL_R1'
 '@S9S_MB_2U_LIB.S9S_MB_2U(SCH_1):SMB_INA230_4_3V3AUX_SCL_R1':
 C_SIGNAL='@s9s_mb_2u_lib.s9s_mb_2u(sch_1):smb_ina230_4_3v3aux_scl_r1';
NODE_NAME     R3572 2
 '@S9S_MB_2U_LIB.S9S_MB_2U(SCH_1):PAGE163_I38@PURE_QUANTA.Q_RES(CHIPS)':
 'B': CDS_PINID='B';
NODE_NAME     U264 5
 '@S9S_MB_2U_LIB.S9S_MB_2U(SCH_1):PAGE163_I46@PURE_QUANTA.INA230AIRGTR(CHIPS)':
 'SCL': CDS_PINID='SCL';
NET_NAME
'SMB_INA230_4_3V3AUX_SDA_R'
 '@S9S_MB_2U_LIB.S9S_MB_2U(SCH_1):SMB_INA230_4_3V3AUX_SDA_R':
 C_SIGNAL='@s9s_mb_2u_lib.s9s_mb_2u(sch_1):smb_ina230_4_3v3aux_sda_r';
NODE_NAME     R3595 2
 '@S9S_MB_2U_LIB.S9S_MB_2U(SCH_1):PAGE220_I26@PURE_QUANTA.Q_RES(CHIPS)':
 'B': CDS_PINID='B';
NODE_NAME     R3573 1
 '@S9S_MB_2U_LIB.S9S_MB_2U(SCH_1):PAGE163_I37@PURE_QUANTA.Q_RES(CHIPS)':
 'A': CDS_PINID='A';
NET_NAME
'SMB_INA230_4_3V3AUX_SDA_R1'
 '@S9S_MB_2U_LIB.S9S_MB_2U(SCH_1):SMB_INA230_4_3V3AUX_SDA_R1':
 C_SIGNAL='@s9s_mb_2u_lib.s9s_mb_2u(sch_1):smb_ina230_4_3v3aux_sda_r1';
NODE_NAME     R3573 2
 '@S9S_MB_2U_LIB.S9S_MB_2U(SCH_1):PAGE163_I37@PURE_QUANTA.Q_RES(CHIPS)':
 'B': CDS_PINID='B';
NODE_NAME     U264 4
 '@S9S_MB_2U_LIB.S9S_MB_2U(SCH_1):PAGE163_I46@PURE_QUANTA.INA230AIRGTR(CHIPS)':
 'SDA': CDS_PINID='SDA';
NET_NAME
'SMB_INA230_5_3V3AUX_SCL_R'
 '@S9S_MB_2U_LIB.S9S_MB_2U(SCH_1):SMB_INA230_5_3V3AUX_SCL_R':
 C_SIGNAL='@s9s_mb_2u_lib.s9s_mb_2u(sch_1):smb_ina230_5_3v3aux_scl_r';
NODE_NAME     R3592 2
 '@S9S_MB_2U_LIB.S9S_MB_2U(SCH_1):PAGE220_I20@PURE_QUANTA.Q_RES(CHIPS)':
 'B': CDS_PINID='B';
NODE_NAME     R3576 1
 '@S9S_MB_2U_LIB.S9S_MB_2U(SCH_1):PAGE163_I61@PURE_QUANTA.Q_RES(CHIPS)':
 'A': CDS_PINID='A';
NET_NAME
'SMB_INA230_5_3V3AUX_SCL_R1'
 '@S9S_MB_2U_LIB.S9S_MB_2U(SCH_1):SMB_INA230_5_3V3AUX_SCL_R1':
 C_SIGNAL='@s9s_mb_2u_lib.s9s_mb_2u(sch_1):smb_ina230_5_3v3aux_scl_r1';
NODE_NAME     R3576 2
 '@S9S_MB_2U_LIB.S9S_MB_2U(SCH_1):PAGE163_I61@PURE_QUANTA.Q_RES(CHIPS)':
 'B': CDS_PINID='B';
NODE_NAME     U265 5
 '@S9S_MB_2U_LIB.S9S_MB_2U(SCH_1):PAGE163_I69@PURE_QUANTA.INA230AIRGTR(CHIPS)':
 'SCL': CDS_PINID='SCL';
NET_NAME
'SMB_INA230_5_3V3AUX_SDA_R'
 '@S9S_MB_2U_LIB.S9S_MB_2U(SCH_1):SMB_INA230_5_3V3AUX_SDA_R':
 C_SIGNAL='@s9s_mb_2u_lib.s9s_mb_2u(sch_1):smb_ina230_5_3v3aux_sda_r';
NODE_NAME     R3593 2
 '@S9S_MB_2U_LIB.S9S_MB_2U(SCH_1):PAGE220_I19@PURE_QUANTA.Q_RES(CHIPS)':
 'B': CDS_PINID='B';
NODE_NAME     R3577 1
 '@S9S_MB_2U_LIB.S9S_MB_2U(SCH_1):PAGE163_I60@PURE_QUANTA.Q_RES(CHIPS)':
 'A': CDS_PINID='A';
NET_NAME
'SMB_INA230_5_3V3AUX_SDA_R1'
 '@S9S_MB_2U_LIB.S9S_MB_2U(SCH_1):SMB_INA230_5_3V3AUX_SDA_R1':
 C_SIGNAL='@s9s_mb_2u_lib.s9s_mb_2u(sch_1):smb_ina230_5_3v3aux_sda_r1';
NODE_NAME     R3577 2
 '@S9S_MB_2U_LIB.S9S_MB_2U(SCH_1):PAGE163_I60@PURE_QUANTA.Q_RES(CHIPS)':
 'B': CDS_PINID='B';
NODE_NAME     U265 4
 '@S9S_MB_2U_LIB.S9S_MB_2U(SCH_1):PAGE163_I69@PURE_QUANTA.INA230AIRGTR(CHIPS)':
 'SDA': CDS_PINID='SDA';
NET_NAME
'SMB_IOEXP_3V3AUX_SCL'
 '@S9S_MB_2U_LIB.S9S_MB_2U(SCH_1):SMB_IOEXP_3V3AUX_SCL':
 C_SIGNAL='@s9s_mb_2u_lib.s9s_mb_2u(sch_1):smb_ioexp_3v3aux_scl';
NODE_NAME     R2982 1
 '@S9S_MB_2U_LIB.S9S_MB_2U(SCH_1):PAGE214_I96@PURE_QUANTA.Q_RES(CHIPS)':
 'A': CDS_PINID='A';
NODE_NAME     R3393 2
 '@S9S_MB_2U_LIB.S9S_MB_2U(SCH_1):PAGE219_I38@PURE_QUANTA.Q_RES(CHIPS)':
 'B': CDS_PINID='B';
NODE_NAME     R3582 2
 '@S9S_MB_2U_LIB.S9S_MB_2U(SCH_1):PAGE219_I52@PURE_QUANTA.Q_RES(CHIPS)':
 'B': CDS_PINID='B';
NET_NAME
'SMB_IOEXP_3V3AUX_SCL_R'
 '@S9S_MB_2U_LIB.S9S_MB_2U(SCH_1):SMB_IOEXP_3V3AUX_SCL_R':
 C_SIGNAL='@s9s_mb_2u_lib.s9s_mb_2u(sch_1):smb_ioexp_3v3aux_scl_r';
NODE_NAME     R3393 1
 '@S9S_MB_2U_LIB.S9S_MB_2U(SCH_1):PAGE219_I38@PURE_QUANTA.Q_RES(CHIPS)':
 'A': CDS_PINID='A';
NODE_NAME     U36 7
 '@S9S_MB_2U_LIB.S9S_MB_2U(SCH_1):PAGE219_I45@PURE_QUANTA.TCA9548APWR(CHIPS)':
 'SC1': CDS_PINID='SC1';
NET_NAME
'SMB_IOEXP_3V3AUX_SCL_R1'
 '@S9S_MB_2U_LIB.S9S_MB_2U(SCH_1):SMB_IOEXP_3V3AUX_SCL_R1':
 C_SIGNAL='@s9s_mb_2u_lib.s9s_mb_2u(sch_1):smb_ioexp_3v3aux_scl_r1';
NODE_NAME     U181 22
 '@S9S_MB_2U_LIB.S9S_MB_2U(SCH_1):PAGE214_I66@PURE_QUANTA.PCA9539RPW(CHIPS)':
 'SCL': CDS_PINID='SCL';
NODE_NAME     R2982 2
 '@S9S_MB_2U_LIB.S9S_MB_2U(SCH_1):PAGE214_I96@PURE_QUANTA.Q_RES(CHIPS)':
 'B': CDS_PINID='B';
NET_NAME
'SMB_IOEXP_3V3AUX_SDA'
 '@S9S_MB_2U_LIB.S9S_MB_2U(SCH_1):SMB_IOEXP_3V3AUX_SDA':
 C_SIGNAL='@s9s_mb_2u_lib.s9s_mb_2u(sch_1):smb_ioexp_3v3aux_sda';
NODE_NAME     R2983 1
 '@S9S_MB_2U_LIB.S9S_MB_2U(SCH_1):PAGE214_I101@PURE_QUANTA.Q_RES(CHIPS)':
 'A': CDS_PINID='A';
NODE_NAME     R3394 2
 '@S9S_MB_2U_LIB.S9S_MB_2U(SCH_1):PAGE219_I40@PURE_QUANTA.Q_RES(CHIPS)':
 'B': CDS_PINID='B';
NODE_NAME     R3583 2
 '@S9S_MB_2U_LIB.S9S_MB_2U(SCH_1):PAGE219_I51@PURE_QUANTA.Q_RES(CHIPS)':
 'B': CDS_PINID='B';
NET_NAME
'SMB_IOEXP_3V3AUX_SDA_R'
 '@S9S_MB_2U_LIB.S9S_MB_2U(SCH_1):SMB_IOEXP_3V3AUX_SDA_R':
 C_SIGNAL='@s9s_mb_2u_lib.s9s_mb_2u(sch_1):smb_ioexp_3v3aux_sda_r';
NODE_NAME     R3394 1
 '@S9S_MB_2U_LIB.S9S_MB_2U(SCH_1):PAGE219_I40@PURE_QUANTA.Q_RES(CHIPS)':
 'A': CDS_PINID='A';
NODE_NAME     U36 6
 '@S9S_MB_2U_LIB.S9S_MB_2U(SCH_1):PAGE219_I45@PURE_QUANTA.TCA9548APWR(CHIPS)':
 'SD1': CDS_PINID='SD1';
NET_NAME
'SMB_IOEXP_3V3AUX_SDA_R1'
 '@S9S_MB_2U_LIB.S9S_MB_2U(SCH_1):SMB_IOEXP_3V3AUX_SDA_R1':
 C_SIGNAL='@s9s_mb_2u_lib.s9s_mb_2u(sch_1):smb_ioexp_3v3aux_sda_r1';
NODE_NAME     U181 23
 '@S9S_MB_2U_LIB.S9S_MB_2U(SCH_1):PAGE214_I66@PURE_QUANTA.PCA9539RPW(CHIPS)':
 'SDA': CDS_PINID='SDA';
NODE_NAME     R2983 2
 '@S9S_MB_2U_LIB.S9S_MB_2U(SCH_1):PAGE214_I101@PURE_QUANTA.Q_RES(CHIPS)':
 'B': CDS_PINID='B';
NET_NAME
'SMB_LM75_0_3V3AUX_SCL'
 '@S9S_MB_2U_LIB.S9S_MB_2U(SCH_1):SMB_LM75_0_3V3AUX_SCL':
 C_SIGNAL='@s9s_mb_2u_lib.s9s_mb_2u(sch_1):smb_lm75_0_3v3aux_scl';
NODE_NAME     R3725 2
 '@S9S_MB_2U_LIB.S9S_MB_2U(SCH_1):PAGE221_I53@PURE_QUANTA.Q_RES(CHIPS)':
 'B': CDS_PINID='B';
NODE_NAME     R4180 1
 '@S9S_MB_2U_LIB.S9S_MB_2U(SCH_1):PAGE161_I77@PURE_QUANTA.Q_RES(CHIPS)':
 'A': CDS_PINID='A';
NODE_NAME     R3715 2
 '@S9S_MB_2U_LIB.S9S_MB_2U(SCH_1):PAGE221_I139@PURE_QUANTA.Q_RES(CHIPS)':
 'B': CDS_PINID='B';
NODE_NAME     R4689 1
 '@S9S_MB_2U_LIB.S9S_MB_2U(SCH_1):PAGE240_I38@PURE_QUANTA.Q_RES(CHIPS)':
 'A': CDS_PINID='A';
NODE_NAME     R4894 2
 '@S9S_MB_2U_LIB.S9S_MB_2U(SCH_1):PAGE327_I15@PURE_QUANTA.Q_RES(CHIPS)':
 'B': CDS_PINID='B';
NET_NAME
'SMB_LM75_0_3V3AUX_SCL_R'
 '@S9S_MB_2U_LIB.S9S_MB_2U(SCH_1):SMB_LM75_0_3V3AUX_SCL_R':
 C_SIGNAL='@s9s_mb_2u_lib.s9s_mb_2u(sch_1):smb_lm75_0_3v3aux_scl_r';
NODE_NAME     U39 7
 '@S9S_MB_2U_LIB.S9S_MB_2U(SCH_1):PAGE221_I103@PURE_QUANTA.TCA9548APWR(CHIPS)':
 'SC1': CDS_PINID='SC1';
NODE_NAME     R3715 1
 '@S9S_MB_2U_LIB.S9S_MB_2U(SCH_1):PAGE221_I139@PURE_QUANTA.Q_RES(CHIPS)':
 'A': CDS_PINID='A';
NET_NAME
'SMB_LM75_0_3V3AUX_SCL_R1'
 '@S9S_MB_2U_LIB.S9S_MB_2U(SCH_1):SMB_LM75_0_3V3AUX_SCL_R1':
 C_SIGNAL='@s9s_mb_2u_lib.s9s_mb_2u(sch_1):smb_lm75_0_3v3aux_scl_r1';
NODE_NAME     R4180 2
 '@S9S_MB_2U_LIB.S9S_MB_2U(SCH_1):PAGE161_I77@PURE_QUANTA.Q_RES(CHIPS)':
 'B': CDS_PINID='B';
NODE_NAME     U270 2
 '@S9S_MB_2U_LIB.S9S_MB_2U(SCH_1):PAGE161_I164@PURE_QUANTA.LM75BD(CHIPS)':
 'SCL': CDS_PINID='SCL';
NET_NAME
'SMB_LM75_0_3V3AUX_SDA'
 '@S9S_MB_2U_LIB.S9S_MB_2U(SCH_1):SMB_LM75_0_3V3AUX_SDA':
 C_SIGNAL='@s9s_mb_2u_lib.s9s_mb_2u(sch_1):smb_lm75_0_3v3aux_sda';
NODE_NAME     R3726 2
 '@S9S_MB_2U_LIB.S9S_MB_2U(SCH_1):PAGE221_I52@PURE_QUANTA.Q_RES(CHIPS)':
 'B': CDS_PINID='B';
NODE_NAME     R4183 1
 '@S9S_MB_2U_LIB.S9S_MB_2U(SCH_1):PAGE161_I78@PURE_QUANTA.Q_RES(CHIPS)':
 'A': CDS_PINID='A';
NODE_NAME     R3716 2
 '@S9S_MB_2U_LIB.S9S_MB_2U(SCH_1):PAGE221_I140@PURE_QUANTA.Q_RES(CHIPS)':
 'B': CDS_PINID='B';
NODE_NAME     R4690 1
 '@S9S_MB_2U_LIB.S9S_MB_2U(SCH_1):PAGE240_I37@PURE_QUANTA.Q_RES(CHIPS)':
 'A': CDS_PINID='A';
NODE_NAME     R4895 2
 '@S9S_MB_2U_LIB.S9S_MB_2U(SCH_1):PAGE327_I16@PURE_QUANTA.Q_RES(CHIPS)':
 'B': CDS_PINID='B';
NET_NAME
'SMB_LM75_0_3V3AUX_SDA_R'
 '@S9S_MB_2U_LIB.S9S_MB_2U(SCH_1):SMB_LM75_0_3V3AUX_SDA_R':
 C_SIGNAL='@s9s_mb_2u_lib.s9s_mb_2u(sch_1):smb_lm75_0_3v3aux_sda_r';
NODE_NAME     U39 6
 '@S9S_MB_2U_LIB.S9S_MB_2U(SCH_1):PAGE221_I103@PURE_QUANTA.TCA9548APWR(CHIPS)':
 'SD1': CDS_PINID='SD1';
NODE_NAME     R3716 1
 '@S9S_MB_2U_LIB.S9S_MB_2U(SCH_1):PAGE221_I140@PURE_QUANTA.Q_RES(CHIPS)':
 'A': CDS_PINID='A';
NET_NAME
'SMB_LM75_0_3V3AUX_SDA_R1'
 '@S9S_MB_2U_LIB.S9S_MB_2U(SCH_1):SMB_LM75_0_3V3AUX_SDA_R1':
 C_SIGNAL='@s9s_mb_2u_lib.s9s_mb_2u(sch_1):smb_lm75_0_3v3aux_sda_r1';
NODE_NAME     R4183 2
 '@S9S_MB_2U_LIB.S9S_MB_2U(SCH_1):PAGE161_I78@PURE_QUANTA.Q_RES(CHIPS)':
 'B': CDS_PINID='B';
NODE_NAME     U270 1
 '@S9S_MB_2U_LIB.S9S_MB_2U(SCH_1):PAGE161_I164@PURE_QUANTA.LM75BD(CHIPS)':
 'SDA': CDS_PINID='SDA';
NET_NAME
'SMB_LM75_1_3V3AUX_SCL'
 '@S9S_MB_2U_LIB.S9S_MB_2U(SCH_1):SMB_LM75_1_3V3AUX_SCL':
 C_SIGNAL='@s9s_mb_2u_lib.s9s_mb_2u(sch_1):smb_lm75_1_3v3aux_scl';
NODE_NAME     R3727 2
 '@S9S_MB_2U_LIB.S9S_MB_2U(SCH_1):PAGE221_I51@PURE_QUANTA.Q_RES(CHIPS)':
 'B': CDS_PINID='B';
NODE_NAME     R4179 1
 '@S9S_MB_2U_LIB.S9S_MB_2U(SCH_1):PAGE161_I109@PURE_QUANTA.Q_RES(CHIPS)':
 'A': CDS_PINID='A';
NODE_NAME     R3717 2
 '@S9S_MB_2U_LIB.S9S_MB_2U(SCH_1):PAGE221_I141@PURE_QUANTA.Q_RES(CHIPS)':
 'B': CDS_PINID='B';
NET_NAME
'SMB_LM75_1_3V3AUX_SCL_R'
 '@S9S_MB_2U_LIB.S9S_MB_2U(SCH_1):SMB_LM75_1_3V3AUX_SCL_R':
 C_SIGNAL='@s9s_mb_2u_lib.s9s_mb_2u(sch_1):smb_lm75_1_3v3aux_scl_r';
NODE_NAME     U39 9
 '@S9S_MB_2U_LIB.S9S_MB_2U(SCH_1):PAGE221_I103@PURE_QUANTA.TCA9548APWR(CHIPS)':
 'SC2': CDS_PINID='SC2';
NODE_NAME     R3717 1
 '@S9S_MB_2U_LIB.S9S_MB_2U(SCH_1):PAGE221_I141@PURE_QUANTA.Q_RES(CHIPS)':
 'A': CDS_PINID='A';
NET_NAME
'SMB_LM75_1_3V3AUX_SCL_R1'
 '@S9S_MB_2U_LIB.S9S_MB_2U(SCH_1):SMB_LM75_1_3V3AUX_SCL_R1':
 C_SIGNAL='@s9s_mb_2u_lib.s9s_mb_2u(sch_1):smb_lm75_1_3v3aux_scl_r1';
NODE_NAME     R4179 2
 '@S9S_MB_2U_LIB.S9S_MB_2U(SCH_1):PAGE161_I109@PURE_QUANTA.Q_RES(CHIPS)':
 'B': CDS_PINID='B';
NODE_NAME     U271 2
 '@S9S_MB_2U_LIB.S9S_MB_2U(SCH_1):PAGE161_I165@PURE_QUANTA.LM75BD(CHIPS)':
 'SCL': CDS_PINID='SCL';
NET_NAME
'SMB_LM75_1_3V3AUX_SDA'
 '@S9S_MB_2U_LIB.S9S_MB_2U(SCH_1):SMB_LM75_1_3V3AUX_SDA':
 C_SIGNAL='@s9s_mb_2u_lib.s9s_mb_2u(sch_1):smb_lm75_1_3v3aux_sda';
NODE_NAME     R3728 2
 '@S9S_MB_2U_LIB.S9S_MB_2U(SCH_1):PAGE221_I50@PURE_QUANTA.Q_RES(CHIPS)':
 'B': CDS_PINID='B';
NODE_NAME     R4182 1
 '@S9S_MB_2U_LIB.S9S_MB_2U(SCH_1):PAGE161_I107@PURE_QUANTA.Q_RES(CHIPS)':
 'A': CDS_PINID='A';
NODE_NAME     R3718 2
 '@S9S_MB_2U_LIB.S9S_MB_2U(SCH_1):PAGE221_I142@PURE_QUANTA.Q_RES(CHIPS)':
 'B': CDS_PINID='B';
NET_NAME
'SMB_LM75_1_3V3AUX_SDA_R'
 '@S9S_MB_2U_LIB.S9S_MB_2U(SCH_1):SMB_LM75_1_3V3AUX_SDA_R':
 C_SIGNAL='@s9s_mb_2u_lib.s9s_mb_2u(sch_1):smb_lm75_1_3v3aux_sda_r';
NODE_NAME     U39 8
 '@S9S_MB_2U_LIB.S9S_MB_2U(SCH_1):PAGE221_I103@PURE_QUANTA.TCA9548APWR(CHIPS)':
 'SD2': CDS_PINID='SD2';
NODE_NAME     R3718 1
 '@S9S_MB_2U_LIB.S9S_MB_2U(SCH_1):PAGE221_I142@PURE_QUANTA.Q_RES(CHIPS)':
 'A': CDS_PINID='A';
NET_NAME
'SMB_LM75_1_3V3AUX_SDA_R1'
 '@S9S_MB_2U_LIB.S9S_MB_2U(SCH_1):SMB_LM75_1_3V3AUX_SDA_R1':
 C_SIGNAL='@s9s_mb_2u_lib.s9s_mb_2u(sch_1):smb_lm75_1_3v3aux_sda_r1';
NODE_NAME     R4182 2
 '@S9S_MB_2U_LIB.S9S_MB_2U(SCH_1):PAGE161_I107@PURE_QUANTA.Q_RES(CHIPS)':
 'B': CDS_PINID='B';
NODE_NAME     U271 1
 '@S9S_MB_2U_LIB.S9S_MB_2U(SCH_1):PAGE161_I165@PURE_QUANTA.LM75BD(CHIPS)':
 'SDA': CDS_PINID='SDA';
NET_NAME
'SMB_LM75_2_3V3AUX_SCL'
 '@S9S_MB_2U_LIB.S9S_MB_2U(SCH_1):SMB_LM75_2_3V3AUX_SCL':
 C_SIGNAL='@s9s_mb_2u_lib.s9s_mb_2u(sch_1):smb_lm75_2_3v3aux_scl';
NODE_NAME     R3729 2
 '@S9S_MB_2U_LIB.S9S_MB_2U(SCH_1):PAGE221_I48@PURE_QUANTA.Q_RES(CHIPS)':
 'B': CDS_PINID='B';
NODE_NAME     R4178 1
 '@S9S_MB_2U_LIB.S9S_MB_2U(SCH_1):PAGE161_I114@PURE_QUANTA.Q_RES(CHIPS)':
 'A': CDS_PINID='A';
NODE_NAME     R3719 2
 '@S9S_MB_2U_LIB.S9S_MB_2U(SCH_1):PAGE221_I143@PURE_QUANTA.Q_RES(CHIPS)':
 'B': CDS_PINID='B';
NET_NAME
'SMB_LM75_2_3V3AUX_SCL_R'
 '@S9S_MB_2U_LIB.S9S_MB_2U(SCH_1):SMB_LM75_2_3V3AUX_SCL_R':
 C_SIGNAL='@s9s_mb_2u_lib.s9s_mb_2u(sch_1):smb_lm75_2_3v3aux_scl_r';
NODE_NAME     U39 11
 '@S9S_MB_2U_LIB.S9S_MB_2U(SCH_1):PAGE221_I103@PURE_QUANTA.TCA9548APWR(CHIPS)':
 'SC3': CDS_PINID='SC3';
NODE_NAME     R3719 1
 '@S9S_MB_2U_LIB.S9S_MB_2U(SCH_1):PAGE221_I143@PURE_QUANTA.Q_RES(CHIPS)':
 'A': CDS_PINID='A';
NET_NAME
'SMB_LM75_2_3V3AUX_SCL_R1'
 '@S9S_MB_2U_LIB.S9S_MB_2U(SCH_1):SMB_LM75_2_3V3AUX_SCL_R1':
 C_SIGNAL='@s9s_mb_2u_lib.s9s_mb_2u(sch_1):smb_lm75_2_3v3aux_scl_r1';
NODE_NAME     R4178 2
 '@S9S_MB_2U_LIB.S9S_MB_2U(SCH_1):PAGE161_I114@PURE_QUANTA.Q_RES(CHIPS)':
 'B': CDS_PINID='B';
NODE_NAME     U272 2
 '@S9S_MB_2U_LIB.S9S_MB_2U(SCH_1):PAGE161_I166@PURE_QUANTA.LM75BD(CHIPS)':
 'SCL': CDS_PINID='SCL';
NET_NAME
'SMB_LM75_2_3V3AUX_SDA'
 '@S9S_MB_2U_LIB.S9S_MB_2U(SCH_1):SMB_LM75_2_3V3AUX_SDA':
 C_SIGNAL='@s9s_mb_2u_lib.s9s_mb_2u(sch_1):smb_lm75_2_3v3aux_sda';
NODE_NAME     R3730 2
 '@S9S_MB_2U_LIB.S9S_MB_2U(SCH_1):PAGE221_I49@PURE_QUANTA.Q_RES(CHIPS)':
 'B': CDS_PINID='B';
NODE_NAME     R4181 1
 '@S9S_MB_2U_LIB.S9S_MB_2U(SCH_1):PAGE161_I116@PURE_QUANTA.Q_RES(CHIPS)':
 'A': CDS_PINID='A';
NODE_NAME     R3720 2
 '@S9S_MB_2U_LIB.S9S_MB_2U(SCH_1):PAGE221_I144@PURE_QUANTA.Q_RES(CHIPS)':
 'B': CDS_PINID='B';
NET_NAME
'SMB_LM75_2_3V3AUX_SDA_R'
 '@S9S_MB_2U_LIB.S9S_MB_2U(SCH_1):SMB_LM75_2_3V3AUX_SDA_R':
 C_SIGNAL='@s9s_mb_2u_lib.s9s_mb_2u(sch_1):smb_lm75_2_3v3aux_sda_r';
NODE_NAME     U39 10
 '@S9S_MB_2U_LIB.S9S_MB_2U(SCH_1):PAGE221_I103@PURE_QUANTA.TCA9548APWR(CHIPS)':
 'SD3': CDS_PINID='SD3';
NODE_NAME     R3720 1
 '@S9S_MB_2U_LIB.S9S_MB_2U(SCH_1):PAGE221_I144@PURE_QUANTA.Q_RES(CHIPS)':
 'A': CDS_PINID='A';
NET_NAME
'SMB_LM75_2_3V3AUX_SDA_R1'
 '@S9S_MB_2U_LIB.S9S_MB_2U(SCH_1):SMB_LM75_2_3V3AUX_SDA_R1':
 C_SIGNAL='@s9s_mb_2u_lib.s9s_mb_2u(sch_1):smb_lm75_2_3v3aux_sda_r1';
NODE_NAME     R4181 2
 '@S9S_MB_2U_LIB.S9S_MB_2U(SCH_1):PAGE161_I116@PURE_QUANTA.Q_RES(CHIPS)':
 'B': CDS_PINID='B';
NODE_NAME     U272 1
 '@S9S_MB_2U_LIB.S9S_MB_2U(SCH_1):PAGE161_I166@PURE_QUANTA.LM75BD(CHIPS)':
 'SDA': CDS_PINID='SDA';
NET_NAME
'SMB_LM75_3_3V3AUX_SCL'
 '@S9S_MB_2U_LIB.S9S_MB_2U(SCH_1):SMB_LM75_3_3V3AUX_SCL':
 C_SIGNAL='@s9s_mb_2u_lib.s9s_mb_2u(sch_1):smb_lm75_3_3v3aux_scl';
NODE_NAME     R3731 2
 '@S9S_MB_2U_LIB.S9S_MB_2U(SCH_1):PAGE221_I98@PURE_QUANTA.Q_RES(CHIPS)':
 'B': CDS_PINID='B';
NODE_NAME     R3553 1
 '@S9S_MB_2U_LIB.S9S_MB_2U(SCH_1):PAGE161_I134@PURE_QUANTA.Q_RES(CHIPS)':
 'A': CDS_PINID='A';
NODE_NAME     R3721 2
 '@S9S_MB_2U_LIB.S9S_MB_2U(SCH_1):PAGE221_I120@PURE_QUANTA.Q_RES(CHIPS)':
 'B': CDS_PINID='B';
NET_NAME
'SMB_LM75_3_3V3AUX_SCL_R'
 '@S9S_MB_2U_LIB.S9S_MB_2U(SCH_1):SMB_LM75_3_3V3AUX_SCL_R':
 C_SIGNAL='@s9s_mb_2u_lib.s9s_mb_2u(sch_1):smb_lm75_3_3v3aux_scl_r';
NODE_NAME     U39 14
 '@S9S_MB_2U_LIB.S9S_MB_2U(SCH_1):PAGE221_I103@PURE_QUANTA.TCA9548APWR(CHIPS)':
 'SC4': CDS_PINID='SC4';
NODE_NAME     R3721 1
 '@S9S_MB_2U_LIB.S9S_MB_2U(SCH_1):PAGE221_I120@PURE_QUANTA.Q_RES(CHIPS)':
 'A': CDS_PINID='A';
NET_NAME
'SMB_LM75_3_3V3AUX_SCL_R1'
 '@S9S_MB_2U_LIB.S9S_MB_2U(SCH_1):SMB_LM75_3_3V3AUX_SCL_R1':
 C_SIGNAL='@s9s_mb_2u_lib.s9s_mb_2u(sch_1):smb_lm75_3_3v3aux_scl_r1';
NODE_NAME     R3553 2
 '@S9S_MB_2U_LIB.S9S_MB_2U(SCH_1):PAGE161_I134@PURE_QUANTA.Q_RES(CHIPS)':
 'B': CDS_PINID='B';
NODE_NAME     U273 2
 '@S9S_MB_2U_LIB.S9S_MB_2U(SCH_1):PAGE161_I167@PURE_QUANTA.LM75BD(CHIPS)':
 'SCL': CDS_PINID='SCL';
NET_NAME
'SMB_LM75_3_3V3AUX_SDA'
 '@S9S_MB_2U_LIB.S9S_MB_2U(SCH_1):SMB_LM75_3_3V3AUX_SDA':
 C_SIGNAL='@s9s_mb_2u_lib.s9s_mb_2u(sch_1):smb_lm75_3_3v3aux_sda';
NODE_NAME     R3732 2
 '@S9S_MB_2U_LIB.S9S_MB_2U(SCH_1):PAGE221_I34@PURE_QUANTA.Q_RES(CHIPS)':
 'B': CDS_PINID='B';
NODE_NAME     R3554 1
 '@S9S_MB_2U_LIB.S9S_MB_2U(SCH_1):PAGE161_I136@PURE_QUANTA.Q_RES(CHIPS)':
 'A': CDS_PINID='A';
NODE_NAME     R3722 2
 '@S9S_MB_2U_LIB.S9S_MB_2U(SCH_1):PAGE221_I119@PURE_QUANTA.Q_RES(CHIPS)':
 'B': CDS_PINID='B';
NET_NAME
'SMB_LM75_3_3V3AUX_SDA_R'
 '@S9S_MB_2U_LIB.S9S_MB_2U(SCH_1):SMB_LM75_3_3V3AUX_SDA_R':
 C_SIGNAL='@s9s_mb_2u_lib.s9s_mb_2u(sch_1):smb_lm75_3_3v3aux_sda_r';
NODE_NAME     U39 13
 '@S9S_MB_2U_LIB.S9S_MB_2U(SCH_1):PAGE221_I103@PURE_QUANTA.TCA9548APWR(CHIPS)':
 'SD4': CDS_PINID='SD4';
NODE_NAME     R3722 1
 '@S9S_MB_2U_LIB.S9S_MB_2U(SCH_1):PAGE221_I119@PURE_QUANTA.Q_RES(CHIPS)':
 'A': CDS_PINID='A';
NET_NAME
'SMB_LM75_3_3V3AUX_SDA_R1'
 '@S9S_MB_2U_LIB.S9S_MB_2U(SCH_1):SMB_LM75_3_3V3AUX_SDA_R1':
 C_SIGNAL='@s9s_mb_2u_lib.s9s_mb_2u(sch_1):smb_lm75_3_3v3aux_sda_r1';
NODE_NAME     R3554 2
 '@S9S_MB_2U_LIB.S9S_MB_2U(SCH_1):PAGE161_I136@PURE_QUANTA.Q_RES(CHIPS)':
 'B': CDS_PINID='B';
NODE_NAME     U273 1
 '@S9S_MB_2U_LIB.S9S_MB_2U(SCH_1):PAGE161_I167@PURE_QUANTA.LM75BD(CHIPS)':
 'SDA': CDS_PINID='SDA';
NET_NAME
'SMB_M2_P0_1V8AUX_SCL'
 '@S9S_MB_2U_LIB.S9S_MB_2U(SCH_1):SMB_M2_P0_1V8AUX_SCL':
 C_SIGNAL='@s9s_mb_2u_lib.s9s_mb_2u(sch_1):smb_m2_p0_1v8aux_scl';
NODE_NAME     J59 40
 '@S9S_MB_2U_LIB.S9S_MB_2U(SCH_1):PAGE182_I178@PURE_QUANTA.SCONN75K_APCI0155P004A(CHIPS)':
 'NC12': CDS_PINID='NC12';
NODE_NAME     R2411 2
 '@S9S_MB_2U_LIB.S9S_MB_2U(SCH_1):PAGE183_I66@PURE_QUANTA.Q_RES(CHIPS)':
 'B': CDS_PINID='B';
NET_NAME
'SMB_M2_P0_1V8AUX_SCL_R'
 '@S9S_MB_2U_LIB.S9S_MB_2U(SCH_1):SMB_M2_P0_1V8AUX_SCL_R':
 C_SIGNAL='@s9s_mb_2u_lib.s9s_mb_2u(sch_1):smb_m2_p0_1v8aux_scl_r';
NODE_NAME     U98 3
 '@S9S_MB_2U_LIB.S9S_MB_2U(SCH_1):PAGE183_I27@PURE_QUANTA.PCA9306DP1(CHIPS)':
 'SCL1': CDS_PINID='SCL1';
NODE_NAME     R1703 2
 '@S9S_MB_2U_LIB.S9S_MB_2U(SCH_1):PAGE183_I45@PURE_QUANTA.Q_RES(CHIPS)':
 'B': CDS_PINID='B';
NODE_NAME     R2411 1
 '@S9S_MB_2U_LIB.S9S_MB_2U(SCH_1):PAGE183_I66@PURE_QUANTA.Q_RES(CHIPS)':
 'A': CDS_PINID='A';
NET_NAME
'SMB_M2_P0_1V8AUX_SDA'
 '@S9S_MB_2U_LIB.S9S_MB_2U(SCH_1):SMB_M2_P0_1V8AUX_SDA':
 C_SIGNAL='@s9s_mb_2u_lib.s9s_mb_2u(sch_1):smb_m2_p0_1v8aux_sda';
NODE_NAME     J59 42
 '@S9S_MB_2U_LIB.S9S_MB_2U(SCH_1):PAGE182_I178@PURE_QUANTA.SCONN75K_APCI0155P004A(CHIPS)':
 'NC13': CDS_PINID='NC13';
NODE_NAME     R2410 2
 '@S9S_MB_2U_LIB.S9S_MB_2U(SCH_1):PAGE183_I65@PURE_QUANTA.Q_RES(CHIPS)':
 'B': CDS_PINID='B';
NET_NAME
'SMB_M2_P0_1V8AUX_SDA_R'
 '@S9S_MB_2U_LIB.S9S_MB_2U(SCH_1):SMB_M2_P0_1V8AUX_SDA_R':
 C_SIGNAL='@s9s_mb_2u_lib.s9s_mb_2u(sch_1):smb_m2_p0_1v8aux_sda_r';
NODE_NAME     U98 4
 '@S9S_MB_2U_LIB.S9S_MB_2U(SCH_1):PAGE183_I27@PURE_QUANTA.PCA9306DP1(CHIPS)':
 'SDA1': CDS_PINID='SDA1';
NODE_NAME     R1702 2
 '@S9S_MB_2U_LIB.S9S_MB_2U(SCH_1):PAGE183_I43@PURE_QUANTA.Q_RES(CHIPS)':
 'B': CDS_PINID='B';
NODE_NAME     R2410 1
 '@S9S_MB_2U_LIB.S9S_MB_2U(SCH_1):PAGE183_I65@PURE_QUANTA.Q_RES(CHIPS)':
 'A': CDS_PINID='A';
NET_NAME
'SMB_OCP_SFF_3V3AUX_BUF_R_SCL'
 '@S9S_MB_2U_LIB.S9S_MB_2U(SCH_1):SMB_OCP_SFF_3V3AUX_BUF_R_SCL':
 C_SIGNAL='@s9s_mb_2u_lib.s9s_mb_2u(sch_1):smb_ocp_sff_3v3aux_buf_r_scl';
NODE_NAME     R424 1
 '@S9S_MB_2U_LIB.S9S_MB_2U(SCH_1):PAGE150_I151@PURE_QUANTA.Q_RES(CHIPS)':
 'A': CDS_PINID='A';
NODE_NAME     J37 A7
 '@S9S_MB_2U_LIB.S9S_MB_2U(SCH_1):PAGE150_I199@PURE_QUANTA.SCONN168_ME1016810202011(CHIPS)':
 'SMCLK': CDS_PINID='SMCLK';
NET_NAME
'SMB_OCP_SFF_3V3AUX_BUF_R_SDA'
 '@S9S_MB_2U_LIB.S9S_MB_2U(SCH_1):SMB_OCP_SFF_3V3AUX_BUF_R_SDA':
 C_SIGNAL='@s9s_mb_2u_lib.s9s_mb_2u(sch_1):smb_ocp_sff_3v3aux_buf_r_sda';
NODE_NAME     J37 A8
 '@S9S_MB_2U_LIB.S9S_MB_2U(SCH_1):PAGE150_I199@PURE_QUANTA.SCONN168_ME1016810202011(CHIPS)':
 'SMDAT': CDS_PINID='SMDAT';
NODE_NAME     R425 1
 '@S9S_MB_2U_LIB.S9S_MB_2U(SCH_1):PAGE150_I220@PURE_QUANTA.Q_RES(CHIPS)':
 'A': CDS_PINID='A';
NET_NAME
'SMB_OCP_SFF_3V3AUX_BUF_SCL'
 '@S9S_MB_2U_LIB.S9S_MB_2U(SCH_1):SMB_OCP_SFF_3V3AUX_BUF_SCL':
 C_SIGNAL='@s9s_mb_2u_lib.s9s_mb_2u(sch_1):smb_ocp_sff_3v3aux_buf_scl';
NODE_NAME     R424 2
 '@S9S_MB_2U_LIB.S9S_MB_2U(SCH_1):PAGE150_I151@PURE_QUANTA.Q_RES(CHIPS)':
 'B': CDS_PINID='B';
NODE_NAME     U236 7
 '@S9S_MB_2U_LIB.S9S_MB_2U(SCH_1):PAGE216_I28@PURE_QUANTA.PCA9617ADP(CHIPS)':
 'SCLB': CDS_PINID='SCLB';
NODE_NAME     R3500 2
 '@S9S_MB_2U_LIB.S9S_MB_2U(SCH_1):PAGE216_I31@PURE_QUANTA.Q_RES(CHIPS)':
 'B': CDS_PINID='B';
NET_NAME
'SMB_OCP_SFF_3V3AUX_BUF_SDA'
 '@S9S_MB_2U_LIB.S9S_MB_2U(SCH_1):SMB_OCP_SFF_3V3AUX_BUF_SDA':
 C_SIGNAL='@s9s_mb_2u_lib.s9s_mb_2u(sch_1):smb_ocp_sff_3v3aux_buf_sda';
NODE_NAME     U236 6
 '@S9S_MB_2U_LIB.S9S_MB_2U(SCH_1):PAGE216_I28@PURE_QUANTA.PCA9617ADP(CHIPS)':
 'SDAB': CDS_PINID='SDAB';
NODE_NAME     R3501 2
 '@S9S_MB_2U_LIB.S9S_MB_2U(SCH_1):PAGE216_I30@PURE_QUANTA.Q_RES(CHIPS)':
 'B': CDS_PINID='B';
NODE_NAME     R425 2
 '@S9S_MB_2U_LIB.S9S_MB_2U(SCH_1):PAGE150_I220@PURE_QUANTA.Q_RES(CHIPS)':
 'B': CDS_PINID='B';
NET_NAME
'SMB_OCP_SFF_3V3AUX_SCL'
 '@S9S_MB_2U_LIB.S9S_MB_2U(SCH_1):SMB_OCP_SFF_3V3AUX_SCL':
 C_SIGNAL='@s9s_mb_2u_lib.s9s_mb_2u(sch_1):smb_ocp_sff_3v3aux_scl';
NODE_NAME     R3240 1
 '@S9S_MB_2U_LIB.S9S_MB_2U(SCH_1):PAGE228_I259@PURE_QUANTA.Q_RES(CHIPS)':
 'A': CDS_PINID='A';
NODE_NAME     U236 2
 '@S9S_MB_2U_LIB.S9S_MB_2U(SCH_1):PAGE216_I28@PURE_QUANTA.PCA9617ADP(CHIPS)':
 'SCLA': CDS_PINID='SCLA';
NODE_NAME     R3238 1
 '@S9S_MB_2U_LIB.S9S_MB_2U(SCH_1):PAGE227_I101@PURE_QUANTA.Q_RES(CHIPS)':
 'A': CDS_PINID='A';
NET_NAME
'SMB_OCP_SFF_3V3AUX_SCL_R0'
 '@S9S_MB_2U_LIB.S9S_MB_2U(SCH_1):SMB_OCP_SFF_3V3AUX_SCL_R0':
 C_SIGNAL='@s9s_mb_2u_lib.s9s_mb_2u(sch_1):smb_ocp_sff_3v3aux_scl_r0';
NODE_NAME     R3238 2
 '@S9S_MB_2U_LIB.S9S_MB_2U(SCH_1):PAGE227_I101@PURE_QUANTA.Q_RES(CHIPS)':
 'B': CDS_PINID='B';
NODE_NAME     J41 A1
 '@S9S_MB_2U_LIB.S9S_MB_2U(SCH_1):PAGE227_I173@PURE_QUANTA.SCONN168_ME1016810202011(CHIPS)':
 'GND_A1': CDS_PINID='GND_A1';
NET_NAME
'SMB_OCP_SFF_3V3AUX_SDA'
 '@S9S_MB_2U_LIB.S9S_MB_2U(SCH_1):SMB_OCP_SFF_3V3AUX_SDA':
 C_SIGNAL='@s9s_mb_2u_lib.s9s_mb_2u(sch_1):smb_ocp_sff_3v3aux_sda';
NODE_NAME     R3241 1
 '@S9S_MB_2U_LIB.S9S_MB_2U(SCH_1):PAGE228_I258@PURE_QUANTA.Q_RES(CHIPS)':
 'A': CDS_PINID='A';
NODE_NAME     U236 3
 '@S9S_MB_2U_LIB.S9S_MB_2U(SCH_1):PAGE216_I28@PURE_QUANTA.PCA9617ADP(CHIPS)':
 'SDAA': CDS_PINID='SDAA';
NODE_NAME     R3239 1
 '@S9S_MB_2U_LIB.S9S_MB_2U(SCH_1):PAGE227_I102@PURE_QUANTA.Q_RES(CHIPS)':
 'A': CDS_PINID='A';
NET_NAME
'SMB_OCP_SFF_3V3AUX_SDA_R0'
 '@S9S_MB_2U_LIB.S9S_MB_2U(SCH_1):SMB_OCP_SFF_3V3AUX_SDA_R0':
 C_SIGNAL='@s9s_mb_2u_lib.s9s_mb_2u(sch_1):smb_ocp_sff_3v3aux_sda_r0';
NODE_NAME     R3239 2
 '@S9S_MB_2U_LIB.S9S_MB_2U(SCH_1):PAGE227_I102@PURE_QUANTA.Q_RES(CHIPS)':
 'B': CDS_PINID='B';
NODE_NAME     J41 A2
 '@S9S_MB_2U_LIB.S9S_MB_2U(SCH_1):PAGE227_I173@PURE_QUANTA.SCONN168_ME1016810202011(CHIPS)':
 'GND_A2': CDS_PINID='GND_A2';
NET_NAME
'SMB_OCP_V3_2_3V3AUX_BUF_R_SCL'
 '@S9S_MB_2U_LIB.S9S_MB_2U(SCH_1):SMB_OCP_V3_2_3V3AUX_BUF_R_SCL':
 C_SIGNAL='@s9s_mb_2u_lib.s9s_mb_2u(sch_1):smb_ocp_v3_2_3v3aux_buf_r_scl';
NODE_NAME     J35 A7
 '@S9S_MB_2U_LIB.S9S_MB_2U(SCH_1):PAGE146_I303@PURE_QUANTA.SCONN168_ME1016810202011(CHIPS)':
 'SMCLK': CDS_PINID='SMCLK';
NODE_NAME     R3228 1
 '@S9S_MB_2U_LIB.S9S_MB_2U(SCH_1):PAGE146_I339@PURE_QUANTA.Q_RES(CHIPS)':
 'A': CDS_PINID='A';
NET_NAME
'SMB_OCP_V3_2_3V3AUX_BUF_R_SDA'
 '@S9S_MB_2U_LIB.S9S_MB_2U(SCH_1):SMB_OCP_V3_2_3V3AUX_BUF_R_SDA':
 C_SIGNAL='@s9s_mb_2u_lib.s9s_mb_2u(sch_1):smb_ocp_v3_2_3v3aux_buf_r_sda';
NODE_NAME     J35 A8
 '@S9S_MB_2U_LIB.S9S_MB_2U(SCH_1):PAGE146_I303@PURE_QUANTA.SCONN168_ME1016810202011(CHIPS)':
 'SMDAT': CDS_PINID='SMDAT';
NODE_NAME     R3229 1
 '@S9S_MB_2U_LIB.S9S_MB_2U(SCH_1):PAGE146_I338@PURE_QUANTA.Q_RES(CHIPS)':
 'A': CDS_PINID='A';
NET_NAME
'SMB_OCP_V3_2_3V3AUX_BUF_SCL'
 '@S9S_MB_2U_LIB.S9S_MB_2U(SCH_1):SMB_OCP_V3_2_3V3AUX_BUF_SCL':
 C_SIGNAL='@s9s_mb_2u_lib.s9s_mb_2u(sch_1):smb_ocp_v3_2_3v3aux_buf_scl';
NODE_NAME     U235 7
 '@S9S_MB_2U_LIB.S9S_MB_2U(SCH_1):PAGE216_I5@PURE_QUANTA.PCA9617ADP(CHIPS)':
 'SCLB': CDS_PINID='SCLB';
NODE_NAME     R3519 2
 '@S9S_MB_2U_LIB.S9S_MB_2U(SCH_1):PAGE216_I34@PURE_QUANTA.Q_RES(CHIPS)':
 'B': CDS_PINID='B';
NODE_NAME     R3228 2
 '@S9S_MB_2U_LIB.S9S_MB_2U(SCH_1):PAGE146_I339@PURE_QUANTA.Q_RES(CHIPS)':
 'B': CDS_PINID='B';
NET_NAME
'SMB_OCP_V3_2_3V3AUX_BUF_SDA'
 '@S9S_MB_2U_LIB.S9S_MB_2U(SCH_1):SMB_OCP_V3_2_3V3AUX_BUF_SDA':
 C_SIGNAL='@s9s_mb_2u_lib.s9s_mb_2u(sch_1):smb_ocp_v3_2_3v3aux_buf_sda';
NODE_NAME     U235 6
 '@S9S_MB_2U_LIB.S9S_MB_2U(SCH_1):PAGE216_I5@PURE_QUANTA.PCA9617ADP(CHIPS)':
 'SDAB': CDS_PINID='SDAB';
NODE_NAME     R3520 2
 '@S9S_MB_2U_LIB.S9S_MB_2U(SCH_1):PAGE216_I33@PURE_QUANTA.Q_RES(CHIPS)':
 'B': CDS_PINID='B';
NODE_NAME     R3229 2
 '@S9S_MB_2U_LIB.S9S_MB_2U(SCH_1):PAGE146_I338@PURE_QUANTA.Q_RES(CHIPS)':
 'B': CDS_PINID='B';
NET_NAME
'SMB_OCP_V3_2_3V3AUX_SCL'
 '@S9S_MB_2U_LIB.S9S_MB_2U(SCH_1):SMB_OCP_V3_2_3V3AUX_SCL':
 C_SIGNAL='@s9s_mb_2u_lib.s9s_mb_2u(sch_1):smb_ocp_v3_2_3v3aux_scl';
NODE_NAME     R3242 1
 '@S9S_MB_2U_LIB.S9S_MB_2U(SCH_1):PAGE228_I260@PURE_QUANTA.Q_RES(CHIPS)':
 'A': CDS_PINID='A';
NODE_NAME     U235 2
 '@S9S_MB_2U_LIB.S9S_MB_2U(SCH_1):PAGE216_I5@PURE_QUANTA.PCA9617ADP(CHIPS)':
 'SCLA': CDS_PINID='SCLA';
NODE_NAME     R2425 1
 '@S9S_MB_2U_LIB.S9S_MB_2U(SCH_1):PAGE227_I93@PURE_QUANTA.Q_RES(CHIPS)':
 'A': CDS_PINID='A';
NET_NAME
'SMB_OCP_V3_2_3V3AUX_SCL_R0'
 '@S9S_MB_2U_LIB.S9S_MB_2U(SCH_1):SMB_OCP_V3_2_3V3AUX_SCL_R0':
 C_SIGNAL='@s9s_mb_2u_lib.s9s_mb_2u(sch_1):smb_ocp_v3_2_3v3aux_scl_r0';
NODE_NAME     R2425 2
 '@S9S_MB_2U_LIB.S9S_MB_2U(SCH_1):PAGE227_I93@PURE_QUANTA.Q_RES(CHIPS)':
 'B': CDS_PINID='B';
NODE_NAME     J41 A11
 '@S9S_MB_2U_LIB.S9S_MB_2U(SCH_1):PAGE227_I173@PURE_QUANTA.SCONN168_ME1016810202011(CHIPS)':
 'PERST1#': CDS_PINID='\perst1#\';
NET_NAME
'SMB_OCP_V3_2_3V3AUX_SDA'
 '@S9S_MB_2U_LIB.S9S_MB_2U(SCH_1):SMB_OCP_V3_2_3V3AUX_SDA':
 C_SIGNAL='@s9s_mb_2u_lib.s9s_mb_2u(sch_1):smb_ocp_v3_2_3v3aux_sda';
NODE_NAME     R3243 1
 '@S9S_MB_2U_LIB.S9S_MB_2U(SCH_1):PAGE228_I261@PURE_QUANTA.Q_RES(CHIPS)':
 'A': CDS_PINID='A';
NODE_NAME     U235 3
 '@S9S_MB_2U_LIB.S9S_MB_2U(SCH_1):PAGE216_I5@PURE_QUANTA.PCA9617ADP(CHIPS)':
 'SDAA': CDS_PINID='SDAA';
NODE_NAME     R3858 1
 '@S9S_MB_2U_LIB.S9S_MB_2U(SCH_1):PAGE227_I94@PURE_QUANTA.Q_RES(CHIPS)':
 'A': CDS_PINID='A';
NET_NAME
'SMB_OCP_V3_2_3V3AUX_SDA_R0'
 '@S9S_MB_2U_LIB.S9S_MB_2U(SCH_1):SMB_OCP_V3_2_3V3AUX_SDA_R0':
 C_SIGNAL='@s9s_mb_2u_lib.s9s_mb_2u(sch_1):smb_ocp_v3_2_3v3aux_sda_r0';
NODE_NAME     R3858 2
 '@S9S_MB_2U_LIB.S9S_MB_2U(SCH_1):PAGE227_I94@PURE_QUANTA.Q_RES(CHIPS)':
 'B': CDS_PINID='B';
NODE_NAME     J41 A12
 '@S9S_MB_2U_LIB.S9S_MB_2U(SCH_1):PAGE227_I173@PURE_QUANTA.SCONN168_ME1016810202011(CHIPS)':
 'PRSNTB2#': CDS_PINID='\prsntb2#\';
NET_NAME
'SMB_PCIE0_3V3AUX_SCL'
 '@S9S_MB_2U_LIB.S9S_MB_2U(SCH_1):SMB_PCIE0_3V3AUX_SCL':
 C_SIGNAL='@s9s_mb_2u_lib.s9s_mb_2u(sch_1):smb_pcie0_3v3aux_scl';
NODE_NAME     R2204 2
 '@S9S_MB_2U_LIB.S9S_MB_2U(SCH_1):PAGE219_I57@PURE_QUANTA.Q_RES(CHIPS)':
 'B': CDS_PINID='B';
NODE_NAME     R588 1
 '@S9S_MB_2U_LIB.S9S_MB_2U(SCH_1):PAGE219_I65@PURE_QUANTA.Q_RES(CHIPS)':
 'A': CDS_PINID='A';
NODE_NAME     J41 A23
 '@S9S_MB_2U_LIB.S9S_MB_2U(SCH_1):PAGE227_I173@PURE_QUANTA.SCONN168_ME1016810202011(CHIPS)':
 'PERN2': CDS_PINID='PERN2';
NET_NAME
'SMB_PCIE0_3V3AUX_SCL_R'
 '@S9S_MB_2U_LIB.S9S_MB_2U(SCH_1):SMB_PCIE0_3V3AUX_SCL_R':
 C_SIGNAL='@s9s_mb_2u_lib.s9s_mb_2u(sch_1):smb_pcie0_3v3aux_scl_r';
NODE_NAME     U36 22
 '@S9S_MB_2U_LIB.S9S_MB_2U(SCH_1):PAGE219_I45@PURE_QUANTA.TCA9548APWR(CHIPS)':
 'SCL': CDS_PINID='SCL';
NODE_NAME     R588 2
 '@S9S_MB_2U_LIB.S9S_MB_2U(SCH_1):PAGE219_I65@PURE_QUANTA.Q_RES(CHIPS)':
 'B': CDS_PINID='B';
NET_NAME
'SMB_PCIE0_3V3AUX_SCL_R3'
 '@S9S_MB_2U_LIB.S9S_MB_2U(SCH_1):SMB_PCIE0_3V3AUX_SCL_R3':
 C_SIGNAL='@s9s_mb_2u_lib.s9s_mb_2u(sch_1):smb_pcie0_3v3aux_scl_r3';
NODE_NAME     R2967 1
 '@S9S_MB_2U_LIB.S9S_MB_2U(SCH_1):PAGE219_I36@PURE_QUANTA.Q_RES(CHIPS)':
 'A': CDS_PINID='A';
NODE_NAME     U36 9
 '@S9S_MB_2U_LIB.S9S_MB_2U(SCH_1):PAGE219_I45@PURE_QUANTA.TCA9548APWR(CHIPS)':
 'SC2': CDS_PINID='SC2';
NET_NAME
'SMB_PCIE0_3V3AUX_SCL_R5'
 '@S9S_MB_2U_LIB.S9S_MB_2U(SCH_1):SMB_PCIE0_3V3AUX_SCL_R5':
 C_SIGNAL='@s9s_mb_2u_lib.s9s_mb_2u(sch_1):smb_pcie0_3v3aux_scl_r5';
NODE_NAME     R3526 1
 '@S9S_MB_2U_LIB.S9S_MB_2U(SCH_1):PAGE219_I35@PURE_QUANTA.Q_RES(CHIPS)':
 'A': CDS_PINID='A';
NODE_NAME     U36 11
 '@S9S_MB_2U_LIB.S9S_MB_2U(SCH_1):PAGE219_I45@PURE_QUANTA.TCA9548APWR(CHIPS)':
 'SC3': CDS_PINID='SC3';
NET_NAME
'SMB_PCIE0_3V3AUX_SDA'
 '@S9S_MB_2U_LIB.S9S_MB_2U(SCH_1):SMB_PCIE0_3V3AUX_SDA':
 C_SIGNAL='@s9s_mb_2u_lib.s9s_mb_2u(sch_1):smb_pcie0_3v3aux_sda';
NODE_NAME     R2205 2
 '@S9S_MB_2U_LIB.S9S_MB_2U(SCH_1):PAGE219_I56@PURE_QUANTA.Q_RES(CHIPS)':
 'B': CDS_PINID='B';
NODE_NAME     R589 1
 '@S9S_MB_2U_LIB.S9S_MB_2U(SCH_1):PAGE219_I66@PURE_QUANTA.Q_RES(CHIPS)':
 'A': CDS_PINID='A';
NODE_NAME     J41 A24
 '@S9S_MB_2U_LIB.S9S_MB_2U(SCH_1):PAGE227_I173@PURE_QUANTA.SCONN168_ME1016810202011(CHIPS)':
 'PERP2': CDS_PINID='PERP2';
NET_NAME
'SMB_PCIE0_3V3AUX_SDA_R'
 '@S9S_MB_2U_LIB.S9S_MB_2U(SCH_1):SMB_PCIE0_3V3AUX_SDA_R':
 C_SIGNAL='@s9s_mb_2u_lib.s9s_mb_2u(sch_1):smb_pcie0_3v3aux_sda_r';
NODE_NAME     U36 23
 '@S9S_MB_2U_LIB.S9S_MB_2U(SCH_1):PAGE219_I45@PURE_QUANTA.TCA9548APWR(CHIPS)':
 'SDA': CDS_PINID='SDA';
NODE_NAME     R589 2
 '@S9S_MB_2U_LIB.S9S_MB_2U(SCH_1):PAGE219_I66@PURE_QUANTA.Q_RES(CHIPS)':
 'B': CDS_PINID='B';
NET_NAME
'SMB_PCIE0_3V3AUX_SDA_R3'
 '@S9S_MB_2U_LIB.S9S_MB_2U(SCH_1):SMB_PCIE0_3V3AUX_SDA_R3':
 C_SIGNAL='@s9s_mb_2u_lib.s9s_mb_2u(sch_1):smb_pcie0_3v3aux_sda_r3';
NODE_NAME     R2968 1
 '@S9S_MB_2U_LIB.S9S_MB_2U(SCH_1):PAGE219_I39@PURE_QUANTA.Q_RES(CHIPS)':
 'A': CDS_PINID='A';
NODE_NAME     U36 8
 '@S9S_MB_2U_LIB.S9S_MB_2U(SCH_1):PAGE219_I45@PURE_QUANTA.TCA9548APWR(CHIPS)':
 'SD2': CDS_PINID='SD2';
NET_NAME
'SMB_PCIE0_3V3AUX_SDA_R5'
 '@S9S_MB_2U_LIB.S9S_MB_2U(SCH_1):SMB_PCIE0_3V3AUX_SDA_R5':
 C_SIGNAL='@s9s_mb_2u_lib.s9s_mb_2u(sch_1):smb_pcie0_3v3aux_sda_r5';
NODE_NAME     R3527 1
 '@S9S_MB_2U_LIB.S9S_MB_2U(SCH_1):PAGE219_I37@PURE_QUANTA.Q_RES(CHIPS)':
 'A': CDS_PINID='A';
NODE_NAME     U36 10
 '@S9S_MB_2U_LIB.S9S_MB_2U(SCH_1):PAGE219_I45@PURE_QUANTA.TCA9548APWR(CHIPS)':
 'SD3': CDS_PINID='SD3';
NET_NAME
'SMB_PCIE2_3V3AUX_SCL_R0'
 '@S9S_MB_2U_LIB.S9S_MB_2U(SCH_1):SMB_PCIE2_3V3AUX_SCL_R0':
 C_SIGNAL='@s9s_mb_2u_lib.s9s_mb_2u(sch_1):smb_pcie2_3v3aux_scl_r0';
NODE_NAME     R2413 2
 '@S9S_MB_2U_LIB.S9S_MB_2U(SCH_1):PAGE227_I86@PURE_QUANTA.Q_RES(CHIPS)':
 'B': CDS_PINID='B';
NODE_NAME     J41 A31
 '@S9S_MB_2U_LIB.S9S_MB_2U(SCH_1):PAGE227_I173@PURE_QUANTA.SCONN168_ME1016810202011(CHIPS)':
 'PERP4': CDS_PINID='PERP4';
NET_NAME
'SMB_PCIE2_3V3AUX_SDA_R0'
 '@S9S_MB_2U_LIB.S9S_MB_2U(SCH_1):SMB_PCIE2_3V3AUX_SDA_R0':
 C_SIGNAL='@s9s_mb_2u_lib.s9s_mb_2u(sch_1):smb_pcie2_3v3aux_sda_r0';
NODE_NAME     R2414 2
 '@S9S_MB_2U_LIB.S9S_MB_2U(SCH_1):PAGE227_I85@PURE_QUANTA.Q_RES(CHIPS)':
 'B': CDS_PINID='B';
NODE_NAME     J41 A32
 '@S9S_MB_2U_LIB.S9S_MB_2U(SCH_1):PAGE227_I173@PURE_QUANTA.SCONN168_ME1016810202011(CHIPS)':
 'GND_A32': CDS_PINID='GND_A32';
NET_NAME
'SMB_PCIE3_3V3AUX_SCL_R'
 '@S9S_MB_2U_LIB.S9S_MB_2U(SCH_1):SMB_PCIE3_3V3AUX_SCL_R':
 C_SIGNAL='@s9s_mb_2u_lib.s9s_mb_2u(sch_1):smb_pcie3_3v3aux_scl_r';
NODE_NAME     R2415 2
 '@S9S_MB_2U_LIB.S9S_MB_2U(SCH_1):PAGE227_I25@PURE_QUANTA.Q_RES(CHIPS)':
 'B': CDS_PINID='B';
NODE_NAME     J41 A38
 '@S9S_MB_2U_LIB.S9S_MB_2U(SCH_1):PAGE227_I173@PURE_QUANTA.SCONN168_ME1016810202011(CHIPS)':
 'GND_A38': CDS_PINID='GND_A38';
NET_NAME
'SMB_PCIE3_3V3AUX_SDA_R'
 '@S9S_MB_2U_LIB.S9S_MB_2U(SCH_1):SMB_PCIE3_3V3AUX_SDA_R':
 C_SIGNAL='@s9s_mb_2u_lib.s9s_mb_2u(sch_1):smb_pcie3_3v3aux_sda_r';
NODE_NAME     R2416 2
 '@S9S_MB_2U_LIB.S9S_MB_2U(SCH_1):PAGE227_I24@PURE_QUANTA.Q_RES(CHIPS)':
 'B': CDS_PINID='B';
NODE_NAME     J41 A39
 '@S9S_MB_2U_LIB.S9S_MB_2U(SCH_1):PAGE227_I173@PURE_QUANTA.SCONN168_ME1016810202011(CHIPS)':
 'PERN7': CDS_PINID='PERN7';
NET_NAME
'SMB_PCIE_E1S_ISO_EN'
 '@S9S_MB_2U_LIB.S9S_MB_2U(SCH_1):SMB_PCIE_E1S_ISO_EN':
 C_SIGNAL='@s9s_mb_2u_lib.s9s_mb_2u(sch_1):smb_pcie_e1s_iso_en';
NODE_NAME     R3531 1
 '@S9S_MB_2U_LIB.S9S_MB_2U(SCH_1):PAGE183_I96@PURE_QUANTA.Q_RES(CHIPS)':
 'A': CDS_PINID='A';
NODE_NAME     R2125 2
 '@S9S_MB_2U_LIB.S9S_MB_2U(SCH_1):PAGE297_I296@PURE_QUANTA.Q_RES(CHIPS)':
 'B': CDS_PINID='B';
NODE_NAME     R2114 2
 '@S9S_MB_2U_LIB.S9S_MB_2U(SCH_1):PAGE297_I302@PURE_QUANTA.Q_RES(CHIPS)':
 'B': CDS_PINID='B';
NET_NAME
'SMB_PCIE_E1S_ISO_EN_R'
 '@S9S_MB_2U_LIB.S9S_MB_2U(SCH_1):SMB_PCIE_E1S_ISO_EN_R':
 C_SIGNAL='@s9s_mb_2u_lib.s9s_mb_2u(sch_1):smb_pcie_e1s_iso_en_r';
NODE_NAME     U279 5
 '@S9S_MB_2U_LIB.S9S_MB_2U(SCH_1):PAGE183_I93@PURE_QUANTA.PCA9617ADP(CHIPS)':
 'EN': CDS_PINID='EN';
NODE_NAME     R3531 2
 '@S9S_MB_2U_LIB.S9S_MB_2U(SCH_1):PAGE183_I96@PURE_QUANTA.Q_RES(CHIPS)':
 'B': CDS_PINID='B';
NODE_NAME     R3529 2
 '@S9S_MB_2U_LIB.S9S_MB_2U(SCH_1):PAGE183_I99@PURE_QUANTA.Q_RES(CHIPS)':
 'B': CDS_PINID='B';
NET_NAME
'SMB_PCIE_E1S_ISO_EN_R2'
 '@S9S_MB_2U_LIB.S9S_MB_2U(SCH_1):SMB_PCIE_E1S_ISO_EN_R2':
 C_SIGNAL='@s9s_mb_2u_lib.s9s_mb_2u(sch_1):smb_pcie_e1s_iso_en_r2';
NODE_NAME     R2114 1
 '@S9S_MB_2U_LIB.S9S_MB_2U(SCH_1):PAGE297_I302@PURE_QUANTA.Q_RES(CHIPS)':
 'A': CDS_PINID='A';
NODE_NAME     U134 4
 '@S9S_MB_2U_LIB.S9S_MB_2U(SCH_1):PAGE297_I305@PURE_QUANTA.74LVC2G07DW7(CHIPS)':
 '2Y': CDS_PINID='\2y\';
NET_NAME
'SMB_PCIE_M2_0_EN'
 '@S9S_MB_2U_LIB.S9S_MB_2U(SCH_1):SMB_PCIE_M2_0_EN':
 C_SIGNAL='@s9s_mb_2u_lib.s9s_mb_2u(sch_1):smb_pcie_m2_0_en';
NODE_NAME     U98 8
 '@S9S_MB_2U_LIB.S9S_MB_2U(SCH_1):PAGE183_I27@PURE_QUANTA.PCA9306DP1(CHIPS)':
 'EN': CDS_PINID='EN';
NODE_NAME     U98 7
 '@S9S_MB_2U_LIB.S9S_MB_2U(SCH_1):PAGE183_I27@PURE_QUANTA.PCA9306DP1(CHIPS)':
 'VREF2': CDS_PINID='VREF2';
NODE_NAME     R2476 1
 '@S9S_MB_2U_LIB.S9S_MB_2U(SCH_1):PAGE183_I70@PURE_QUANTA.Q_RES(CHIPS)':
 'A': CDS_PINID='A';
NODE_NAME     R1700 2
 '@S9S_MB_2U_LIB.S9S_MB_2U(SCH_1):PAGE183_I72@PURE_QUANTA.Q_RES(CHIPS)':
 'B': CDS_PINID='B';
NET_NAME
'SMB_PEHPCPU0_GTL_R_SCL'
 '@S9S_MB_2U_LIB.S9S_MB_2U(SCH_1):SMB_PEHPCPU0_GTL_R_SCL':
 C_SIGNAL='@s9s_mb_2u_lib.s9s_mb_2u(sch_1):smb_pehpcpu0_gtl_r_scl';
NODE_NAME     R910 2
 '@S9S_MB_2U_LIB.S9S_MB_2U(SCH_1):PAGE223_I24@PURE_QUANTA.Q_RES(CHIPS)':
 'B': CDS_PINID='B';
NODE_NAME     U28 2
 '@S9S_MB_2U_LIB.S9S_MB_2U(SCH_1):PAGE223_I39@PURE_QUANTA.PCA9617ADP(CHIPS)':
 'SCLA': CDS_PINID='SCLA';
NODE_NAME     R960 2
 '@S9S_MB_2U_LIB.S9S_MB_2U(SCH_1):PAGE223_I101@PURE_QUANTA.Q_RES(CHIPS)':
 'B': CDS_PINID='B';
NET_NAME
'SMB_PEHPCPU0_GTL_R_SDA'
 '@S9S_MB_2U_LIB.S9S_MB_2U(SCH_1):SMB_PEHPCPU0_GTL_R_SDA':
 C_SIGNAL='@s9s_mb_2u_lib.s9s_mb_2u(sch_1):smb_pehpcpu0_gtl_r_sda';
NODE_NAME     R911 2
 '@S9S_MB_2U_LIB.S9S_MB_2U(SCH_1):PAGE223_I22@PURE_QUANTA.Q_RES(CHIPS)':
 'B': CDS_PINID='B';
NODE_NAME     U28 3
 '@S9S_MB_2U_LIB.S9S_MB_2U(SCH_1):PAGE223_I39@PURE_QUANTA.PCA9617ADP(CHIPS)':
 'SDAA': CDS_PINID='SDAA';
NODE_NAME     R909 2
 '@S9S_MB_2U_LIB.S9S_MB_2U(SCH_1):PAGE223_I102@PURE_QUANTA.Q_RES(CHIPS)':
 'B': CDS_PINID='B';
NET_NAME
'SMB_PEHPCPU0_GTL_SCL'
 '@S9S_MB_2U_LIB.S9S_MB_2U(SCH_1):SMB_PEHPCPU0_GTL_SCL':
 C_SIGNAL='@s9s_mb_2u_lib.s9s_mb_2u(sch_1):smb_pehpcpu0_gtl_scl';
NODE_NAME     U2 CA25
 '@S9S_MB_2U_LIB.S9S_MB_2U(SCH_1):PAGE14_I1@PURE_QUANTA.SOCKET4677_AZIF0045P001C01CS(CHIPS)':
 'CXPSMBUSSCL': CDS_PINID='CXPSMBUSSCL';
NODE_NAME     R960 1
 '@S9S_MB_2U_LIB.S9S_MB_2U(SCH_1):PAGE223_I101@PURE_QUANTA.Q_RES(CHIPS)':
 'A': CDS_PINID='A';
NET_NAME
'SMB_PEHPCPU0_GTL_SDA'
 '@S9S_MB_2U_LIB.S9S_MB_2U(SCH_1):SMB_PEHPCPU0_GTL_SDA':
 C_SIGNAL='@s9s_mb_2u_lib.s9s_mb_2u(sch_1):smb_pehpcpu0_gtl_sda';
NODE_NAME     U2 BY26
 '@S9S_MB_2U_LIB.S9S_MB_2U(SCH_1):PAGE14_I1@PURE_QUANTA.SOCKET4677_AZIF0045P001C01CS(CHIPS)':
 'CXPSMBUSSDA': CDS_PINID='CXPSMBUSSDA';
NODE_NAME     R909 1
 '@S9S_MB_2U_LIB.S9S_MB_2U(SCH_1):PAGE223_I102@PURE_QUANTA.Q_RES(CHIPS)':
 'A': CDS_PINID='A';
NET_NAME
'SMB_PEHPCPU0_LVC3_R_SCL'
 '@S9S_MB_2U_LIB.S9S_MB_2U(SCH_1):SMB_PEHPCPU0_LVC3_R_SCL':
 C_SIGNAL='@s9s_mb_2u_lib.s9s_mb_2u(sch_1):smb_pehpcpu0_lvc3_r_scl';
NODE_NAME     R1130 2
 '@S9S_MB_2U_LIB.S9S_MB_2U(SCH_1):PAGE154_I130@PURE_QUANTA.Q_RES(CHIPS)':
 'B': CDS_PINID='B';
NODE_NAME     U209 22
 '@S9S_MB_2U_LIB.S9S_MB_2U(SCH_1):PAGE154_I206@PURE_QUANTA.PCA9555APW(CHIPS)':
 'SCL': CDS_PINID='SCL';
NET_NAME
'SMB_PEHPCPU0_LVC3_R_SDA'
 '@S9S_MB_2U_LIB.S9S_MB_2U(SCH_1):SMB_PEHPCPU0_LVC3_R_SDA':
 C_SIGNAL='@s9s_mb_2u_lib.s9s_mb_2u(sch_1):smb_pehpcpu0_lvc3_r_sda';
NODE_NAME     R1131 2
 '@S9S_MB_2U_LIB.S9S_MB_2U(SCH_1):PAGE154_I131@PURE_QUANTA.Q_RES(CHIPS)':
 'B': CDS_PINID='B';
NODE_NAME     U209 23
 '@S9S_MB_2U_LIB.S9S_MB_2U(SCH_1):PAGE154_I206@PURE_QUANTA.PCA9555APW(CHIPS)':
 'SDA': CDS_PINID='SDA';
NET_NAME
'SMB_PEHPCPU0_LVC3_SCL'
 '@S9S_MB_2U_LIB.S9S_MB_2U(SCH_1):SMB_PEHPCPU0_LVC3_SCL':
 C_SIGNAL='@s9s_mb_2u_lib.s9s_mb_2u(sch_1):smb_pehpcpu0_lvc3_scl';
NODE_NAME     R1130 1
 '@S9S_MB_2U_LIB.S9S_MB_2U(SCH_1):PAGE154_I130@PURE_QUANTA.Q_RES(CHIPS)':
 'A': CDS_PINID='A';
NODE_NAME     R2477 2
 '@S9S_MB_2U_LIB.S9S_MB_2U(SCH_1):PAGE223_I88@PURE_QUANTA.Q_RES(CHIPS)':
 'B': CDS_PINID='B';
NODE_NAME     R965 2
 '@S9S_MB_2U_LIB.S9S_MB_2U(SCH_1):PAGE223_I93@PURE_QUANTA.Q_RES(CHIPS)':
 'B': CDS_PINID='B';
NET_NAME
'SMB_PEHPCPU0_LVC3_SCL_R0'
 '@S9S_MB_2U_LIB.S9S_MB_2U(SCH_1):SMB_PEHPCPU0_LVC3_SCL_R0':
 C_SIGNAL='@s9s_mb_2u_lib.s9s_mb_2u(sch_1):smb_pehpcpu0_lvc3_scl_r0';
NODE_NAME     U28 7
 '@S9S_MB_2U_LIB.S9S_MB_2U(SCH_1):PAGE223_I39@PURE_QUANTA.PCA9617ADP(CHIPS)':
 'SCLB': CDS_PINID='SCLB';
NODE_NAME     R2477 1
 '@S9S_MB_2U_LIB.S9S_MB_2U(SCH_1):PAGE223_I88@PURE_QUANTA.Q_RES(CHIPS)':
 'A': CDS_PINID='A';
NET_NAME
'SMB_PEHPCPU0_LVC3_SDA'
 '@S9S_MB_2U_LIB.S9S_MB_2U(SCH_1):SMB_PEHPCPU0_LVC3_SDA':
 C_SIGNAL='@s9s_mb_2u_lib.s9s_mb_2u(sch_1):smb_pehpcpu0_lvc3_sda';
NODE_NAME     R1131 1
 '@S9S_MB_2U_LIB.S9S_MB_2U(SCH_1):PAGE154_I131@PURE_QUANTA.Q_RES(CHIPS)':
 'A': CDS_PINID='A';
NODE_NAME     R2478 2
 '@S9S_MB_2U_LIB.S9S_MB_2U(SCH_1):PAGE223_I89@PURE_QUANTA.Q_RES(CHIPS)':
 'B': CDS_PINID='B';
NODE_NAME     R967 2
 '@S9S_MB_2U_LIB.S9S_MB_2U(SCH_1):PAGE223_I94@PURE_QUANTA.Q_RES(CHIPS)':
 'B': CDS_PINID='B';
NET_NAME
'SMB_PEHPCPU0_LVC3_SDA_R0'
 '@S9S_MB_2U_LIB.S9S_MB_2U(SCH_1):SMB_PEHPCPU0_LVC3_SDA_R0':
 C_SIGNAL='@s9s_mb_2u_lib.s9s_mb_2u(sch_1):smb_pehpcpu0_lvc3_sda_r0';
NODE_NAME     U28 6
 '@S9S_MB_2U_LIB.S9S_MB_2U(SCH_1):PAGE223_I39@PURE_QUANTA.PCA9617ADP(CHIPS)':
 'SDAB': CDS_PINID='SDAB';
NODE_NAME     R2478 1
 '@S9S_MB_2U_LIB.S9S_MB_2U(SCH_1):PAGE223_I89@PURE_QUANTA.Q_RES(CHIPS)':
 'A': CDS_PINID='A';
NET_NAME
'SMB_PEHPCPU1_GTL_R_SCL'
 '@S9S_MB_2U_LIB.S9S_MB_2U(SCH_1):SMB_PEHPCPU1_GTL_R_SCL':
 C_SIGNAL='@s9s_mb_2u_lib.s9s_mb_2u(sch_1):smb_pehpcpu1_gtl_r_scl';
NODE_NAME     U29 2
 '@S9S_MB_2U_LIB.S9S_MB_2U(SCH_1):PAGE223_I43@PURE_QUANTA.PCA9617ADP(CHIPS)':
 'SCLA': CDS_PINID='SCLA';
NODE_NAME     R963 2
 '@S9S_MB_2U_LIB.S9S_MB_2U(SCH_1):PAGE223_I48@PURE_QUANTA.Q_RES(CHIPS)':
 'B': CDS_PINID='B';
NODE_NAME     R961 2
 '@S9S_MB_2U_LIB.S9S_MB_2U(SCH_1):PAGE223_I99@PURE_QUANTA.Q_RES(CHIPS)':
 'B': CDS_PINID='B';
NET_NAME
'SMB_PEHPCPU1_GTL_R_SDA'
 '@S9S_MB_2U_LIB.S9S_MB_2U(SCH_1):SMB_PEHPCPU1_GTL_R_SDA':
 C_SIGNAL='@s9s_mb_2u_lib.s9s_mb_2u(sch_1):smb_pehpcpu1_gtl_r_sda';
NODE_NAME     U29 3
 '@S9S_MB_2U_LIB.S9S_MB_2U(SCH_1):PAGE223_I43@PURE_QUANTA.PCA9617ADP(CHIPS)':
 'SDAA': CDS_PINID='SDAA';
NODE_NAME     R964 2
 '@S9S_MB_2U_LIB.S9S_MB_2U(SCH_1):PAGE223_I46@PURE_QUANTA.Q_RES(CHIPS)':
 'B': CDS_PINID='B';
NODE_NAME     R962 2
 '@S9S_MB_2U_LIB.S9S_MB_2U(SCH_1):PAGE223_I100@PURE_QUANTA.Q_RES(CHIPS)':
 'B': CDS_PINID='B';
NET_NAME
'SMB_PEHPCPU1_GTL_SCL'
 '@S9S_MB_2U_LIB.S9S_MB_2U(SCH_1):SMB_PEHPCPU1_GTL_SCL':
 C_SIGNAL='@s9s_mb_2u_lib.s9s_mb_2u(sch_1):smb_pehpcpu1_gtl_scl';
NODE_NAME     U1 CA25
 '@S9S_MB_2U_LIB.S9S_MB_2U(SCH_1):PAGE45_I29@PURE_QUANTA.SOCKET4677_AZIF0045P001C01CS(CHIPS)':
 'CXPSMBUSSCL': CDS_PINID='CXPSMBUSSCL';
NODE_NAME     R961 1
 '@S9S_MB_2U_LIB.S9S_MB_2U(SCH_1):PAGE223_I99@PURE_QUANTA.Q_RES(CHIPS)':
 'A': CDS_PINID='A';
NET_NAME
'SMB_PEHPCPU1_GTL_SDA'
 '@S9S_MB_2U_LIB.S9S_MB_2U(SCH_1):SMB_PEHPCPU1_GTL_SDA':
 C_SIGNAL='@s9s_mb_2u_lib.s9s_mb_2u(sch_1):smb_pehpcpu1_gtl_sda';
NODE_NAME     U1 BY26
 '@S9S_MB_2U_LIB.S9S_MB_2U(SCH_1):PAGE45_I29@PURE_QUANTA.SOCKET4677_AZIF0045P001C01CS(CHIPS)':
 'CXPSMBUSSDA': CDS_PINID='CXPSMBUSSDA';
NODE_NAME     R962 1
 '@S9S_MB_2U_LIB.S9S_MB_2U(SCH_1):PAGE223_I100@PURE_QUANTA.Q_RES(CHIPS)':
 'A': CDS_PINID='A';
NET_NAME
'SMB_PEHPCPU1_LVC3_R3_SCL'
 '@S9S_MB_2U_LIB.S9S_MB_2U(SCH_1):SMB_PEHPCPU1_LVC3_R3_SCL':
 C_SIGNAL='@s9s_mb_2u_lib.s9s_mb_2u(sch_1):smb_pehpcpu1_lvc3_r3_scl';
NODE_NAME     R3156 2
 '@S9S_MB_2U_LIB.S9S_MB_2U(SCH_1):PAGE132_I34@PURE_QUANTA.Q_RES(CHIPS)':
 'B': CDS_PINID='B';
NODE_NAME     U51 22
 '@S9S_MB_2U_LIB.S9S_MB_2U(SCH_1):PAGE132_I66@PURE_QUANTA.PCA9555APW(CHIPS)':
 'SCL': CDS_PINID='SCL';
NET_NAME
'SMB_PEHPCPU1_LVC3_R3_SDA'
 '@S9S_MB_2U_LIB.S9S_MB_2U(SCH_1):SMB_PEHPCPU1_LVC3_R3_SDA':
 C_SIGNAL='@s9s_mb_2u_lib.s9s_mb_2u(sch_1):smb_pehpcpu1_lvc3_r3_sda';
NODE_NAME     R3157 2
 '@S9S_MB_2U_LIB.S9S_MB_2U(SCH_1):PAGE132_I33@PURE_QUANTA.Q_RES(CHIPS)':
 'B': CDS_PINID='B';
NODE_NAME     U51 23
 '@S9S_MB_2U_LIB.S9S_MB_2U(SCH_1):PAGE132_I66@PURE_QUANTA.PCA9555APW(CHIPS)':
 'SDA': CDS_PINID='SDA';
NET_NAME
'SMB_PEHPCPU1_LVC3_SCL'
 '@S9S_MB_2U_LIB.S9S_MB_2U(SCH_1):SMB_PEHPCPU1_LVC3_SCL':
 C_SIGNAL='@s9s_mb_2u_lib.s9s_mb_2u(sch_1):smb_pehpcpu1_lvc3_scl';
NODE_NAME     R2479 2
 '@S9S_MB_2U_LIB.S9S_MB_2U(SCH_1):PAGE223_I76@PURE_QUANTA.Q_RES(CHIPS)':
 'B': CDS_PINID='B';
NODE_NAME     R966 2
 '@S9S_MB_2U_LIB.S9S_MB_2U(SCH_1):PAGE223_I82@PURE_QUANTA.Q_RES(CHIPS)':
 'B': CDS_PINID='B';
NODE_NAME     R3156 1
 '@S9S_MB_2U_LIB.S9S_MB_2U(SCH_1):PAGE132_I34@PURE_QUANTA.Q_RES(CHIPS)':
 'A': CDS_PINID='A';
NET_NAME
'SMB_PEHPCPU1_LVC3_SCL_R0'
 '@S9S_MB_2U_LIB.S9S_MB_2U(SCH_1):SMB_PEHPCPU1_LVC3_SCL_R0':
 C_SIGNAL='@s9s_mb_2u_lib.s9s_mb_2u(sch_1):smb_pehpcpu1_lvc3_scl_r0';
NODE_NAME     U29 7
 '@S9S_MB_2U_LIB.S9S_MB_2U(SCH_1):PAGE223_I43@PURE_QUANTA.PCA9617ADP(CHIPS)':
 'SCLB': CDS_PINID='SCLB';
NODE_NAME     R2479 1
 '@S9S_MB_2U_LIB.S9S_MB_2U(SCH_1):PAGE223_I76@PURE_QUANTA.Q_RES(CHIPS)':
 'A': CDS_PINID='A';
NET_NAME
'SMB_PEHPCPU1_LVC3_SDA'
 '@S9S_MB_2U_LIB.S9S_MB_2U(SCH_1):SMB_PEHPCPU1_LVC3_SDA':
 C_SIGNAL='@s9s_mb_2u_lib.s9s_mb_2u(sch_1):smb_pehpcpu1_lvc3_sda';
NODE_NAME     R2480 2
 '@S9S_MB_2U_LIB.S9S_MB_2U(SCH_1):PAGE223_I77@PURE_QUANTA.Q_RES(CHIPS)':
 'B': CDS_PINID='B';
NODE_NAME     R968 2
 '@S9S_MB_2U_LIB.S9S_MB_2U(SCH_1):PAGE223_I81@PURE_QUANTA.Q_RES(CHIPS)':
 'B': CDS_PINID='B';
NODE_NAME     R3157 1
 '@S9S_MB_2U_LIB.S9S_MB_2U(SCH_1):PAGE132_I33@PURE_QUANTA.Q_RES(CHIPS)':
 'A': CDS_PINID='A';
NET_NAME
'SMB_PEHPCPU1_LVC3_SDA_R0'
 '@S9S_MB_2U_LIB.S9S_MB_2U(SCH_1):SMB_PEHPCPU1_LVC3_SDA_R0':
 C_SIGNAL='@s9s_mb_2u_lib.s9s_mb_2u(sch_1):smb_pehpcpu1_lvc3_sda_r0';
NODE_NAME     U29 6
 '@S9S_MB_2U_LIB.S9S_MB_2U(SCH_1):PAGE223_I43@PURE_QUANTA.PCA9617ADP(CHIPS)':
 'SDAB': CDS_PINID='SDAB';
NODE_NAME     R2480 1
 '@S9S_MB_2U_LIB.S9S_MB_2U(SCH_1):PAGE223_I77@PURE_QUANTA.Q_RES(CHIPS)':
 'A': CDS_PINID='A';
NET_NAME
'SMB_PMBUS_SML1_ME_SCL'
 '@S9S_MB_2U_LIB.S9S_MB_2U(SCH_1):SMB_PMBUS_SML1_ME_SCL':
 C_SIGNAL='@s9s_mb_2u_lib.s9s_mb_2u(sch_1):smb_pmbus_sml1_me_scl';
NODE_NAME     R3060 2
 '@S9S_MB_2U_LIB.S9S_MB_2U(SCH_1):PAGE228_I237@PURE_QUANTA.Q_RES(CHIPS)':
 'B': CDS_PINID='B';
NODE_NAME     J100 5
 '@S9S_MB_2U_LIB.S9S_MB_2U(SCH_1):PAGE215_I32@PURE_QUANTA.SCONN20_513860200CV01(CHIPS)':
 '5': CDS_PINID='\5\';
NET_NAME
'SMB_PMBUS_SML1_ME_SDA'
 '@S9S_MB_2U_LIB.S9S_MB_2U(SCH_1):SMB_PMBUS_SML1_ME_SDA':
 C_SIGNAL='@s9s_mb_2u_lib.s9s_mb_2u(sch_1):smb_pmbus_sml1_me_sda';
NODE_NAME     R3061 2
 '@S9S_MB_2U_LIB.S9S_MB_2U(SCH_1):PAGE228_I234@PURE_QUANTA.Q_RES(CHIPS)':
 'B': CDS_PINID='B';
NODE_NAME     J100 7
 '@S9S_MB_2U_LIB.S9S_MB_2U(SCH_1):PAGE215_I32@PURE_QUANTA.SCONN20_513860200CV01(CHIPS)':
 '7': CDS_PINID='\7\';
NET_NAME
'SMB_S3M_CPU0_3V3AUX_SCL'
 '@S9S_MB_2U_LIB.S9S_MB_2U(SCH_1):SMB_S3M_CPU0_3V3AUX_SCL':
 C_SIGNAL='@s9s_mb_2u_lib.s9s_mb_2u(sch_1):smb_s3m_cpu0_3v3aux_scl';
NODE_NAME     R977 2
 '@S9S_MB_2U_LIB.S9S_MB_2U(SCH_1):PAGE224_I8@PURE_QUANTA.Q_RES(CHIPS)':
 'B': CDS_PINID='B';
NODE_NAME     R448 1
 '@S9S_MB_2U_LIB.S9S_MB_2U(SCH_1):PAGE224_I13@PURE_QUANTA.Q_RES(CHIPS)':
 'A': CDS_PINID='A';
NODE_NAME     U30 7
 '@S9S_MB_2U_LIB.S9S_MB_2U(SCH_1):PAGE224_I28@PURE_QUANTA.PCA9517AD(CHIPS)':
 'SCLB': CDS_PINID='SCLB';
NODE_NAME     R2209 2
 '@S9S_MB_2U_LIB.S9S_MB_2U(SCH_1):PAGE224_I63@PURE_QUANTA.Q_RES(CHIPS)':
 'B': CDS_PINID='B';
NET_NAME
'SMB_S3M_CPU0_3V3AUX_SCL_R'
 '@S9S_MB_2U_LIB.S9S_MB_2U(SCH_1):SMB_S3M_CPU0_3V3AUX_SCL_R':
 C_SIGNAL='@s9s_mb_2u_lib.s9s_mb_2u(sch_1):smb_s3m_cpu0_3v3aux_scl_r';
NODE_NAME     R2209 1
 '@S9S_MB_2U_LIB.S9S_MB_2U(SCH_1):PAGE224_I63@PURE_QUANTA.Q_RES(CHIPS)':
 'A': CDS_PINID='A';
NODE_NAME     U143 6
 '@S9S_MB_2U_LIB.S9S_MB_2U(SCH_1):PAGE224_I106@PURE_QUANTA.PCA9545APW(CHIPS)':
 'SC0': CDS_PINID='SC0';
NET_NAME
'SMB_S3M_CPU0_3V3AUX_SDA'
 '@S9S_MB_2U_LIB.S9S_MB_2U(SCH_1):SMB_S3M_CPU0_3V3AUX_SDA':
 C_SIGNAL='@s9s_mb_2u_lib.s9s_mb_2u(sch_1):smb_s3m_cpu0_3v3aux_sda';
NODE_NAME     R1648 1
 '@S9S_MB_2U_LIB.S9S_MB_2U(SCH_1):PAGE224_I3@PURE_QUANTA.Q_RES(CHIPS)':
 'A': CDS_PINID='A';
NODE_NAME     R979 2
 '@S9S_MB_2U_LIB.S9S_MB_2U(SCH_1):PAGE224_I6@PURE_QUANTA.Q_RES(CHIPS)':
 'B': CDS_PINID='B';
NODE_NAME     U30 6
 '@S9S_MB_2U_LIB.S9S_MB_2U(SCH_1):PAGE224_I28@PURE_QUANTA.PCA9517AD(CHIPS)':
 'SDAB': CDS_PINID='SDAB';
NODE_NAME     R2208 2
 '@S9S_MB_2U_LIB.S9S_MB_2U(SCH_1):PAGE224_I62@PURE_QUANTA.Q_RES(CHIPS)':
 'B': CDS_PINID='B';
NET_NAME
'SMB_S3M_CPU0_3V3AUX_SDA_R'
 '@S9S_MB_2U_LIB.S9S_MB_2U(SCH_1):SMB_S3M_CPU0_3V3AUX_SDA_R':
 C_SIGNAL='@s9s_mb_2u_lib.s9s_mb_2u(sch_1):smb_s3m_cpu0_3v3aux_sda_r';
NODE_NAME     R2208 1
 '@S9S_MB_2U_LIB.S9S_MB_2U(SCH_1):PAGE224_I62@PURE_QUANTA.Q_RES(CHIPS)':
 'A': CDS_PINID='A';
NODE_NAME     U143 5
 '@S9S_MB_2U_LIB.S9S_MB_2U(SCH_1):PAGE224_I106@PURE_QUANTA.PCA9545APW(CHIPS)':
 'SD0': CDS_PINID='SD0';
NET_NAME
'SMB_S3M_CPU0_PIROM_3V3AUX_SCL'
 '@S9S_MB_2U_LIB.S9S_MB_2U(SCH_1):SMB_S3M_CPU0_PIROM_3V3AUX_SCL':
 C_SIGNAL='@s9s_mb_2u_lib.s9s_mb_2u(sch_1):smb_s3m_cpu0_pirom_3v3aux_scl';
NODE_NAME     R1932 1
 '@S9S_MB_2U_LIB.S9S_MB_2U(SCH_1):PAGE14_I109@PURE_QUANTA.Q_RES(CHIPS)':
 'A': CDS_PINID='A';
NODE_NAME     R3123 2
 '@S9S_MB_2U_LIB.S9S_MB_2U(SCH_1):PAGE224_I115@PURE_QUANTA.Q_RES(CHIPS)':
 'B': CDS_PINID='B';
NODE_NAME     R3222 1
 '@S9S_MB_2U_LIB.S9S_MB_2U(SCH_1):PAGE224_I132@PURE_QUANTA.Q_RES(CHIPS)':
 'A': CDS_PINID='A';
NET_NAME
'SMB_S3M_CPU0_PIROM_3V3AUX_SCL_1'
 '@S9S_MB_2U_LIB.S9S_MB_2U(SCH_1):SMB_S3M_CPU0_PIROM_3V3AUX_SCL_R1':
 C_SIGNAL='@s9s_mb_2u_lib.s9s_mb_2u(sch_1):smb_s3m_cpu0_pirom_3v3aux_scl_r1';
NODE_NAME     U2 CU70
 '@S9S_MB_2U_LIB.S9S_MB_2U(SCH_1):PAGE14_I1@PURE_QUANTA.SOCKET4677_AZIF0045P001C01CS(CHIPS)':
 'PIROM_SCL': CDS_PINID='PIROM_SCL';
NODE_NAME     R1932 2
 '@S9S_MB_2U_LIB.S9S_MB_2U(SCH_1):PAGE14_I109@PURE_QUANTA.Q_RES(CHIPS)':
 'B': CDS_PINID='B';
NET_NAME
'SMB_S3M_CPU0_PIROM_3V3AUX_SCL_R'
 '@S9S_MB_2U_LIB.S9S_MB_2U(SCH_1):SMB_S3M_CPU0_PIROM_3V3AUX_SCL_R':
 C_SIGNAL='@s9s_mb_2u_lib.s9s_mb_2u(sch_1):smb_s3m_cpu0_pirom_3v3aux_scl_r';
NODE_NAME     U143 13
 '@S9S_MB_2U_LIB.S9S_MB_2U(SCH_1):PAGE224_I106@PURE_QUANTA.PCA9545APW(CHIPS)':
 'SC2': CDS_PINID='SC2';
NODE_NAME     R3123 1
 '@S9S_MB_2U_LIB.S9S_MB_2U(SCH_1):PAGE224_I115@PURE_QUANTA.Q_RES(CHIPS)':
 'A': CDS_PINID='A';
NET_NAME
'SMB_S3M_CPU0_PIROM_3V3AUX_SDA'
 '@S9S_MB_2U_LIB.S9S_MB_2U(SCH_1):SMB_S3M_CPU0_PIROM_3V3AUX_SDA':
 C_SIGNAL='@s9s_mb_2u_lib.s9s_mb_2u(sch_1):smb_s3m_cpu0_pirom_3v3aux_sda';
NODE_NAME     R1933 1
 '@S9S_MB_2U_LIB.S9S_MB_2U(SCH_1):PAGE14_I110@PURE_QUANTA.Q_RES(CHIPS)':
 'A': CDS_PINID='A';
NODE_NAME     R3124 2
 '@S9S_MB_2U_LIB.S9S_MB_2U(SCH_1):PAGE224_I114@PURE_QUANTA.Q_RES(CHIPS)':
 'B': CDS_PINID='B';
NODE_NAME     R3223 1
 '@S9S_MB_2U_LIB.S9S_MB_2U(SCH_1):PAGE224_I133@PURE_QUANTA.Q_RES(CHIPS)':
 'A': CDS_PINID='A';
NET_NAME
'SMB_S3M_CPU0_PIROM_3V3AUX_SDA_1'
 '@S9S_MB_2U_LIB.S9S_MB_2U(SCH_1):SMB_S3M_CPU0_PIROM_3V3AUX_SDA_R1':
 C_SIGNAL='@s9s_mb_2u_lib.s9s_mb_2u(sch_1):smb_s3m_cpu0_pirom_3v3aux_sda_r1';
NODE_NAME     U2 CM71
 '@S9S_MB_2U_LIB.S9S_MB_2U(SCH_1):PAGE14_I1@PURE_QUANTA.SOCKET4677_AZIF0045P001C01CS(CHIPS)':
 'PIROM_SDA': CDS_PINID='PIROM_SDA';
NODE_NAME     R1933 2
 '@S9S_MB_2U_LIB.S9S_MB_2U(SCH_1):PAGE14_I110@PURE_QUANTA.Q_RES(CHIPS)':
 'B': CDS_PINID='B';
NET_NAME
'SMB_S3M_CPU0_PIROM_3V3AUX_SDA_R'
 '@S9S_MB_2U_LIB.S9S_MB_2U(SCH_1):SMB_S3M_CPU0_PIROM_3V3AUX_SDA_R':
 C_SIGNAL='@s9s_mb_2u_lib.s9s_mb_2u(sch_1):smb_s3m_cpu0_pirom_3v3aux_sda_r';
NODE_NAME     U143 12
 '@S9S_MB_2U_LIB.S9S_MB_2U(SCH_1):PAGE224_I106@PURE_QUANTA.PCA9545APW(CHIPS)':
 'SD2': CDS_PINID='SD2';
NODE_NAME     R3124 1
 '@S9S_MB_2U_LIB.S9S_MB_2U(SCH_1):PAGE224_I114@PURE_QUANTA.Q_RES(CHIPS)':
 'A': CDS_PINID='A';
NET_NAME
'SMB_S3M_CPU0_R_SCL'
 '@S9S_MB_2U_LIB.S9S_MB_2U(SCH_1):SMB_S3M_CPU0_R_SCL':
 C_SIGNAL='@s9s_mb_2u_lib.s9s_mb_2u(sch_1):smb_s3m_cpu0_r_scl';
NODE_NAME     U30 2
 '@S9S_MB_2U_LIB.S9S_MB_2U(SCH_1):PAGE224_I28@PURE_QUANTA.PCA9517AD(CHIPS)':
 'SCLA': CDS_PINID='SCLA';
NODE_NAME     R969 2
 '@S9S_MB_2U_LIB.S9S_MB_2U(SCH_1):PAGE224_I43@PURE_QUANTA.Q_RES(CHIPS)':
 'B': CDS_PINID='B';
NODE_NAME     R993 2
 '@S9S_MB_2U_LIB.S9S_MB_2U(SCH_1):PAGE224_I44@PURE_QUANTA.Q_RES(CHIPS)':
 'B': CDS_PINID='B';
NET_NAME
'SMB_S3M_CPU0_R_SDA'
 '@S9S_MB_2U_LIB.S9S_MB_2U(SCH_1):SMB_S3M_CPU0_R_SDA':
 C_SIGNAL='@s9s_mb_2u_lib.s9s_mb_2u(sch_1):smb_s3m_cpu0_r_sda';
NODE_NAME     U30 3
 '@S9S_MB_2U_LIB.S9S_MB_2U(SCH_1):PAGE224_I28@PURE_QUANTA.PCA9517AD(CHIPS)':
 'SDAA': CDS_PINID='SDAA';
NODE_NAME     R971 2
 '@S9S_MB_2U_LIB.S9S_MB_2U(SCH_1):PAGE224_I42@PURE_QUANTA.Q_RES(CHIPS)':
 'B': CDS_PINID='B';
NODE_NAME     R994 2
 '@S9S_MB_2U_LIB.S9S_MB_2U(SCH_1):PAGE224_I142@PURE_QUANTA.Q_RES(CHIPS)':
 'B': CDS_PINID='B';
NET_NAME
'SMB_S3M_CPU0_SCL'
 '@S9S_MB_2U_LIB.S9S_MB_2U(SCH_1):SMB_S3M_CPU0_SCL':
 C_SIGNAL='@s9s_mb_2u_lib.s9s_mb_2u(sch_1):smb_s3m_cpu0_scl';
NODE_NAME     U2 CE64
 '@S9S_MB_2U_LIB.S9S_MB_2U(SCH_1):PAGE15_I1@PURE_QUANTA.SOCKET4677_AZIF0045P001C01CS(CHIPS)':
 'SMB_CLK': CDS_PINID='SMB_CLK';
NODE_NAME     R993 1
 '@S9S_MB_2U_LIB.S9S_MB_2U(SCH_1):PAGE224_I44@PURE_QUANTA.Q_RES(CHIPS)':
 'A': CDS_PINID='A';
NET_NAME
'SMB_S3M_CPU0_SDA'
 '@S9S_MB_2U_LIB.S9S_MB_2U(SCH_1):SMB_S3M_CPU0_SDA':
 C_SIGNAL='@s9s_mb_2u_lib.s9s_mb_2u(sch_1):smb_s3m_cpu0_sda';
NODE_NAME     U2 CD63
 '@S9S_MB_2U_LIB.S9S_MB_2U(SCH_1):PAGE15_I1@PURE_QUANTA.SOCKET4677_AZIF0045P001C01CS(CHIPS)':
 'SMB_DATA': CDS_PINID='SMB_DATA';
NODE_NAME     R994 1
 '@S9S_MB_2U_LIB.S9S_MB_2U(SCH_1):PAGE224_I142@PURE_QUANTA.Q_RES(CHIPS)':
 'A': CDS_PINID='A';
NET_NAME
'SMB_S3M_CPU1_3V3AUX_SCL'
 '@S9S_MB_2U_LIB.S9S_MB_2U(SCH_1):SMB_S3M_CPU1_3V3AUX_SCL':
 C_SIGNAL='@s9s_mb_2u_lib.s9s_mb_2u(sch_1):smb_s3m_cpu1_3v3aux_scl';
NODE_NAME     R448 2
 '@S9S_MB_2U_LIB.S9S_MB_2U(SCH_1):PAGE224_I13@PURE_QUANTA.Q_RES(CHIPS)':
 'B': CDS_PINID='B';
NODE_NAME     R978 2
 '@S9S_MB_2U_LIB.S9S_MB_2U(SCH_1):PAGE224_I16@PURE_QUANTA.Q_RES(CHIPS)':
 'B': CDS_PINID='B';
NODE_NAME     U31 7
 '@S9S_MB_2U_LIB.S9S_MB_2U(SCH_1):PAGE224_I37@PURE_QUANTA.PCA9517AD(CHIPS)':
 'SCLB': CDS_PINID='SCLB';
NODE_NAME     R2211 2
 '@S9S_MB_2U_LIB.S9S_MB_2U(SCH_1):PAGE224_I65@PURE_QUANTA.Q_RES(CHIPS)':
 'B': CDS_PINID='B';
NET_NAME
'SMB_S3M_CPU1_3V3AUX_SCL_R'
 '@S9S_MB_2U_LIB.S9S_MB_2U(SCH_1):SMB_S3M_CPU1_3V3AUX_SCL_R':
 C_SIGNAL='@s9s_mb_2u_lib.s9s_mb_2u(sch_1):smb_s3m_cpu1_3v3aux_scl_r';
NODE_NAME     R2211 1
 '@S9S_MB_2U_LIB.S9S_MB_2U(SCH_1):PAGE224_I65@PURE_QUANTA.Q_RES(CHIPS)':
 'A': CDS_PINID='A';
NODE_NAME     U143 9
 '@S9S_MB_2U_LIB.S9S_MB_2U(SCH_1):PAGE224_I106@PURE_QUANTA.PCA9545APW(CHIPS)':
 'SC1': CDS_PINID='SC1';
NET_NAME
'SMB_S3M_CPU1_3V3AUX_SDA'
 '@S9S_MB_2U_LIB.S9S_MB_2U(SCH_1):SMB_S3M_CPU1_3V3AUX_SDA':
 C_SIGNAL='@s9s_mb_2u_lib.s9s_mb_2u(sch_1):smb_s3m_cpu1_3v3aux_sda';
NODE_NAME     R1648 2
 '@S9S_MB_2U_LIB.S9S_MB_2U(SCH_1):PAGE224_I3@PURE_QUANTA.Q_RES(CHIPS)':
 'B': CDS_PINID='B';
NODE_NAME     R980 2
 '@S9S_MB_2U_LIB.S9S_MB_2U(SCH_1):PAGE224_I14@PURE_QUANTA.Q_RES(CHIPS)':
 'B': CDS_PINID='B';
NODE_NAME     U31 6
 '@S9S_MB_2U_LIB.S9S_MB_2U(SCH_1):PAGE224_I37@PURE_QUANTA.PCA9517AD(CHIPS)':
 'SDAB': CDS_PINID='SDAB';
NODE_NAME     R2210 2
 '@S9S_MB_2U_LIB.S9S_MB_2U(SCH_1):PAGE224_I64@PURE_QUANTA.Q_RES(CHIPS)':
 'B': CDS_PINID='B';
NET_NAME
'SMB_S3M_CPU1_3V3AUX_SDA_R'
 '@S9S_MB_2U_LIB.S9S_MB_2U(SCH_1):SMB_S3M_CPU1_3V3AUX_SDA_R':
 C_SIGNAL='@s9s_mb_2u_lib.s9s_mb_2u(sch_1):smb_s3m_cpu1_3v3aux_sda_r';
NODE_NAME     R2210 1
 '@S9S_MB_2U_LIB.S9S_MB_2U(SCH_1):PAGE224_I64@PURE_QUANTA.Q_RES(CHIPS)':
 'A': CDS_PINID='A';
NODE_NAME     U143 8
 '@S9S_MB_2U_LIB.S9S_MB_2U(SCH_1):PAGE224_I106@PURE_QUANTA.PCA9545APW(CHIPS)':
 'SD1': CDS_PINID='SD1';
NET_NAME
'SMB_S3M_CPU1_PIROM_3V3AUX_SCL'
 '@S9S_MB_2U_LIB.S9S_MB_2U(SCH_1):SMB_S3M_CPU1_PIROM_3V3AUX_SCL':
 C_SIGNAL='@s9s_mb_2u_lib.s9s_mb_2u(sch_1):smb_s3m_cpu1_pirom_3v3aux_scl';
NODE_NAME     R1934 1
 '@S9S_MB_2U_LIB.S9S_MB_2U(SCH_1):PAGE45_I81@PURE_QUANTA.Q_RES(CHIPS)':
 'A': CDS_PINID='A';
NODE_NAME     R3125 2
 '@S9S_MB_2U_LIB.S9S_MB_2U(SCH_1):PAGE224_I116@PURE_QUANTA.Q_RES(CHIPS)':
 'B': CDS_PINID='B';
NODE_NAME     R3224 1
 '@S9S_MB_2U_LIB.S9S_MB_2U(SCH_1):PAGE224_I131@PURE_QUANTA.Q_RES(CHIPS)':
 'A': CDS_PINID='A';
NET_NAME
'SMB_S3M_CPU1_PIROM_3V3AUX_SCL_1'
 '@S9S_MB_2U_LIB.S9S_MB_2U(SCH_1):SMB_S3M_CPU1_PIROM_3V3AUX_SCL_R1':
 C_SIGNAL='@s9s_mb_2u_lib.s9s_mb_2u(sch_1):smb_s3m_cpu1_pirom_3v3aux_scl_r1';
NODE_NAME     U1 CU70
 '@S9S_MB_2U_LIB.S9S_MB_2U(SCH_1):PAGE45_I29@PURE_QUANTA.SOCKET4677_AZIF0045P001C01CS(CHIPS)':
 'PIROM_SCL': CDS_PINID='PIROM_SCL';
NODE_NAME     R1934 2
 '@S9S_MB_2U_LIB.S9S_MB_2U(SCH_1):PAGE45_I81@PURE_QUANTA.Q_RES(CHIPS)':
 'B': CDS_PINID='B';
NET_NAME
'SMB_S3M_CPU1_PIROM_3V3AUX_SCL_R'
 '@S9S_MB_2U_LIB.S9S_MB_2U(SCH_1):SMB_S3M_CPU1_PIROM_3V3AUX_SCL_R':
 C_SIGNAL='@s9s_mb_2u_lib.s9s_mb_2u(sch_1):smb_s3m_cpu1_pirom_3v3aux_scl_r';
NODE_NAME     U143 16
 '@S9S_MB_2U_LIB.S9S_MB_2U(SCH_1):PAGE224_I106@PURE_QUANTA.PCA9545APW(CHIPS)':
 'SC3': CDS_PINID='SC3';
NODE_NAME     R3125 1
 '@S9S_MB_2U_LIB.S9S_MB_2U(SCH_1):PAGE224_I116@PURE_QUANTA.Q_RES(CHIPS)':
 'A': CDS_PINID='A';
NET_NAME
'SMB_S3M_CPU1_PIROM_3V3AUX_SDA'
 '@S9S_MB_2U_LIB.S9S_MB_2U(SCH_1):SMB_S3M_CPU1_PIROM_3V3AUX_SDA':
 C_SIGNAL='@s9s_mb_2u_lib.s9s_mb_2u(sch_1):smb_s3m_cpu1_pirom_3v3aux_sda';
NODE_NAME     R1935 1
 '@S9S_MB_2U_LIB.S9S_MB_2U(SCH_1):PAGE45_I82@PURE_QUANTA.Q_RES(CHIPS)':
 'A': CDS_PINID='A';
NODE_NAME     R3126 2
 '@S9S_MB_2U_LIB.S9S_MB_2U(SCH_1):PAGE224_I117@PURE_QUANTA.Q_RES(CHIPS)':
 'B': CDS_PINID='B';
NODE_NAME     R3225 1
 '@S9S_MB_2U_LIB.S9S_MB_2U(SCH_1):PAGE224_I130@PURE_QUANTA.Q_RES(CHIPS)':
 'A': CDS_PINID='A';
NET_NAME
'SMB_S3M_CPU1_PIROM_3V3AUX_SDA_1'
 '@S9S_MB_2U_LIB.S9S_MB_2U(SCH_1):SMB_S3M_CPU1_PIROM_3V3AUX_SDA_R1':
 C_SIGNAL='@s9s_mb_2u_lib.s9s_mb_2u(sch_1):smb_s3m_cpu1_pirom_3v3aux_sda_r1';
NODE_NAME     U1 CM71
 '@S9S_MB_2U_LIB.S9S_MB_2U(SCH_1):PAGE45_I29@PURE_QUANTA.SOCKET4677_AZIF0045P001C01CS(CHIPS)':
 'PIROM_SDA': CDS_PINID='PIROM_SDA';
NODE_NAME     R1935 2
 '@S9S_MB_2U_LIB.S9S_MB_2U(SCH_1):PAGE45_I82@PURE_QUANTA.Q_RES(CHIPS)':
 'B': CDS_PINID='B';
NET_NAME
'SMB_S3M_CPU1_PIROM_3V3AUX_SDA_R'
 '@S9S_MB_2U_LIB.S9S_MB_2U(SCH_1):SMB_S3M_CPU1_PIROM_3V3AUX_SDA_R':
 C_SIGNAL='@s9s_mb_2u_lib.s9s_mb_2u(sch_1):smb_s3m_cpu1_pirom_3v3aux_sda_r';
NODE_NAME     U143 15
 '@S9S_MB_2U_LIB.S9S_MB_2U(SCH_1):PAGE224_I106@PURE_QUANTA.PCA9545APW(CHIPS)':
 'SD3': CDS_PINID='SD3';
NODE_NAME     R3126 1
 '@S9S_MB_2U_LIB.S9S_MB_2U(SCH_1):PAGE224_I117@PURE_QUANTA.Q_RES(CHIPS)':
 'A': CDS_PINID='A';
NET_NAME
'SMB_S3M_CPU1_R_SCL'
 '@S9S_MB_2U_LIB.S9S_MB_2U(SCH_1):SMB_S3M_CPU1_R_SCL':
 C_SIGNAL='@s9s_mb_2u_lib.s9s_mb_2u(sch_1):smb_s3m_cpu1_r_scl';
NODE_NAME     U31 2
 '@S9S_MB_2U_LIB.S9S_MB_2U(SCH_1):PAGE224_I37@PURE_QUANTA.PCA9517AD(CHIPS)':
 'SCLA': CDS_PINID='SCLA';
NODE_NAME     R970 2
 '@S9S_MB_2U_LIB.S9S_MB_2U(SCH_1):PAGE224_I50@PURE_QUANTA.Q_RES(CHIPS)':
 'B': CDS_PINID='B';
NODE_NAME     R995 2
 '@S9S_MB_2U_LIB.S9S_MB_2U(SCH_1):PAGE224_I51@PURE_QUANTA.Q_RES(CHIPS)':
 'B': CDS_PINID='B';
NET_NAME
'SMB_S3M_CPU1_R_SDA'
 '@S9S_MB_2U_LIB.S9S_MB_2U(SCH_1):SMB_S3M_CPU1_R_SDA':
 C_SIGNAL='@s9s_mb_2u_lib.s9s_mb_2u(sch_1):smb_s3m_cpu1_r_sda';
NODE_NAME     U31 3
 '@S9S_MB_2U_LIB.S9S_MB_2U(SCH_1):PAGE224_I37@PURE_QUANTA.PCA9517AD(CHIPS)':
 'SDAA': CDS_PINID='SDAA';
NODE_NAME     R972 2
 '@S9S_MB_2U_LIB.S9S_MB_2U(SCH_1):PAGE224_I49@PURE_QUANTA.Q_RES(CHIPS)':
 'B': CDS_PINID='B';
NODE_NAME     R996 2
 '@S9S_MB_2U_LIB.S9S_MB_2U(SCH_1):PAGE224_I143@PURE_QUANTA.Q_RES(CHIPS)':
 'B': CDS_PINID='B';
NET_NAME
'SMB_S3M_CPU1_SCL'
 '@S9S_MB_2U_LIB.S9S_MB_2U(SCH_1):SMB_S3M_CPU1_SCL':
 C_SIGNAL='@s9s_mb_2u_lib.s9s_mb_2u(sch_1):smb_s3m_cpu1_scl';
NODE_NAME     U1 CE64
 '@S9S_MB_2U_LIB.S9S_MB_2U(SCH_1):PAGE46_I5@PURE_QUANTA.SOCKET4677_AZIF0045P001C01CS(CHIPS)':
 'SMB_CLK': CDS_PINID='SMB_CLK';
NODE_NAME     R995 1
 '@S9S_MB_2U_LIB.S9S_MB_2U(SCH_1):PAGE224_I51@PURE_QUANTA.Q_RES(CHIPS)':
 'A': CDS_PINID='A';
NET_NAME
'SMB_S3M_CPU1_SDA'
 '@S9S_MB_2U_LIB.S9S_MB_2U(SCH_1):SMB_S3M_CPU1_SDA':
 C_SIGNAL='@s9s_mb_2u_lib.s9s_mb_2u(sch_1):smb_s3m_cpu1_sda';
NODE_NAME     U1 CD63
 '@S9S_MB_2U_LIB.S9S_MB_2U(SCH_1):PAGE46_I5@PURE_QUANTA.SOCKET4677_AZIF0045P001C01CS(CHIPS)':
 'SMB_DATA': CDS_PINID='SMB_DATA';
NODE_NAME     R996 1
 '@S9S_MB_2U_LIB.S9S_MB_2U(SCH_1):PAGE224_I143@PURE_QUANTA.Q_RES(CHIPS)':
 'A': CDS_PINID='A';
NET_NAME
'SMB_S3M_CPU_3V3AUX_SCL'
 '@S9S_MB_2U_LIB.S9S_MB_2U(SCH_1):SMB_S3M_CPU_3V3AUX_SCL':
 C_SIGNAL='@s9s_mb_2u_lib.s9s_mb_2u(sch_1):smb_s3m_cpu_3v3aux_scl';
NODE_NAME     R2212 1
 '@S9S_MB_2U_LIB.S9S_MB_2U(SCH_1):PAGE228_I202@PURE_QUANTA.Q_RES(CHIPS)':
 'A': CDS_PINID='A';
NODE_NAME     U143 18
 '@S9S_MB_2U_LIB.S9S_MB_2U(SCH_1):PAGE224_I106@PURE_QUANTA.PCA9545APW(CHIPS)':
 'SCL': CDS_PINID='SCL';
NODE_NAME     R2417 1
 '@S9S_MB_2U_LIB.S9S_MB_2U(SCH_1):PAGE227_I22@PURE_QUANTA.Q_RES(CHIPS)':
 'A': CDS_PINID='A';
NET_NAME
'SMB_S3M_CPU_3V3AUX_SCL_R0'
 '@S9S_MB_2U_LIB.S9S_MB_2U(SCH_1):SMB_S3M_CPU_3V3AUX_SCL_R0':
 C_SIGNAL='@s9s_mb_2u_lib.s9s_mb_2u(sch_1):smb_s3m_cpu_3v3aux_scl_r0';
NODE_NAME     R2417 2
 '@S9S_MB_2U_LIB.S9S_MB_2U(SCH_1):PAGE227_I22@PURE_QUANTA.Q_RES(CHIPS)':
 'B': CDS_PINID='B';
NODE_NAME     J41 A40
 '@S9S_MB_2U_LIB.S9S_MB_2U(SCH_1):PAGE227_I173@PURE_QUANTA.SCONN168_ME1016810202011(CHIPS)':
 'PERP7': CDS_PINID='PERP7';
NET_NAME
'SMB_S3M_CPU_3V3AUX_SDA'
 '@S9S_MB_2U_LIB.S9S_MB_2U(SCH_1):SMB_S3M_CPU_3V3AUX_SDA':
 C_SIGNAL='@s9s_mb_2u_lib.s9s_mb_2u(sch_1):smb_s3m_cpu_3v3aux_sda';
NODE_NAME     R2213 1
 '@S9S_MB_2U_LIB.S9S_MB_2U(SCH_1):PAGE228_I203@PURE_QUANTA.Q_RES(CHIPS)':
 'A': CDS_PINID='A';
NODE_NAME     U143 19
 '@S9S_MB_2U_LIB.S9S_MB_2U(SCH_1):PAGE224_I106@PURE_QUANTA.PCA9545APW(CHIPS)':
 'SDA': CDS_PINID='SDA';
NODE_NAME     R2418 1
 '@S9S_MB_2U_LIB.S9S_MB_2U(SCH_1):PAGE227_I23@PURE_QUANTA.Q_RES(CHIPS)':
 'A': CDS_PINID='A';
NET_NAME
'SMB_S3M_CPU_3V3AUX_SDA_R0'
 '@S9S_MB_2U_LIB.S9S_MB_2U(SCH_1):SMB_S3M_CPU_3V3AUX_SDA_R0':
 C_SIGNAL='@s9s_mb_2u_lib.s9s_mb_2u(sch_1):smb_s3m_cpu_3v3aux_sda_r0';
NODE_NAME     R2418 2
 '@S9S_MB_2U_LIB.S9S_MB_2U(SCH_1):PAGE227_I23@PURE_QUANTA.Q_RES(CHIPS)':
 'B': CDS_PINID='B';
NODE_NAME     J41 A41
 '@S9S_MB_2U_LIB.S9S_MB_2U(SCH_1):PAGE227_I173@PURE_QUANTA.SCONN168_ME1016810202011(CHIPS)':
 'GND_A41': CDS_PINID='GND_A41';
NET_NAME
'SMB_SENSOR_E1S_3V3AUX_SCL'
 '@S9S_MB_2U_LIB.S9S_MB_2U(SCH_1):SMB_SENSOR_E1S_3V3AUX_SCL':
 C_SIGNAL='@s9s_mb_2u_lib.s9s_mb_2u(sch_1):smb_sensor_e1s_3v3aux_scl';
NODE_NAME     U279 7
 '@S9S_MB_2U_LIB.S9S_MB_2U(SCH_1):PAGE183_I93@PURE_QUANTA.PCA9617ADP(CHIPS)':
 'SCLB': CDS_PINID='SCLB';
NODE_NAME     R3526 2
 '@S9S_MB_2U_LIB.S9S_MB_2U(SCH_1):PAGE219_I35@PURE_QUANTA.Q_RES(CHIPS)':
 'B': CDS_PINID='B';
NODE_NAME     R3535 2
 '@S9S_MB_2U_LIB.S9S_MB_2U(SCH_1):PAGE219_I49@PURE_QUANTA.Q_RES(CHIPS)':
 'B': CDS_PINID='B';
NET_NAME
'SMB_SENSOR_E1S_3V3AUX_SDA'
 '@S9S_MB_2U_LIB.S9S_MB_2U(SCH_1):SMB_SENSOR_E1S_3V3AUX_SDA':
 C_SIGNAL='@s9s_mb_2u_lib.s9s_mb_2u(sch_1):smb_sensor_e1s_3v3aux_sda';
NODE_NAME     U279 6
 '@S9S_MB_2U_LIB.S9S_MB_2U(SCH_1):PAGE183_I93@PURE_QUANTA.PCA9617ADP(CHIPS)':
 'SDAB': CDS_PINID='SDAB';
NODE_NAME     R3527 2
 '@S9S_MB_2U_LIB.S9S_MB_2U(SCH_1):PAGE219_I37@PURE_QUANTA.Q_RES(CHIPS)':
 'B': CDS_PINID='B';
NODE_NAME     R3536 2
 '@S9S_MB_2U_LIB.S9S_MB_2U(SCH_1):PAGE219_I50@PURE_QUANTA.Q_RES(CHIPS)':
 'B': CDS_PINID='B';
NET_NAME
'SMB_SENSOR_M2_P0_3V3AUX_SCL'
 '@S9S_MB_2U_LIB.S9S_MB_2U(SCH_1):SMB_SENSOR_M2_P0_3V3AUX_SCL':
 C_SIGNAL='@s9s_mb_2u_lib.s9s_mb_2u(sch_1):smb_sensor_m2_p0_3v3aux_scl';
NODE_NAME     U98 6
 '@S9S_MB_2U_LIB.S9S_MB_2U(SCH_1):PAGE183_I27@PURE_QUANTA.PCA9306DP1(CHIPS)':
 'SCL2': CDS_PINID='SCL2';
NODE_NAME     R1089 2
 '@S9S_MB_2U_LIB.S9S_MB_2U(SCH_1):PAGE219_I21@PURE_QUANTA.Q_RES(CHIPS)':
 'B': CDS_PINID='B';
NODE_NAME     R2967 2
 '@S9S_MB_2U_LIB.S9S_MB_2U(SCH_1):PAGE219_I36@PURE_QUANTA.Q_RES(CHIPS)':
 'B': CDS_PINID='B';
NET_NAME
'SMB_SENSOR_M2_P0_3V3AUX_SDA'
 '@S9S_MB_2U_LIB.S9S_MB_2U(SCH_1):SMB_SENSOR_M2_P0_3V3AUX_SDA':
 C_SIGNAL='@s9s_mb_2u_lib.s9s_mb_2u(sch_1):smb_sensor_m2_p0_3v3aux_sda';
NODE_NAME     U98 5
 '@S9S_MB_2U_LIB.S9S_MB_2U(SCH_1):PAGE183_I27@PURE_QUANTA.PCA9306DP1(CHIPS)':
 'SDA2': CDS_PINID='SDA2';
NODE_NAME     R1090 2
 '@S9S_MB_2U_LIB.S9S_MB_2U(SCH_1):PAGE219_I20@PURE_QUANTA.Q_RES(CHIPS)':
 'B': CDS_PINID='B';
NODE_NAME     R2968 2
 '@S9S_MB_2U_LIB.S9S_MB_2U(SCH_1):PAGE219_I39@PURE_QUANTA.Q_RES(CHIPS)':
 'B': CDS_PINID='B';
NET_NAME
'SMB_SEN_MAM_3V3AUX_SCL'
 '@S9S_MB_2U_LIB.S9S_MB_2U(SCH_1):SMB_SEN_MAM_3V3AUX_SCL':
 C_SIGNAL='@s9s_mb_2u_lib.s9s_mb_2u(sch_1):smb_sen_mam_3v3aux_scl';
NODE_NAME     R1793 2
 '@S9S_MB_2U_LIB.S9S_MB_2U(SCH_1):PAGE239_I19@PURE_QUANTA.Q_RES(CHIPS)':
 'B': CDS_PINID='B';
NODE_NAME     U193 13
 '@S9S_MB_2U_LIB.S9S_MB_2U(SCH_1):PAGE239_I57@PURE_QUANTA.MAX11617EEET(CHIPS)':
 'SCL': CDS_PINID='SCL';
NET_NAME
'SMB_SEN_MAM_3V3AUX_SDA'
 '@S9S_MB_2U_LIB.S9S_MB_2U(SCH_1):SMB_SEN_MAM_3V3AUX_SDA':
 C_SIGNAL='@s9s_mb_2u_lib.s9s_mb_2u(sch_1):smb_sen_mam_3v3aux_sda';
NODE_NAME     R1792 2
 '@S9S_MB_2U_LIB.S9S_MB_2U(SCH_1):PAGE239_I20@PURE_QUANTA.Q_RES(CHIPS)':
 'B': CDS_PINID='B';
NODE_NAME     U193 14
 '@S9S_MB_2U_LIB.S9S_MB_2U(SCH_1):PAGE239_I57@PURE_QUANTA.MAX11617EEET(CHIPS)':
 'SDA': CDS_PINID='SDA';
NET_NAME
'SMB_SEN_TIC_3V3AUX_SCL'
 '@S9S_MB_2U_LIB.S9S_MB_2U(SCH_1):SMB_SEN_TIC_3V3AUX_SCL':
 C_SIGNAL='@s9s_mb_2u_lib.s9s_mb_2u(sch_1):smb_sen_tic_3v3aux_scl';
NODE_NAME     U269 3
 '@S9S_MB_2U_LIB.S9S_MB_2U(SCH_1):PAGE239_I103@PURE_QUANTA.ADC128D818CIMTXNOPB(CHIPS)':
 'SCL': CDS_PINID='SCL';
NODE_NAME     R3672 2
 '@S9S_MB_2U_LIB.S9S_MB_2U(SCH_1):PAGE239_I111@PURE_QUANTA.Q_RES(CHIPS)':
 'B': CDS_PINID='B';
NET_NAME
'SMB_SEN_TIC_3V3AUX_SDA'
 '@S9S_MB_2U_LIB.S9S_MB_2U(SCH_1):SMB_SEN_TIC_3V3AUX_SDA':
 C_SIGNAL='@s9s_mb_2u_lib.s9s_mb_2u(sch_1):smb_sen_tic_3v3aux_sda';
NODE_NAME     U269 2
 '@S9S_MB_2U_LIB.S9S_MB_2U(SCH_1):PAGE239_I103@PURE_QUANTA.ADC128D818CIMTXNOPB(CHIPS)':
 'SDA': CDS_PINID='SDA';
NODE_NAME     R3671 2
 '@S9S_MB_2U_LIB.S9S_MB_2U(SCH_1):PAGE239_I110@PURE_QUANTA.Q_RES(CHIPS)':
 'B': CDS_PINID='B';
NET_NAME
'SMB_SML0B_3V3AUX_SCL'
 '@S9S_MB_2U_LIB.S9S_MB_2U(SCH_1):SMB_SML0B_3V3AUX_SCL':
 C_SIGNAL='@s9s_mb_2u_lib.s9s_mb_2u(sch_1):smb_sml0b_3v3aux_scl';
NODE_NAME     U4 BB3
 '@S9S_MB_2U_LIB.S9S_MB_2U(SCH_1):PAGE175_I93@PURE_QUANTA.EMMITSBURG_REV0P9(CHIPS)':
 'GPPC_C_4_ME_SML0BCLK': CDS_PINID='GPPC_C_4_ME_SML0BCLK';
NODE_NAME     R1545 1
 '@S9S_MB_2U_LIB.S9S_MB_2U(SCH_1):PAGE175_I137@PURE_QUANTA.Q_RES(CHIPS)':
 'A': CDS_PINID='A';
NET_NAME
'SMB_SML0B_3V3AUX_SDA'
 '@S9S_MB_2U_LIB.S9S_MB_2U(SCH_1):SMB_SML0B_3V3AUX_SDA':
 C_SIGNAL='@s9s_mb_2u_lib.s9s_mb_2u(sch_1):smb_sml0b_3v3aux_sda';
NODE_NAME     U4 AU4
 '@S9S_MB_2U_LIB.S9S_MB_2U(SCH_1):PAGE175_I93@PURE_QUANTA.EMMITSBURG_REV0P9(CHIPS)':
 'GPPC_C_3_ME_SML0BDATA': CDS_PINID='GPPC_C_3_ME_SML0BDATA';
NODE_NAME     R1546 1
 '@S9S_MB_2U_LIB.S9S_MB_2U(SCH_1):PAGE175_I138@PURE_QUANTA.Q_RES(CHIPS)':
 'A': CDS_PINID='A';
NET_NAME
'SMB_SML0_3V3AUX_PCH_SCL'
 '@S9S_MB_2U_LIB.S9S_MB_2U(SCH_1):SMB_SML0_3V3AUX_PCH_SCL':
 C_SIGNAL='@s9s_mb_2u_lib.s9s_mb_2u(sch_1):smb_sml0_3v3aux_pch_scl';
NODE_NAME     U4 BC4
 '@S9S_MB_2U_LIB.S9S_MB_2U(SCH_1):PAGE175_I93@PURE_QUANTA.EMMITSBURG_REV0P9(CHIPS)':
 'GPPC_C_0_ME_SML0CLK': CDS_PINID='GPPC_C_0_ME_SML0CLK';
NODE_NAME     JP4 1
 '@S9S_MB_2U_LIB.S9S_MB_2U(SCH_1):PAGE175_I256@PURE_QUANTA.CONN3_210HP1030BR1(CHIPS)':
 '1': CDS_PINID='\1\';
NODE_NAME     R581 2
 '@S9S_MB_2U_LIB.S9S_MB_2U(SCH_1):PAGE228_I44@PURE_QUANTA.Q_RES(CHIPS)':
 'B': CDS_PINID='B';
NET_NAME
'SMB_SML0_3V3AUX_PCH_SDA'
 '@S9S_MB_2U_LIB.S9S_MB_2U(SCH_1):SMB_SML0_3V3AUX_PCH_SDA':
 C_SIGNAL='@s9s_mb_2u_lib.s9s_mb_2u(sch_1):smb_sml0_3v3aux_pch_sda';
NODE_NAME     U4 BA4
 '@S9S_MB_2U_LIB.S9S_MB_2U(SCH_1):PAGE175_I93@PURE_QUANTA.EMMITSBURG_REV0P9(CHIPS)':
 'GPPC_C_1_ME_SML0DATA': CDS_PINID='GPPC_C_1_ME_SML0DATA';
NODE_NAME     JP4 3
 '@S9S_MB_2U_LIB.S9S_MB_2U(SCH_1):PAGE175_I256@PURE_QUANTA.CONN3_210HP1030BR1(CHIPS)':
 '3': CDS_PINID='\3\';
NODE_NAME     R582 2
 '@S9S_MB_2U_LIB.S9S_MB_2U(SCH_1):PAGE228_I45@PURE_QUANTA.Q_RES(CHIPS)':
 'B': CDS_PINID='B';
NET_NAME
'SMB_SML0_3V3AUX_SCL'
 '@S9S_MB_2U_LIB.S9S_MB_2U(SCH_1):SMB_SML0_3V3AUX_SCL':
 C_SIGNAL='@s9s_mb_2u_lib.s9s_mb_2u(sch_1):smb_sml0_3v3aux_scl';
NODE_NAME     R1384 1
 '@S9S_MB_2U_LIB.S9S_MB_2U(SCH_1):PAGE228_I4@PURE_QUANTA.Q_RES(CHIPS)':
 'A': CDS_PINID='A';
NODE_NAME     R581 1
 '@S9S_MB_2U_LIB.S9S_MB_2U(SCH_1):PAGE228_I44@PURE_QUANTA.Q_RES(CHIPS)':
 'A': CDS_PINID='A';
NODE_NAME     R3058 1
 '@S9S_MB_2U_LIB.S9S_MB_2U(SCH_1):PAGE228_I242@PURE_QUANTA.Q_RES(CHIPS)':
 'A': CDS_PINID='A';
NODE_NAME     R4506 1
 '@S9S_MB_2U_LIB.S9S_MB_2U(SCH_1):PAGE227_I90@PURE_QUANTA.Q_RES(CHIPS)':
 'A': CDS_PINID='A';
NET_NAME
'SMB_SML0_3V3AUX_SCL_R1'
 '@S9S_MB_2U_LIB.S9S_MB_2U(SCH_1):SMB_SML0_3V3AUX_SCL_R1':
 C_SIGNAL='@s9s_mb_2u_lib.s9s_mb_2u(sch_1):smb_sml0_3v3aux_scl_r1';
NODE_NAME     R4506 2
 '@S9S_MB_2U_LIB.S9S_MB_2U(SCH_1):PAGE227_I90@PURE_QUANTA.Q_RES(CHIPS)':
 'B': CDS_PINID='B';
NODE_NAME     J41 A25
 '@S9S_MB_2U_LIB.S9S_MB_2U(SCH_1):PAGE227_I173@PURE_QUANTA.SCONN168_ME1016810202011(CHIPS)':
 'GND_A25': CDS_PINID='GND_A25';
NET_NAME
'SMB_SML0_3V3AUX_SDA'
 '@S9S_MB_2U_LIB.S9S_MB_2U(SCH_1):SMB_SML0_3V3AUX_SDA':
 C_SIGNAL='@s9s_mb_2u_lib.s9s_mb_2u(sch_1):smb_sml0_3v3aux_sda';
NODE_NAME     R1385 1
 '@S9S_MB_2U_LIB.S9S_MB_2U(SCH_1):PAGE228_I5@PURE_QUANTA.Q_RES(CHIPS)':
 'A': CDS_PINID='A';
NODE_NAME     R582 1
 '@S9S_MB_2U_LIB.S9S_MB_2U(SCH_1):PAGE228_I45@PURE_QUANTA.Q_RES(CHIPS)':
 'A': CDS_PINID='A';
NODE_NAME     R3059 1
 '@S9S_MB_2U_LIB.S9S_MB_2U(SCH_1):PAGE228_I243@PURE_QUANTA.Q_RES(CHIPS)':
 'A': CDS_PINID='A';
NODE_NAME     R4507 1
 '@S9S_MB_2U_LIB.S9S_MB_2U(SCH_1):PAGE227_I89@PURE_QUANTA.Q_RES(CHIPS)':
 'A': CDS_PINID='A';
NET_NAME
'SMB_SML0_3V3AUX_SDA_R1'
 '@S9S_MB_2U_LIB.S9S_MB_2U(SCH_1):SMB_SML0_3V3AUX_SDA_R1':
 C_SIGNAL='@s9s_mb_2u_lib.s9s_mb_2u(sch_1):smb_sml0_3v3aux_sda_r1';
NODE_NAME     R4507 2
 '@S9S_MB_2U_LIB.S9S_MB_2U(SCH_1):PAGE227_I89@PURE_QUANTA.Q_RES(CHIPS)':
 'B': CDS_PINID='B';
NODE_NAME     J41 A26
 '@S9S_MB_2U_LIB.S9S_MB_2U(SCH_1):PAGE227_I173@PURE_QUANTA.SCONN168_ME1016810202011(CHIPS)':
 'PERN3': CDS_PINID='PERN3';
NET_NAME
'SMB_SML0_ME_SCL'
 '@S9S_MB_2U_LIB.S9S_MB_2U(SCH_1):SMB_SML0_ME_SCL':
 C_SIGNAL='@s9s_mb_2u_lib.s9s_mb_2u(sch_1):smb_sml0_me_scl';
NODE_NAME     R3058 2
 '@S9S_MB_2U_LIB.S9S_MB_2U(SCH_1):PAGE228_I242@PURE_QUANTA.Q_RES(CHIPS)':
 'B': CDS_PINID='B';
NODE_NAME     J100 1
 '@S9S_MB_2U_LIB.S9S_MB_2U(SCH_1):PAGE215_I32@PURE_QUANTA.SCONN20_513860200CV01(CHIPS)':
 '1': CDS_PINID='\1\';
NET_NAME
'SMB_SML0_ME_SDA'
 '@S9S_MB_2U_LIB.S9S_MB_2U(SCH_1):SMB_SML0_ME_SDA':
 C_SIGNAL='@s9s_mb_2u_lib.s9s_mb_2u(sch_1):smb_sml0_me_sda';
NODE_NAME     R3059 2
 '@S9S_MB_2U_LIB.S9S_MB_2U(SCH_1):PAGE228_I243@PURE_QUANTA.Q_RES(CHIPS)':
 'B': CDS_PINID='B';
NODE_NAME     J100 3
 '@S9S_MB_2U_LIB.S9S_MB_2U(SCH_1):PAGE215_I32@PURE_QUANTA.SCONN20_513860200CV01(CHIPS)':
 '3': CDS_PINID='\3\';
NET_NAME
'SMB_SML1_PMBUS_3V3AUX_PCH_SCL'
 '@S9S_MB_2U_LIB.S9S_MB_2U(SCH_1):SMB_SML1_PMBUS_3V3AUX_PCH_SCL':
 C_SIGNAL='@s9s_mb_2u_lib.s9s_mb_2u(sch_1):smb_sml1_pmbus_3v3aux_pch_scl';
NODE_NAME     R1386 1
 '@S9S_MB_2U_LIB.S9S_MB_2U(SCH_1):PAGE228_I6@PURE_QUANTA.Q_RES(CHIPS)':
 'A': CDS_PINID='A';
NODE_NAME     R2995 1
 '@S9S_MB_2U_LIB.S9S_MB_2U(SCH_1):PAGE228_I228@PURE_QUANTA.Q_RES(CHIPS)':
 'A': CDS_PINID='A';
NODE_NAME     R3060 1
 '@S9S_MB_2U_LIB.S9S_MB_2U(SCH_1):PAGE228_I237@PURE_QUANTA.Q_RES(CHIPS)':
 'A': CDS_PINID='A';
NODE_NAME     R4505 1
 '@S9S_MB_2U_LIB.S9S_MB_2U(SCH_1):PAGE175_I305@PURE_QUANTA.Q_RES(CHIPS)':
 'A': CDS_PINID='A';
NODE_NAME     R2423 1
 '@S9S_MB_2U_LIB.S9S_MB_2U(SCH_1):PAGE227_I97@PURE_QUANTA.Q_RES(CHIPS)':
 'A': CDS_PINID='A';
NET_NAME
'SMB_SML1_PMBUS_3V3AUX_PCH_SCL_1'
 '@S9S_MB_2U_LIB.S9S_MB_2U(SCH_1):SMB_SML1_PMBUS_3V3AUX_PCH_SCL_R1':
 C_SIGNAL='@s9s_mb_2u_lib.s9s_mb_2u(sch_1):smb_sml1_pmbus_3v3aux_pch_scl_r1';
NODE_NAME     U4 AP1
 '@S9S_MB_2U_LIB.S9S_MB_2U(SCH_1):PAGE175_I93@PURE_QUANTA.EMMITSBURG_REV0P9(CHIPS)':
 'GPPC_C_6_ME_SML1CLK': CDS_PINID='GPPC_C_6_ME_SML1CLK';
NODE_NAME     JP9 1
 '@S9S_MB_2U_LIB.S9S_MB_2U(SCH_1):PAGE175_I263@PURE_QUANTA.CONN3_210HP1030BR1(CHIPS)':
 '1': CDS_PINID='\1\';
NODE_NAME     R4505 2
 '@S9S_MB_2U_LIB.S9S_MB_2U(SCH_1):PAGE175_I305@PURE_QUANTA.Q_RES(CHIPS)':
 'B': CDS_PINID='B';
NET_NAME
'SMB_SML1_PMBUS_3V3AUX_PCH_SCL_R'
 '@S9S_MB_2U_LIB.S9S_MB_2U(SCH_1):SMB_SML1_PMBUS_3V3AUX_PCH_SCL_R0':
 C_SIGNAL='@s9s_mb_2u_lib.s9s_mb_2u(sch_1):smb_sml1_pmbus_3v3aux_pch_scl_r0';
NODE_NAME     R2423 2
 '@S9S_MB_2U_LIB.S9S_MB_2U(SCH_1):PAGE227_I97@PURE_QUANTA.Q_RES(CHIPS)':
 'B': CDS_PINID='B';
NODE_NAME     J41 A7
 '@S9S_MB_2U_LIB.S9S_MB_2U(SCH_1):PAGE227_I173@PURE_QUANTA.SCONN168_ME1016810202011(CHIPS)':
 'SMCLK': CDS_PINID='SMCLK';
NET_NAME
'SMB_SML1_PMBUS_3V3AUX_PCH_SDA'
 '@S9S_MB_2U_LIB.S9S_MB_2U(SCH_1):SMB_SML1_PMBUS_3V3AUX_PCH_SDA':
 C_SIGNAL='@s9s_mb_2u_lib.s9s_mb_2u(sch_1):smb_sml1_pmbus_3v3aux_pch_sda';
NODE_NAME     R1387 1
 '@S9S_MB_2U_LIB.S9S_MB_2U(SCH_1):PAGE228_I7@PURE_QUANTA.Q_RES(CHIPS)':
 'A': CDS_PINID='A';
NODE_NAME     R2996 1
 '@S9S_MB_2U_LIB.S9S_MB_2U(SCH_1):PAGE228_I229@PURE_QUANTA.Q_RES(CHIPS)':
 'A': CDS_PINID='A';
NODE_NAME     R3061 1
 '@S9S_MB_2U_LIB.S9S_MB_2U(SCH_1):PAGE228_I234@PURE_QUANTA.Q_RES(CHIPS)':
 'A': CDS_PINID='A';
NODE_NAME     R4504 1
 '@S9S_MB_2U_LIB.S9S_MB_2U(SCH_1):PAGE175_I308@PURE_QUANTA.Q_RES(CHIPS)':
 'A': CDS_PINID='A';
NODE_NAME     R2424 1
 '@S9S_MB_2U_LIB.S9S_MB_2U(SCH_1):PAGE227_I96@PURE_QUANTA.Q_RES(CHIPS)':
 'A': CDS_PINID='A';
NET_NAME
'SMB_SML1_PMBUS_3V3AUX_PCH_SDA_1'
 '@S9S_MB_2U_LIB.S9S_MB_2U(SCH_1):SMB_SML1_PMBUS_3V3AUX_PCH_SDA_R1':
 C_SIGNAL='@s9s_mb_2u_lib.s9s_mb_2u(sch_1):smb_sml1_pmbus_3v3aux_pch_sda_r1';
NODE_NAME     U4 AW4
 '@S9S_MB_2U_LIB.S9S_MB_2U(SCH_1):PAGE175_I93@PURE_QUANTA.EMMITSBURG_REV0P9(CHIPS)':
 'GPPC_C_7_ME_SML1DATA': CDS_PINID='GPPC_C_7_ME_SML1DATA';
NODE_NAME     JP9 3
 '@S9S_MB_2U_LIB.S9S_MB_2U(SCH_1):PAGE175_I263@PURE_QUANTA.CONN3_210HP1030BR1(CHIPS)':
 '3': CDS_PINID='\3\';
NODE_NAME     R4504 2
 '@S9S_MB_2U_LIB.S9S_MB_2U(SCH_1):PAGE175_I308@PURE_QUANTA.Q_RES(CHIPS)':
 'B': CDS_PINID='B';
NET_NAME
'SMB_SML1_PMBUS_3V3AUX_PCH_SDA_R'
 '@S9S_MB_2U_LIB.S9S_MB_2U(SCH_1):SMB_SML1_PMBUS_3V3AUX_PCH_SDA_R0':
 C_SIGNAL='@s9s_mb_2u_lib.s9s_mb_2u(sch_1):smb_sml1_pmbus_3v3aux_pch_sda_r0';
NODE_NAME     R2424 2
 '@S9S_MB_2U_LIB.S9S_MB_2U(SCH_1):PAGE227_I96@PURE_QUANTA.Q_RES(CHIPS)':
 'B': CDS_PINID='B';
NODE_NAME     J41 A8
 '@S9S_MB_2U_LIB.S9S_MB_2U(SCH_1):PAGE227_I173@PURE_QUANTA.SCONN168_ME1016810202011(CHIPS)':
 'SMDAT': CDS_PINID='SMDAT';
NET_NAME
'SMB_SML1_PMBUS_HSC_L_SCL'
 '@S9S_MB_2U_LIB.S9S_MB_2U(SCH_1):SMB_SML1_PMBUS_HSC_L_SCL':
 C_SIGNAL='@s9s_mb_2u_lib.s9s_mb_2u(sch_1):smb_sml1_pmbus_hsc_l_scl';
NODE_NAME     PU289 11
 '@S9S_MB_2U_LIB.S9S_MB_2U(SCH_1):PAGE303_I56@PURE_QUANTA.MP5990GMA1111Z(CHIPS)':
 'SCL': CDS_PINID='SCL';
NODE_NAME     R3909 2
 '@S9S_MB_2U_LIB.S9S_MB_2U(SCH_1):PAGE303_I38@PURE_QUANTA.Q_RES(CHIPS)':
 'B': CDS_PINID='B';
NET_NAME
'SMB_SML1_PMBUS_HSC_MODULE_SCL'
 '@S9S_MB_2U_LIB.S9S_MB_2U(SCH_1):SMB_SML1_PMBUS_HSC_MODULE_SCL':
 C_SIGNAL='@s9s_mb_2u_lib.s9s_mb_2u(sch_1):smb_sml1_pmbus_hsc_module_scl';
NODE_NAME     R4695 2
 '@S9S_MB_2U_LIB.S9S_MB_2U(SCH_1):PAGE327_I26@PURE_QUANTA.Q_RES(CHIPS)':
 'B': CDS_PINID='B';
NODE_NAME     PJ42 18
 '@S9S_MB_2U_LIB.S9S_MB_2U(SCH_1):PAGE327_I34@PURE_QUANTA.SCONN21_9193031121LF(CHIPS)':
 '18': CDS_PINID='\18\';
NODE_NAME     JP10 1
 '@S9S_MB_2U_LIB.S9S_MB_2U(SCH_1):PAGE327_I51@PURE_QUANTA.CONN3_210HP1030BR1(CHIPS)':
 '1': CDS_PINID='\1\';
NET_NAME
'SMB_SML1_PMBUS_HSC_MODULE_SDA'
 '@S9S_MB_2U_LIB.S9S_MB_2U(SCH_1):SMB_SML1_PMBUS_HSC_MODULE_SDA':
 C_SIGNAL='@s9s_mb_2u_lib.s9s_mb_2u(sch_1):smb_sml1_pmbus_hsc_module_sda';
NODE_NAME     R4696 2
 '@S9S_MB_2U_LIB.S9S_MB_2U(SCH_1):PAGE327_I25@PURE_QUANTA.Q_RES(CHIPS)':
 'B': CDS_PINID='B';
NODE_NAME     PJ42 19
 '@S9S_MB_2U_LIB.S9S_MB_2U(SCH_1):PAGE327_I34@PURE_QUANTA.SCONN21_9193031121LF(CHIPS)':
 '19': CDS_PINID='\19\';
NODE_NAME     JP10 2
 '@S9S_MB_2U_LIB.S9S_MB_2U(SCH_1):PAGE327_I51@PURE_QUANTA.CONN3_210HP1030BR1(CHIPS)':
 '2': CDS_PINID='\2\';
NET_NAME
'SMB_SML1_PMBUS_HSC_R_SDA'
 '@S9S_MB_2U_LIB.S9S_MB_2U(SCH_1):SMB_SML1_PMBUS_HSC_R_SDA':
 C_SIGNAL='@s9s_mb_2u_lib.s9s_mb_2u(sch_1):smb_sml1_pmbus_hsc_r_sda';
NODE_NAME     PU289 12
 '@S9S_MB_2U_LIB.S9S_MB_2U(SCH_1):PAGE303_I56@PURE_QUANTA.MP5990GMA1111Z(CHIPS)':
 'SDA': CDS_PINID='SDA';
NODE_NAME     R1714 2
 '@S9S_MB_2U_LIB.S9S_MB_2U(SCH_1):PAGE303_I37@PURE_QUANTA.Q_RES(CHIPS)':
 'B': CDS_PINID='B';
NET_NAME
'SMB_SML1_PMBUS_HSC_SCL'
 '@S9S_MB_2U_LIB.S9S_MB_2U(SCH_1):SMB_SML1_PMBUS_HSC_SCL':
 C_SIGNAL='@s9s_mb_2u_lib.s9s_mb_2u(sch_1):smb_sml1_pmbus_hsc_scl';
NODE_NAME     R4530 2
 '@S9S_MB_2U_LIB.S9S_MB_2U(SCH_1):PAGE228_I293@PURE_QUANTA.Q_RES(CHIPS)':
 'B': CDS_PINID='B';
NODE_NAME     R3909 1
 '@S9S_MB_2U_LIB.S9S_MB_2U(SCH_1):PAGE303_I38@PURE_QUANTA.Q_RES(CHIPS)':
 'A': CDS_PINID='A';
NODE_NAME     R4695 1
 '@S9S_MB_2U_LIB.S9S_MB_2U(SCH_1):PAGE327_I26@PURE_QUANTA.Q_RES(CHIPS)':
 'A': CDS_PINID='A';
NET_NAME
'SMB_SML1_PMBUS_HSC_SCL_R3'
 '@S9S_MB_2U_LIB.S9S_MB_2U(SCH_1):SMB_SML1_PMBUS_HSC_SCL_R3':
 C_SIGNAL='@s9s_mb_2u_lib.s9s_mb_2u(sch_1):smb_sml1_pmbus_hsc_scl_r3';
NODE_NAME     R2995 2
 '@S9S_MB_2U_LIB.S9S_MB_2U(SCH_1):PAGE228_I228@PURE_QUANTA.Q_RES(CHIPS)':
 'B': CDS_PINID='B';
NODE_NAME     R4530 1
 '@S9S_MB_2U_LIB.S9S_MB_2U(SCH_1):PAGE228_I293@PURE_QUANTA.Q_RES(CHIPS)':
 'A': CDS_PINID='A';
NET_NAME
'SMB_SML1_PMBUS_HSC_SDA'
 '@S9S_MB_2U_LIB.S9S_MB_2U(SCH_1):SMB_SML1_PMBUS_HSC_SDA':
 C_SIGNAL='@s9s_mb_2u_lib.s9s_mb_2u(sch_1):smb_sml1_pmbus_hsc_sda';
NODE_NAME     R4531 2
 '@S9S_MB_2U_LIB.S9S_MB_2U(SCH_1):PAGE228_I296@PURE_QUANTA.Q_RES(CHIPS)':
 'B': CDS_PINID='B';
NODE_NAME     R4696 1
 '@S9S_MB_2U_LIB.S9S_MB_2U(SCH_1):PAGE327_I25@PURE_QUANTA.Q_RES(CHIPS)':
 'A': CDS_PINID='A';
NODE_NAME     R1714 1
 '@S9S_MB_2U_LIB.S9S_MB_2U(SCH_1):PAGE303_I37@PURE_QUANTA.Q_RES(CHIPS)':
 'A': CDS_PINID='A';
NET_NAME
'SMB_SML1_PMBUS_HSC_SDA_R3'
 '@S9S_MB_2U_LIB.S9S_MB_2U(SCH_1):SMB_SML1_PMBUS_HSC_SDA_R3':
 C_SIGNAL='@s9s_mb_2u_lib.s9s_mb_2u(sch_1):smb_sml1_pmbus_hsc_sda_r3';
NODE_NAME     R2996 2
 '@S9S_MB_2U_LIB.S9S_MB_2U(SCH_1):PAGE228_I229@PURE_QUANTA.Q_RES(CHIPS)':
 'B': CDS_PINID='B';
NODE_NAME     R4531 1
 '@S9S_MB_2U_LIB.S9S_MB_2U(SCH_1):PAGE228_I296@PURE_QUANTA.Q_RES(CHIPS)':
 'A': CDS_PINID='A';
NET_NAME
'SMB_VR_3V3AUX_SCL'
 '@S9S_MB_2U_LIB.S9S_MB_2U(SCH_1):SMB_VR_3V3AUX_SCL':
 C_SIGNAL='@s9s_mb_2u_lib.s9s_mb_2u(sch_1):smb_vr_3v3aux_scl';
NODE_NAME     R1661 1
 '@S9S_MB_2U_LIB.S9S_MB_2U(SCH_1):PAGE228_I89@PURE_QUANTA.Q_RES(CHIPS)':
 'A': CDS_PINID='A';
NODE_NAME     R2449 1
 '@S9S_MB_2U_LIB.S9S_MB_2U(SCH_1):PAGE228_I206@PURE_QUANTA.Q_RES(CHIPS)':
 'A': CDS_PINID='A';
NODE_NAME     R3723 2
 '@S9S_MB_2U_LIB.S9S_MB_2U(SCH_1):PAGE221_I55@PURE_QUANTA.Q_RES(CHIPS)':
 'B': CDS_PINID='B';
NODE_NAME     R3713 2
 '@S9S_MB_2U_LIB.S9S_MB_2U(SCH_1):PAGE221_I137@PURE_QUANTA.Q_RES(CHIPS)':
 'B': CDS_PINID='B';
NET_NAME
'SMB_VR_3V3AUX_SCL_R'
 '@S9S_MB_2U_LIB.S9S_MB_2U(SCH_1):SMB_VR_3V3AUX_SCL_R':
 C_SIGNAL='@s9s_mb_2u_lib.s9s_mb_2u(sch_1):smb_vr_3v3aux_scl_r';
NODE_NAME     R1661 2
 '@S9S_MB_2U_LIB.S9S_MB_2U(SCH_1):PAGE228_I89@PURE_QUANTA.Q_RES(CHIPS)':
 'B': CDS_PINID='B';
NODE_NAME     R2455 1
 '@S9S_MB_2U_LIB.S9S_MB_2U(SCH_1):PAGE228_I217@PURE_QUANTA.Q_RES(CHIPS)':
 'A': CDS_PINID='A';
NODE_NAME     R2453 1
 '@S9S_MB_2U_LIB.S9S_MB_2U(SCH_1):PAGE228_I219@PURE_QUANTA.Q_RES(CHIPS)':
 'A': CDS_PINID='A';
NODE_NAME     R4595 1
 '@S9S_MB_2U_LIB.S9S_MB_2U(SCH_1):PAGE282_I39@PURE_QUANTA.Q_RES(CHIPS)':
 'A': CDS_PINID='A';
NODE_NAME     R4594 1
 '@S9S_MB_2U_LIB.S9S_MB_2U(SCH_1):PAGE278_I58@PURE_QUANTA.Q_RES(CHIPS)':
 'A': CDS_PINID='A';
NET_NAME
'SMB_VR_3V3AUX_SCL_R0'
 '@S9S_MB_2U_LIB.S9S_MB_2U(SCH_1):SMB_VR_3V3AUX_SCL_R0':
 C_SIGNAL='@s9s_mb_2u_lib.s9s_mb_2u(sch_1):smb_vr_3v3aux_scl_r0';
NODE_NAME     R2421 2
 '@S9S_MB_2U_LIB.S9S_MB_2U(SCH_1):PAGE227_I99@PURE_QUANTA.Q_RES(CHIPS)':
 'B': CDS_PINID='B';
NODE_NAME     J41 A5
 '@S9S_MB_2U_LIB.S9S_MB_2U(SCH_1):PAGE227_I173@PURE_QUANTA.SCONN168_ME1016810202011(CHIPS)':
 'GND_A5': CDS_PINID='GND_A5';
NET_NAME
'SMB_VR_3V3AUX_SCL_R1'
 '@S9S_MB_2U_LIB.S9S_MB_2U(SCH_1):SMB_VR_3V3AUX_SCL_R1':
 C_SIGNAL='@s9s_mb_2u_lib.s9s_mb_2u(sch_1):smb_vr_3v3aux_scl_r1';
NODE_NAME     R2449 2
 '@S9S_MB_2U_LIB.S9S_MB_2U(SCH_1):PAGE228_I206@PURE_QUANTA.Q_RES(CHIPS)':
 'B': CDS_PINID='B';
NODE_NAME     R1793 1
 '@S9S_MB_2U_LIB.S9S_MB_2U(SCH_1):PAGE239_I19@PURE_QUANTA.Q_RES(CHIPS)':
 'A': CDS_PINID='A';
NODE_NAME     R3672 1
 '@S9S_MB_2U_LIB.S9S_MB_2U(SCH_1):PAGE239_I111@PURE_QUANTA.Q_RES(CHIPS)':
 'A': CDS_PINID='A';
NET_NAME
'SMB_VR_3V3AUX_SCL_R2'
 '@S9S_MB_2U_LIB.S9S_MB_2U(SCH_1):SMB_VR_3V3AUX_SCL_R2':
 C_SIGNAL='@s9s_mb_2u_lib.s9s_mb_2u(sch_1):smb_vr_3v3aux_scl_r2';
NODE_NAME     R2453 2
 '@S9S_MB_2U_LIB.S9S_MB_2U(SCH_1):PAGE228_I219@PURE_QUANTA.Q_RES(CHIPS)':
 'B': CDS_PINID='B';
NODE_NAME     R2402 1
 '@S9S_MB_2U_LIB.S9S_MB_2U(SCH_1):PAGE264_I39@PURE_QUANTA.Q_RES(CHIPS)':
 'A': CDS_PINID='A';
NODE_NAME     R2390 1
 '@S9S_MB_2U_LIB.S9S_MB_2U(SCH_1):PAGE260_I53@PURE_QUANTA.Q_RES(CHIPS)':
 'A': CDS_PINID='A';
NET_NAME
'SMB_VR_3V3AUX_SCL_R3'
 '@S9S_MB_2U_LIB.S9S_MB_2U(SCH_1):SMB_VR_3V3AUX_SCL_R3':
 C_SIGNAL='@s9s_mb_2u_lib.s9s_mb_2u(sch_1):smb_vr_3v3aux_scl_r3';
NODE_NAME     R2455 2
 '@S9S_MB_2U_LIB.S9S_MB_2U(SCH_1):PAGE228_I217@PURE_QUANTA.Q_RES(CHIPS)':
 'B': CDS_PINID='B';
NODE_NAME     R2520 1
 '@S9S_MB_2U_LIB.S9S_MB_2U(SCH_1):PAGE270_I65@PURE_QUANTA.Q_RES(CHIPS)':
 'A': CDS_PINID='A';
NODE_NAME     R1713 1
 '@S9S_MB_2U_LIB.S9S_MB_2U(SCH_1):PAGE252_I40@PURE_QUANTA.Q_RES(CHIPS)':
 'A': CDS_PINID='A';
NODE_NAME     PJP1 1
 '@S9S_MB_2U_LIB.S9S_MB_2U(SCH_1):PAGE252_I32@PURE_QUANTA.CONN3_210HP1030BR1(CHIPS)':
 '1': CDS_PINID='\1\';
NODE_NAME     R2371 1
 '@S9S_MB_2U_LIB.S9S_MB_2U(SCH_1):PAGE252_I80@PURE_QUANTA.Q_RES(CHIPS)':
 'A': CDS_PINID='A';
NET_NAME
'SMB_VR_3V3AUX_SCL_R6'
 '@S9S_MB_2U_LIB.S9S_MB_2U(SCH_1):SMB_VR_3V3AUX_SCL_R6':
 C_SIGNAL='@s9s_mb_2u_lib.s9s_mb_2u(sch_1):smb_vr_3v3aux_scl_r6';
NODE_NAME     U39 5
 '@S9S_MB_2U_LIB.S9S_MB_2U(SCH_1):PAGE221_I103@PURE_QUANTA.TCA9548APWR(CHIPS)':
 'SC0': CDS_PINID='SC0';
NODE_NAME     R3713 1
 '@S9S_MB_2U_LIB.S9S_MB_2U(SCH_1):PAGE221_I137@PURE_QUANTA.Q_RES(CHIPS)':
 'A': CDS_PINID='A';
NET_NAME
'SMB_VR_3V3AUX_SDA'
 '@S9S_MB_2U_LIB.S9S_MB_2U(SCH_1):SMB_VR_3V3AUX_SDA':
 C_SIGNAL='@s9s_mb_2u_lib.s9s_mb_2u(sch_1):smb_vr_3v3aux_sda';
NODE_NAME     R1662 1
 '@S9S_MB_2U_LIB.S9S_MB_2U(SCH_1):PAGE228_I90@PURE_QUANTA.Q_RES(CHIPS)':
 'A': CDS_PINID='A';
NODE_NAME     R2450 1
 '@S9S_MB_2U_LIB.S9S_MB_2U(SCH_1):PAGE228_I207@PURE_QUANTA.Q_RES(CHIPS)':
 'A': CDS_PINID='A';
NODE_NAME     R3724 2
 '@S9S_MB_2U_LIB.S9S_MB_2U(SCH_1):PAGE221_I56@PURE_QUANTA.Q_RES(CHIPS)':
 'B': CDS_PINID='B';
NODE_NAME     R3714 2
 '@S9S_MB_2U_LIB.S9S_MB_2U(SCH_1):PAGE221_I138@PURE_QUANTA.Q_RES(CHIPS)':
 'B': CDS_PINID='B';
NET_NAME
'SMB_VR_3V3AUX_SDA_R'
 '@S9S_MB_2U_LIB.S9S_MB_2U(SCH_1):SMB_VR_3V3AUX_SDA_R':
 C_SIGNAL='@s9s_mb_2u_lib.s9s_mb_2u(sch_1):smb_vr_3v3aux_sda_r';
NODE_NAME     R1662 2
 '@S9S_MB_2U_LIB.S9S_MB_2U(SCH_1):PAGE228_I90@PURE_QUANTA.Q_RES(CHIPS)':
 'B': CDS_PINID='B';
NODE_NAME     R2456 1
 '@S9S_MB_2U_LIB.S9S_MB_2U(SCH_1):PAGE228_I216@PURE_QUANTA.Q_RES(CHIPS)':
 'A': CDS_PINID='A';
NODE_NAME     R2454 1
 '@S9S_MB_2U_LIB.S9S_MB_2U(SCH_1):PAGE228_I218@PURE_QUANTA.Q_RES(CHIPS)':
 'A': CDS_PINID='A';
NODE_NAME     R2563 1
 '@S9S_MB_2U_LIB.S9S_MB_2U(SCH_1):PAGE278_I57@PURE_QUANTA.Q_RES(CHIPS)':
 'A': CDS_PINID='A';
NODE_NAME     R2582 1
 '@S9S_MB_2U_LIB.S9S_MB_2U(SCH_1):PAGE282_I38@PURE_QUANTA.Q_RES(CHIPS)':
 'A': CDS_PINID='A';
NET_NAME
'SMB_VR_3V3AUX_SDA_R0'
 '@S9S_MB_2U_LIB.S9S_MB_2U(SCH_1):SMB_VR_3V3AUX_SDA_R0':
 C_SIGNAL='@s9s_mb_2u_lib.s9s_mb_2u(sch_1):smb_vr_3v3aux_sda_r0';
NODE_NAME     R2422 2
 '@S9S_MB_2U_LIB.S9S_MB_2U(SCH_1):PAGE227_I95@PURE_QUANTA.Q_RES(CHIPS)':
 'B': CDS_PINID='B';
NODE_NAME     J41 A6
 '@S9S_MB_2U_LIB.S9S_MB_2U(SCH_1):PAGE227_I173@PURE_QUANTA.SCONN168_ME1016810202011(CHIPS)':
 'GND_A6': CDS_PINID='GND_A6';
NET_NAME
'SMB_VR_3V3AUX_SDA_R1'
 '@S9S_MB_2U_LIB.S9S_MB_2U(SCH_1):SMB_VR_3V3AUX_SDA_R1':
 C_SIGNAL='@s9s_mb_2u_lib.s9s_mb_2u(sch_1):smb_vr_3v3aux_sda_r1';
NODE_NAME     R2450 2
 '@S9S_MB_2U_LIB.S9S_MB_2U(SCH_1):PAGE228_I207@PURE_QUANTA.Q_RES(CHIPS)':
 'B': CDS_PINID='B';
NODE_NAME     R1792 1
 '@S9S_MB_2U_LIB.S9S_MB_2U(SCH_1):PAGE239_I20@PURE_QUANTA.Q_RES(CHIPS)':
 'A': CDS_PINID='A';
NODE_NAME     R3671 1
 '@S9S_MB_2U_LIB.S9S_MB_2U(SCH_1):PAGE239_I110@PURE_QUANTA.Q_RES(CHIPS)':
 'A': CDS_PINID='A';
NET_NAME
'SMB_VR_3V3AUX_SDA_R2'
 '@S9S_MB_2U_LIB.S9S_MB_2U(SCH_1):SMB_VR_3V3AUX_SDA_R2':
 C_SIGNAL='@s9s_mb_2u_lib.s9s_mb_2u(sch_1):smb_vr_3v3aux_sda_r2';
NODE_NAME     R2454 2
 '@S9S_MB_2U_LIB.S9S_MB_2U(SCH_1):PAGE228_I218@PURE_QUANTA.Q_RES(CHIPS)':
 'B': CDS_PINID='B';
NODE_NAME     R2403 1
 '@S9S_MB_2U_LIB.S9S_MB_2U(SCH_1):PAGE264_I38@PURE_QUANTA.Q_RES(CHIPS)':
 'A': CDS_PINID='A';
NODE_NAME     R2391 1
 '@S9S_MB_2U_LIB.S9S_MB_2U(SCH_1):PAGE260_I51@PURE_QUANTA.Q_RES(CHIPS)':
 'A': CDS_PINID='A';
NET_NAME
'SMB_VR_3V3AUX_SDA_R3'
 '@S9S_MB_2U_LIB.S9S_MB_2U(SCH_1):SMB_VR_3V3AUX_SDA_R3':
 C_SIGNAL='@s9s_mb_2u_lib.s9s_mb_2u(sch_1):smb_vr_3v3aux_sda_r3';
NODE_NAME     R2456 2
 '@S9S_MB_2U_LIB.S9S_MB_2U(SCH_1):PAGE228_I216@PURE_QUANTA.Q_RES(CHIPS)':
 'B': CDS_PINID='B';
NODE_NAME     R2521 1
 '@S9S_MB_2U_LIB.S9S_MB_2U(SCH_1):PAGE270_I66@PURE_QUANTA.Q_RES(CHIPS)':
 'A': CDS_PINID='A';
NODE_NAME     PJP1 3
 '@S9S_MB_2U_LIB.S9S_MB_2U(SCH_1):PAGE252_I32@PURE_QUANTA.CONN3_210HP1030BR1(CHIPS)':
 '3': CDS_PINID='\3\';
NODE_NAME     R1712 1
 '@S9S_MB_2U_LIB.S9S_MB_2U(SCH_1):PAGE252_I42@PURE_QUANTA.Q_RES(CHIPS)':
 'A': CDS_PINID='A';
NODE_NAME     R2372 1
 '@S9S_MB_2U_LIB.S9S_MB_2U(SCH_1):PAGE252_I78@PURE_QUANTA.Q_RES(CHIPS)':
 'A': CDS_PINID='A';
NET_NAME
'SMB_VR_3V3AUX_SDA_R6'
 '@S9S_MB_2U_LIB.S9S_MB_2U(SCH_1):SMB_VR_3V3AUX_SDA_R6':
 C_SIGNAL='@s9s_mb_2u_lib.s9s_mb_2u(sch_1):smb_vr_3v3aux_sda_r6';
NODE_NAME     U39 4
 '@S9S_MB_2U_LIB.S9S_MB_2U(SCH_1):PAGE221_I103@PURE_QUANTA.TCA9548APWR(CHIPS)':
 'SD0': CDS_PINID='SD0';
NODE_NAME     R3714 1
 '@S9S_MB_2U_LIB.S9S_MB_2U(SCH_1):PAGE221_I138@PURE_QUANTA.Q_RES(CHIPS)':
 'A': CDS_PINID='A';
NET_NAME
'SMB_VR_SENSOR_3V3AUX_SCL'
 '@S9S_MB_2U_LIB.S9S_MB_2U(SCH_1):SMB_VR_SENSOR_3V3AUX_SCL':
 C_SIGNAL='@s9s_mb_2u_lib.s9s_mb_2u(sch_1):smb_vr_sensor_3v3aux_scl';
NODE_NAME     R2421 1
 '@S9S_MB_2U_LIB.S9S_MB_2U(SCH_1):PAGE227_I99@PURE_QUANTA.Q_RES(CHIPS)':
 'A': CDS_PINID='A';
NODE_NAME     R4269 2
 '@S9S_MB_2U_LIB.S9S_MB_2U(SCH_1):PAGE221_I102@PURE_QUANTA.Q_RES(CHIPS)':
 'B': CDS_PINID='B';
NODE_NAME     R3711 1
 '@S9S_MB_2U_LIB.S9S_MB_2U(SCH_1):PAGE221_I116@PURE_QUANTA.Q_RES(CHIPS)':
 'A': CDS_PINID='A';
NET_NAME
'SMB_VR_SENSOR_3V3AUX_SCL_R'
 '@S9S_MB_2U_LIB.S9S_MB_2U(SCH_1):SMB_VR_SENSOR_3V3AUX_SCL_R':
 C_SIGNAL='@s9s_mb_2u_lib.s9s_mb_2u(sch_1):smb_vr_sensor_3v3aux_scl_r';
NODE_NAME     U39 22
 '@S9S_MB_2U_LIB.S9S_MB_2U(SCH_1):PAGE221_I103@PURE_QUANTA.TCA9548APWR(CHIPS)':
 'SCL': CDS_PINID='SCL';
NODE_NAME     R3711 2
 '@S9S_MB_2U_LIB.S9S_MB_2U(SCH_1):PAGE221_I116@PURE_QUANTA.Q_RES(CHIPS)':
 'B': CDS_PINID='B';
NET_NAME
'SMB_VR_SENSOR_3V3AUX_SDA'
 '@S9S_MB_2U_LIB.S9S_MB_2U(SCH_1):SMB_VR_SENSOR_3V3AUX_SDA':
 C_SIGNAL='@s9s_mb_2u_lib.s9s_mb_2u(sch_1):smb_vr_sensor_3v3aux_sda';
NODE_NAME     R4270 2
 '@S9S_MB_2U_LIB.S9S_MB_2U(SCH_1):PAGE221_I99@PURE_QUANTA.Q_RES(CHIPS)':
 'B': CDS_PINID='B';
NODE_NAME     R3712 1
 '@S9S_MB_2U_LIB.S9S_MB_2U(SCH_1):PAGE221_I115@PURE_QUANTA.Q_RES(CHIPS)':
 'A': CDS_PINID='A';
NODE_NAME     R2422 1
 '@S9S_MB_2U_LIB.S9S_MB_2U(SCH_1):PAGE227_I95@PURE_QUANTA.Q_RES(CHIPS)':
 'A': CDS_PINID='A';
NET_NAME
'SMB_VR_SENSOR_3V3AUX_SDA_R'
 '@S9S_MB_2U_LIB.S9S_MB_2U(SCH_1):SMB_VR_SENSOR_3V3AUX_SDA_R':
 C_SIGNAL='@s9s_mb_2u_lib.s9s_mb_2u(sch_1):smb_vr_sensor_3v3aux_sda_r';
NODE_NAME     U39 23
 '@S9S_MB_2U_LIB.S9S_MB_2U(SCH_1):PAGE221_I103@PURE_QUANTA.TCA9548APWR(CHIPS)':
 'SDA': CDS_PINID='SDA';
NODE_NAME     R3712 2
 '@S9S_MB_2U_LIB.S9S_MB_2U(SCH_1):PAGE221_I115@PURE_QUANTA.Q_RES(CHIPS)':
 'B': CDS_PINID='B';
NET_NAME
'SPI_PCH_CLK'
 '@S9S_MB_2U_LIB.S9S_MB_2U(SCH_1):SPI_PCH_CLK':
 C_SIGNAL='@s9s_mb_2u_lib.s9s_mb_2u(sch_1):spi_pch_clk';
NODE_NAME     U4 BB15
 '@S9S_MB_2U_LIB.S9S_MB_2U(SCH_1):PAGE177_I27@PURE_QUANTA.EMMITSBURG_REV0P9(CHIPS)':
 'SPI0_CLK': CDS_PINID='SPI0_CLK';
NODE_NAME     R499 1
 '@S9S_MB_2U_LIB.S9S_MB_2U(SCH_1):PAGE177_I106@PURE_QUANTA.Q_RES(CHIPS)':
 'A': CDS_PINID='A';
NET_NAME
'SPI_PCH_CS0_R_N'
 '@S9S_MB_2U_LIB.S9S_MB_2U(SCH_1):SPI_PCH_CS0_R_N':
 C_SIGNAL='@s9s_mb_2u_lib.s9s_mb_2u(sch_1):spi_pch_cs0_r_n';
NODE_NAME     U4 AW13
 '@S9S_MB_2U_LIB.S9S_MB_2U(SCH_1):PAGE177_I27@PURE_QUANTA.EMMITSBURG_REV0P9(CHIPS)':
 'SPI0_FLASH_0_CS_N': CDS_PINID='SPI0_FLASH_0_CS_N';
NODE_NAME     R501 1
 '@S9S_MB_2U_LIB.S9S_MB_2U(SCH_1):PAGE177_I100@PURE_QUANTA.Q_RES(CHIPS)':
 'A': CDS_PINID='A';
NET_NAME
'SPI_PCH_IO0'
 '@S9S_MB_2U_LIB.S9S_MB_2U(SCH_1):SPI_PCH_IO0':
 C_SIGNAL='@s9s_mb_2u_lib.s9s_mb_2u(sch_1):spi_pch_io0';
NODE_NAME     U4 BA13
 '@S9S_MB_2U_LIB.S9S_MB_2U(SCH_1):PAGE177_I27@PURE_QUANTA.EMMITSBURG_REV0P9(CHIPS)':
 'SPI0_MOSI_IO_0': CDS_PINID='SPI0_MOSI_IO_0';
NODE_NAME     R915 1
 '@S9S_MB_2U_LIB.S9S_MB_2U(SCH_1):PAGE177_I118@PURE_QUANTA.Q_RES(CHIPS)':
 'A': CDS_PINID='A';
NET_NAME
'SPI_PCH_IO1'
 '@S9S_MB_2U_LIB.S9S_MB_2U(SCH_1):SPI_PCH_IO1':
 C_SIGNAL='@s9s_mb_2u_lib.s9s_mb_2u(sch_1):spi_pch_io1';
NODE_NAME     U4 AW16
 '@S9S_MB_2U_LIB.S9S_MB_2U(SCH_1):PAGE177_I27@PURE_QUANTA.EMMITSBURG_REV0P9(CHIPS)':
 'SPI0_MISO_IO_1': CDS_PINID='SPI0_MISO_IO_1';
NODE_NAME     R916 1
 '@S9S_MB_2U_LIB.S9S_MB_2U(SCH_1):PAGE177_I119@PURE_QUANTA.Q_RES(CHIPS)':
 'A': CDS_PINID='A';
NET_NAME
'SPI_PCH_IO2'
 '@S9S_MB_2U_LIB.S9S_MB_2U(SCH_1):SPI_PCH_IO2':
 C_SIGNAL='@s9s_mb_2u_lib.s9s_mb_2u(sch_1):spi_pch_io2';
NODE_NAME     U4 AV15
 '@S9S_MB_2U_LIB.S9S_MB_2U(SCH_1):PAGE177_I27@PURE_QUANTA.EMMITSBURG_REV0P9(CHIPS)':
 'SPI0_IO_2': CDS_PINID='SPI0_IO_2';
NODE_NAME     R918 1
 '@S9S_MB_2U_LIB.S9S_MB_2U(SCH_1):PAGE177_I120@PURE_QUANTA.Q_RES(CHIPS)':
 'A': CDS_PINID='A';
NET_NAME
'SPI_PCH_IO3'
 '@S9S_MB_2U_LIB.S9S_MB_2U(SCH_1):SPI_PCH_IO3':
 C_SIGNAL='@s9s_mb_2u_lib.s9s_mb_2u(sch_1):spi_pch_io3';
NODE_NAME     U4 BA16
 '@S9S_MB_2U_LIB.S9S_MB_2U(SCH_1):PAGE177_I27@PURE_QUANTA.EMMITSBURG_REV0P9(CHIPS)':
 'SPI0_IO_3': CDS_PINID='SPI0_IO_3';
NODE_NAME     R917 1
 '@S9S_MB_2U_LIB.S9S_MB_2U(SCH_1):PAGE177_I121@PURE_QUANTA.Q_RES(CHIPS)':
 'A': CDS_PINID='A';
NET_NAME
'SPI_PCH_TPM_CS_N'
 '@S9S_MB_2U_LIB.S9S_MB_2U(SCH_1):SPI_PCH_TPM_CS_N':
 C_SIGNAL='@s9s_mb_2u_lib.s9s_mb_2u(sch_1):spi_pch_tpm_cs_n';
NODE_NAME     U4 BB11
 '@S9S_MB_2U_LIB.S9S_MB_2U(SCH_1):PAGE177_I27@PURE_QUANTA.EMMITSBURG_REV0P9(CHIPS)':
 'SPI0_TPM_CS_N': CDS_PINID='SPI0_TPM_CS_N';
NODE_NAME     R1395 1
 '@S9S_MB_2U_LIB.S9S_MB_2U(SCH_1):PAGE177_I102@PURE_QUANTA.Q_RES(CHIPS)':
 'A': CDS_PINID='A';
NET_NAME
'SPI_SYS_CLK'
 '@S9S_MB_2U_LIB.S9S_MB_2U(SCH_1):SPI_SYS_CLK':
 C_SIGNAL='@s9s_mb_2u_lib.s9s_mb_2u(sch_1):spi_sys_clk';
NODE_NAME     R499 2
 '@S9S_MB_2U_LIB.S9S_MB_2U(SCH_1):PAGE177_I106@PURE_QUANTA.Q_RES(CHIPS)':
 'B': CDS_PINID='B';
NODE_NAME     J41 B11
 '@S9S_MB_2U_LIB.S9S_MB_2U(SCH_1):PAGE227_I173@PURE_QUANTA.SCONN168_ME1016810202011(CHIPS)':
 '+3.3V_EDGE': CDS_PINID='\+3.3v_edge\';
NET_NAME
'SPI_SYS_CS0_N'
 '@S9S_MB_2U_LIB.S9S_MB_2U(SCH_1):SPI_SYS_CS0_N':
 C_SIGNAL='@s9s_mb_2u_lib.s9s_mb_2u(sch_1):spi_sys_cs0_n';
NODE_NAME     R501 2
 '@S9S_MB_2U_LIB.S9S_MB_2U(SCH_1):PAGE177_I100@PURE_QUANTA.Q_RES(CHIPS)':
 'B': CDS_PINID='B';
NODE_NAME     J41 B12
 '@S9S_MB_2U_LIB.S9S_MB_2U(SCH_1):PAGE227_I173@PURE_QUANTA.SCONN168_ME1016810202011(CHIPS)':
 'AUX_PWR_EN': CDS_PINID='AUX_PWR_EN';
NET_NAME
'SPI_SYS_HOLD_IO3'
 '@S9S_MB_2U_LIB.S9S_MB_2U(SCH_1):SPI_SYS_HOLD_IO3':
 C_SIGNAL='@s9s_mb_2u_lib.s9s_mb_2u(sch_1):spi_sys_hold_io3';
NODE_NAME     R917 2
 '@S9S_MB_2U_LIB.S9S_MB_2U(SCH_1):PAGE177_I121@PURE_QUANTA.Q_RES(CHIPS)':
 'B': CDS_PINID='B';
NODE_NAME     J41 B16
 '@S9S_MB_2U_LIB.S9S_MB_2U(SCH_1):PAGE227_I173@PURE_QUANTA.SCONN168_ME1016810202011(CHIPS)':
 'GND_B16': CDS_PINID='GND_B16';
NET_NAME
'SPI_SYS_MISO'
 '@S9S_MB_2U_LIB.S9S_MB_2U(SCH_1):SPI_SYS_MISO':
 C_SIGNAL='@s9s_mb_2u_lib.s9s_mb_2u(sch_1):spi_sys_miso';
NODE_NAME     R916 2
 '@S9S_MB_2U_LIB.S9S_MB_2U(SCH_1):PAGE177_I119@PURE_QUANTA.Q_RES(CHIPS)':
 'B': CDS_PINID='B';
NODE_NAME     J41 B14
 '@S9S_MB_2U_LIB.S9S_MB_2U(SCH_1):PAGE227_I173@PURE_QUANTA.SCONN168_ME1016810202011(CHIPS)':
 'REFCLKN0': CDS_PINID='REFCLKN0';
NET_NAME
'SPI_SYS_MOSI'
 '@S9S_MB_2U_LIB.S9S_MB_2U(SCH_1):SPI_SYS_MOSI':
 C_SIGNAL='@s9s_mb_2u_lib.s9s_mb_2u(sch_1):spi_sys_mosi';
NODE_NAME     R915 2
 '@S9S_MB_2U_LIB.S9S_MB_2U(SCH_1):PAGE177_I118@PURE_QUANTA.Q_RES(CHIPS)':
 'B': CDS_PINID='B';
NODE_NAME     J41 B13
 '@S9S_MB_2U_LIB.S9S_MB_2U(SCH_1):PAGE227_I173@PURE_QUANTA.SCONN168_ME1016810202011(CHIPS)':
 'GND_B13': CDS_PINID='GND_B13';
NET_NAME
'SPI_SYS_WP_IO2'
 '@S9S_MB_2U_LIB.S9S_MB_2U(SCH_1):SPI_SYS_WP_IO2':
 C_SIGNAL='@s9s_mb_2u_lib.s9s_mb_2u(sch_1):spi_sys_wp_io2';
NODE_NAME     R918 2
 '@S9S_MB_2U_LIB.S9S_MB_2U(SCH_1):PAGE177_I120@PURE_QUANTA.Q_RES(CHIPS)':
 'B': CDS_PINID='B';
NODE_NAME     J41 B15
 '@S9S_MB_2U_LIB.S9S_MB_2U(SCH_1):PAGE227_I173@PURE_QUANTA.SCONN168_ME1016810202011(CHIPS)':
 'REFCLKP0': CDS_PINID='REFCLKP0';
NET_NAME
'SPI_TPM_CS_N'
 '@S9S_MB_2U_LIB.S9S_MB_2U(SCH_1):SPI_TPM_CS_N':
 C_SIGNAL='@s9s_mb_2u_lib.s9s_mb_2u(sch_1):spi_tpm_cs_n';
NODE_NAME     R1395 2
 '@S9S_MB_2U_LIB.S9S_MB_2U(SCH_1):PAGE177_I102@PURE_QUANTA.Q_RES(CHIPS)':
 'B': CDS_PINID='B';
NODE_NAME     J41 OB12
 '@S9S_MB_2U_LIB.S9S_MB_2U(SCH_1):PAGE227_I173@PURE_QUANTA.SCONN168_ME1016810202011(CHIPS)':
 'REFCLKP2': CDS_PINID='REFCLKP2';
NET_NAME
'SVID_ALERT0_CPU0_N'
 '@S9S_MB_2U_LIB.S9S_MB_2U(SCH_1):SVID_ALERT0_CPU0_N':
 C_SIGNAL='@s9s_mb_2u_lib.s9s_mb_2u(sch_1):svid_alert0_cpu0_n';
NODE_NAME     U2 BK26
 '@S9S_MB_2U_LIB.S9S_MB_2U(SCH_1):PAGE14_I1@PURE_QUANTA.SOCKET4677_AZIF0045P001C01CS(CHIPS)':
 'SVIDALERT0_N': CDS_PINID='SVIDALERT0_N';
NODE_NAME     R14 1
 '@S9S_MB_2U_LIB.S9S_MB_2U(SCH_1):PAGE14_I61@PURE_QUANTA.Q_RES(CHIPS)':
 'A': CDS_PINID='A';
NET_NAME
'SVID_ALERT0_CPU0_R_N'
 '@S9S_MB_2U_LIB.S9S_MB_2U(SCH_1):SVID_ALERT0_CPU0_R_N':
 C_SIGNAL='@s9s_mb_2u_lib.s9s_mb_2u(sch_1):svid_alert0_cpu0_r_n';
NODE_NAME     R14 2
 '@S9S_MB_2U_LIB.S9S_MB_2U(SCH_1):PAGE14_I61@PURE_QUANTA.Q_RES(CHIPS)':
 'B': CDS_PINID='B';
NODE_NAME     R548 1
 '@S9S_MB_2U_LIB.S9S_MB_2U(SCH_1):PAGE14_I94@PURE_QUANTA.Q_RES(CHIPS)':
 'A': CDS_PINID='A';
NODE_NAME     R2389 1
 '@S9S_MB_2U_LIB.S9S_MB_2U(SCH_1):PAGE260_I52@PURE_QUANTA.Q_RES(CHIPS)':
 'A': CDS_PINID='A';
NODE_NAME     R2370 1
 '@S9S_MB_2U_LIB.S9S_MB_2U(SCH_1):PAGE252_I41@PURE_QUANTA.Q_RES(CHIPS)':
 'A': CDS_PINID='A';
NODE_NAME     R2382 1
 '@S9S_MB_2U_LIB.S9S_MB_2U(SCH_1):PAGE252_I123@PURE_QUANTA.Q_RES(CHIPS)':
 'A': CDS_PINID='A';
NET_NAME
'SVID_ALERT0_CPU1_N'
 '@S9S_MB_2U_LIB.S9S_MB_2U(SCH_1):SVID_ALERT0_CPU1_N':
 C_SIGNAL='@s9s_mb_2u_lib.s9s_mb_2u(sch_1):svid_alert0_cpu1_n';
NODE_NAME     U1 BK26
 '@S9S_MB_2U_LIB.S9S_MB_2U(SCH_1):PAGE45_I29@PURE_QUANTA.SOCKET4677_AZIF0045P001C01CS(CHIPS)':
 'SVIDALERT0_N': CDS_PINID='SVIDALERT0_N';
NODE_NAME     R57 1
 '@S9S_MB_2U_LIB.S9S_MB_2U(SCH_1):PAGE45_I56@PURE_QUANTA.Q_RES(CHIPS)':
 'A': CDS_PINID='A';
NET_NAME
'SVID_ALERT0_CPU1_R_N'
 '@S9S_MB_2U_LIB.S9S_MB_2U(SCH_1):SVID_ALERT0_CPU1_R_N':
 C_SIGNAL='@s9s_mb_2u_lib.s9s_mb_2u(sch_1):svid_alert0_cpu1_r_n';
NODE_NAME     R57 2
 '@S9S_MB_2U_LIB.S9S_MB_2U(SCH_1):PAGE45_I56@PURE_QUANTA.Q_RES(CHIPS)':
 'B': CDS_PINID='B';
NODE_NAME     R558 1
 '@S9S_MB_2U_LIB.S9S_MB_2U(SCH_1):PAGE45_I73@PURE_QUANTA.Q_RES(CHIPS)':
 'A': CDS_PINID='A';
NODE_NAME     R2561 1
 '@S9S_MB_2U_LIB.S9S_MB_2U(SCH_1):PAGE278_I59@PURE_QUANTA.Q_RES(CHIPS)':
 'A': CDS_PINID='A';
NODE_NAME     R2555 1
 '@S9S_MB_2U_LIB.S9S_MB_2U(SCH_1):PAGE270_I101@PURE_QUANTA.Q_RES(CHIPS)':
 'A': CDS_PINID='A';
NODE_NAME     R312 1
 '@S9S_MB_2U_LIB.S9S_MB_2U(SCH_1):PAGE270_I57@PURE_QUANTA.Q_RES(CHIPS)':
 'A': CDS_PINID='A';
NET_NAME
'SVID_ALERT1_CPU0_N'
 '@S9S_MB_2U_LIB.S9S_MB_2U(SCH_1):SVID_ALERT1_CPU0_N':
 C_SIGNAL='@s9s_mb_2u_lib.s9s_mb_2u(sch_1):svid_alert1_cpu0_n';
NODE_NAME     U2 BJ25
 '@S9S_MB_2U_LIB.S9S_MB_2U(SCH_1):PAGE14_I1@PURE_QUANTA.SOCKET4677_AZIF0045P001C01CS(CHIPS)':
 'SVIDALERT1_N': CDS_PINID='SVIDALERT1_N';
NODE_NAME     R17 1
 '@S9S_MB_2U_LIB.S9S_MB_2U(SCH_1):PAGE14_I64@PURE_QUANTA.Q_RES(CHIPS)':
 'A': CDS_PINID='A';
NET_NAME
'SVID_ALERT1_CPU0_R_N'
 '@S9S_MB_2U_LIB.S9S_MB_2U(SCH_1):SVID_ALERT1_CPU0_R_N':
 C_SIGNAL='@s9s_mb_2u_lib.s9s_mb_2u(sch_1):svid_alert1_cpu0_r_n';
NODE_NAME     R17 2
 '@S9S_MB_2U_LIB.S9S_MB_2U(SCH_1):PAGE14_I64@PURE_QUANTA.Q_RES(CHIPS)':
 'B': CDS_PINID='B';
NODE_NAME     R556 1
 '@S9S_MB_2U_LIB.S9S_MB_2U(SCH_1):PAGE14_I100@PURE_QUANTA.Q_RES(CHIPS)':
 'A': CDS_PINID='A';
NODE_NAME     R2401 1
 '@S9S_MB_2U_LIB.S9S_MB_2U(SCH_1):PAGE264_I40@PURE_QUANTA.Q_RES(CHIPS)':
 'A': CDS_PINID='A';
NET_NAME
'SVID_ALERT1_CPU1_N'
 '@S9S_MB_2U_LIB.S9S_MB_2U(SCH_1):SVID_ALERT1_CPU1_N':
 C_SIGNAL='@s9s_mb_2u_lib.s9s_mb_2u(sch_1):svid_alert1_cpu1_n';
NODE_NAME     U1 BJ25
 '@S9S_MB_2U_LIB.S9S_MB_2U(SCH_1):PAGE45_I29@PURE_QUANTA.SOCKET4677_AZIF0045P001C01CS(CHIPS)':
 'SVIDALERT1_N': CDS_PINID='SVIDALERT1_N';
NODE_NAME     R60 1
 '@S9S_MB_2U_LIB.S9S_MB_2U(SCH_1):PAGE45_I53@PURE_QUANTA.Q_RES(CHIPS)':
 'A': CDS_PINID='A';
NET_NAME
'SVID_ALERT1_CPU1_R_N'
 '@S9S_MB_2U_LIB.S9S_MB_2U(SCH_1):SVID_ALERT1_CPU1_R_N':
 C_SIGNAL='@s9s_mb_2u_lib.s9s_mb_2u(sch_1):svid_alert1_cpu1_r_n';
NODE_NAME     R60 2
 '@S9S_MB_2U_LIB.S9S_MB_2U(SCH_1):PAGE45_I53@PURE_QUANTA.Q_RES(CHIPS)':
 'B': CDS_PINID='B';
NODE_NAME     R560 1
 '@S9S_MB_2U_LIB.S9S_MB_2U(SCH_1):PAGE45_I70@PURE_QUANTA.Q_RES(CHIPS)':
 'A': CDS_PINID='A';
NODE_NAME     R2580 1
 '@S9S_MB_2U_LIB.S9S_MB_2U(SCH_1):PAGE282_I40@PURE_QUANTA.Q_RES(CHIPS)':
 'A': CDS_PINID='A';
NET_NAME
'SVID_ALERT_PVCCD_HV_CPU0_R'
 '@S9S_MB_2U_LIB.S9S_MB_2U(SCH_1):SVID_ALERT_PVCCD_HV_CPU0_R':
 C_SIGNAL='@s9s_mb_2u_lib.s9s_mb_2u(sch_1):svid_alert_pvccd_hv_cpu0_r';
NODE_NAME     PU35 19
 '@S9S_MB_2U_LIB.S9S_MB_2U(SCH_1):PAGE264_I53@PURE_QUANTA.ISL69260IRAZT(CHIPS)':
 'NSVALERT#': CDS_PINID='\nsvalert#\';
NODE_NAME     R2401 2
 '@S9S_MB_2U_LIB.S9S_MB_2U(SCH_1):PAGE264_I40@PURE_QUANTA.Q_RES(CHIPS)':
 'B': CDS_PINID='B';
NET_NAME
'SVID_ALERT_PVCCD_HV_CPU1_R'
 '@S9S_MB_2U_LIB.S9S_MB_2U(SCH_1):SVID_ALERT_PVCCD_HV_CPU1_R':
 C_SIGNAL='@s9s_mb_2u_lib.s9s_mb_2u(sch_1):svid_alert_pvccd_hv_cpu1_r';
NODE_NAME     PU18 19
 '@S9S_MB_2U_LIB.S9S_MB_2U(SCH_1):PAGE282_I53@PURE_QUANTA.ISL69260IRAZT(CHIPS)':
 'NSVALERT#': CDS_PINID='\nsvalert#\';
NODE_NAME     R2580 2
 '@S9S_MB_2U_LIB.S9S_MB_2U(SCH_1):PAGE282_I40@PURE_QUANTA.Q_RES(CHIPS)':
 'B': CDS_PINID='B';
NET_NAME
'SVID_ALERT_PVCCINFAON_CPU0_R'
 '@S9S_MB_2U_LIB.S9S_MB_2U(SCH_1):SVID_ALERT_PVCCINFAON_CPU0_R':
 C_SIGNAL='@s9s_mb_2u_lib.s9s_mb_2u(sch_1):svid_alert_pvccinfaon_cpu0_r';
NODE_NAME     PU5 19
 '@S9S_MB_2U_LIB.S9S_MB_2U(SCH_1):PAGE260_I65@PURE_QUANTA.ISL69260IRAZT(CHIPS)':
 'NSVALERT#': CDS_PINID='\nsvalert#\';
NODE_NAME     R2389 2
 '@S9S_MB_2U_LIB.S9S_MB_2U(SCH_1):PAGE260_I52@PURE_QUANTA.Q_RES(CHIPS)':
 'B': CDS_PINID='B';
NET_NAME
'SVID_ALERT_PVCCINFAON_CPU1_R'
 '@S9S_MB_2U_LIB.S9S_MB_2U(SCH_1):SVID_ALERT_PVCCINFAON_CPU1_R':
 C_SIGNAL='@s9s_mb_2u_lib.s9s_mb_2u(sch_1):svid_alert_pvccinfaon_cpu1_r';
NODE_NAME     R2561 2
 '@S9S_MB_2U_LIB.S9S_MB_2U(SCH_1):PAGE278_I59@PURE_QUANTA.Q_RES(CHIPS)':
 'B': CDS_PINID='B';
NODE_NAME     PU22 19
 '@S9S_MB_2U_LIB.S9S_MB_2U(SCH_1):PAGE278_I38@PURE_QUANTA.ISL69260IRAZT(CHIPS)':
 'NSVALERT#': CDS_PINID='\nsvalert#\';
NET_NAME
'SVID_ALERT_PVCCIN_CPU0_R'
 '@S9S_MB_2U_LIB.S9S_MB_2U(SCH_1):SVID_ALERT_PVCCIN_CPU0_R':
 C_SIGNAL='@s9s_mb_2u_lib.s9s_mb_2u(sch_1):svid_alert_pvccin_cpu0_r';
NODE_NAME     PU14 23
 '@S9S_MB_2U_LIB.S9S_MB_2U(SCH_1):PAGE252_I63@PURE_QUANTA.RAA229126GNPHA0(CHIPS)':
 'NSVALERT': CDS_PINID='NSVALERT';
NODE_NAME     R2370 2
 '@S9S_MB_2U_LIB.S9S_MB_2U(SCH_1):PAGE252_I41@PURE_QUANTA.Q_RES(CHIPS)':
 'B': CDS_PINID='B';
NET_NAME
'SVID_ALERT_PVCCIN_CPU1_R'
 '@S9S_MB_2U_LIB.S9S_MB_2U(SCH_1):SVID_ALERT_PVCCIN_CPU1_R':
 C_SIGNAL='@s9s_mb_2u_lib.s9s_mb_2u(sch_1):svid_alert_pvccin_cpu1_r';
NODE_NAME     PU29 23
 '@S9S_MB_2U_LIB.S9S_MB_2U(SCH_1):PAGE270_I33@PURE_QUANTA.RAA229126GNPHA0(CHIPS)':
 'NSVALERT': CDS_PINID='NSVALERT';
NODE_NAME     R312 2
 '@S9S_MB_2U_LIB.S9S_MB_2U(SCH_1):PAGE270_I57@PURE_QUANTA.Q_RES(CHIPS)':
 'B': CDS_PINID='B';
NET_NAME
'SVID_CLK0_CPU0'
 '@S9S_MB_2U_LIB.S9S_MB_2U(SCH_1):SVID_CLK0_CPU0':
 C_SIGNAL='@s9s_mb_2u_lib.s9s_mb_2u(sch_1):svid_clk0_cpu0';
NODE_NAME     U2 BH26
 '@S9S_MB_2U_LIB.S9S_MB_2U(SCH_1):PAGE14_I1@PURE_QUANTA.SOCKET4677_AZIF0045P001C01CS(CHIPS)':
 'SVIDCLK0': CDS_PINID='SVIDCLK0';
NODE_NAME     R13 1
 '@S9S_MB_2U_LIB.S9S_MB_2U(SCH_1):PAGE14_I60@PURE_QUANTA.Q_RES(CHIPS)':
 'A': CDS_PINID='A';
NET_NAME
'SVID_CLK0_CPU0_R'
 '@S9S_MB_2U_LIB.S9S_MB_2U(SCH_1):SVID_CLK0_CPU0_R':
 C_SIGNAL='@s9s_mb_2u_lib.s9s_mb_2u(sch_1):svid_clk0_cpu0_r';
NODE_NAME     R13 2
 '@S9S_MB_2U_LIB.S9S_MB_2U(SCH_1):PAGE14_I60@PURE_QUANTA.Q_RES(CHIPS)':
 'B': CDS_PINID='B';
NODE_NAME     R2322 2
 '@S9S_MB_2U_LIB.S9S_MB_2U(SCH_1):PAGE260_I36@PURE_QUANTA.Q_RES(CHIPS)':
 'B': CDS_PINID='B';
NODE_NAME     R2368 1
 '@S9S_MB_2U_LIB.S9S_MB_2U(SCH_1):PAGE252_I44@PURE_QUANTA.Q_RES(CHIPS)':
 'A': CDS_PINID='A';
NODE_NAME     R2381 1
 '@S9S_MB_2U_LIB.S9S_MB_2U(SCH_1):PAGE252_I125@PURE_QUANTA.Q_RES(CHIPS)':
 'A': CDS_PINID='A';
NODE_NAME     R2596 1
 '@S9S_MB_2U_LIB.S9S_MB_2U(SCH_1):PAGE260_I56@PURE_QUANTA.Q_RES(CHIPS)':
 'A': CDS_PINID='A';
NET_NAME
'SVID_CLK0_CPU1'
 '@S9S_MB_2U_LIB.S9S_MB_2U(SCH_1):SVID_CLK0_CPU1':
 C_SIGNAL='@s9s_mb_2u_lib.s9s_mb_2u(sch_1):svid_clk0_cpu1';
NODE_NAME     U1 BH26
 '@S9S_MB_2U_LIB.S9S_MB_2U(SCH_1):PAGE45_I29@PURE_QUANTA.SOCKET4677_AZIF0045P001C01CS(CHIPS)':
 'SVIDCLK0': CDS_PINID='SVIDCLK0';
NODE_NAME     R56 1
 '@S9S_MB_2U_LIB.S9S_MB_2U(SCH_1):PAGE45_I55@PURE_QUANTA.Q_RES(CHIPS)':
 'A': CDS_PINID='A';
NET_NAME
'SVID_CLK0_CPU1_R'
 '@S9S_MB_2U_LIB.S9S_MB_2U(SCH_1):SVID_CLK0_CPU1_R':
 C_SIGNAL='@s9s_mb_2u_lib.s9s_mb_2u(sch_1):svid_clk0_cpu1_r';
NODE_NAME     R56 2
 '@S9S_MB_2U_LIB.S9S_MB_2U(SCH_1):PAGE45_I55@PURE_QUANTA.Q_RES(CHIPS)':
 'B': CDS_PINID='B';
NODE_NAME     R2559 1
 '@S9S_MB_2U_LIB.S9S_MB_2U(SCH_1):PAGE278_I61@PURE_QUANTA.Q_RES(CHIPS)':
 'A': CDS_PINID='A';
NODE_NAME     R2345 2
 '@S9S_MB_2U_LIB.S9S_MB_2U(SCH_1):PAGE278_I15@PURE_QUANTA.Q_RES(CHIPS)':
 'B': CDS_PINID='B';
NODE_NAME     R310 1
 '@S9S_MB_2U_LIB.S9S_MB_2U(SCH_1):PAGE270_I58@PURE_QUANTA.Q_RES(CHIPS)':
 'A': CDS_PINID='A';
NODE_NAME     R2554 1
 '@S9S_MB_2U_LIB.S9S_MB_2U(SCH_1):PAGE270_I100@PURE_QUANTA.Q_RES(CHIPS)':
 'A': CDS_PINID='A';
NET_NAME
'SVID_CLK1_CPU0'
 '@S9S_MB_2U_LIB.S9S_MB_2U(SCH_1):SVID_CLK1_CPU0':
 C_SIGNAL='@s9s_mb_2u_lib.s9s_mb_2u(sch_1):svid_clk1_cpu0';
NODE_NAME     U2 BF26
 '@S9S_MB_2U_LIB.S9S_MB_2U(SCH_1):PAGE14_I1@PURE_QUANTA.SOCKET4677_AZIF0045P001C01CS(CHIPS)':
 'SVIDCLK1': CDS_PINID='SVIDCLK1';
NODE_NAME     R16 1
 '@S9S_MB_2U_LIB.S9S_MB_2U(SCH_1):PAGE14_I63@PURE_QUANTA.Q_RES(CHIPS)':
 'A': CDS_PINID='A';
NET_NAME
'SVID_CLK1_CPU0_R'
 '@S9S_MB_2U_LIB.S9S_MB_2U(SCH_1):SVID_CLK1_CPU0_R':
 C_SIGNAL='@s9s_mb_2u_lib.s9s_mb_2u(sch_1):svid_clk1_cpu0_r';
NODE_NAME     R16 2
 '@S9S_MB_2U_LIB.S9S_MB_2U(SCH_1):PAGE14_I63@PURE_QUANTA.Q_RES(CHIPS)':
 'B': CDS_PINID='B';
NODE_NAME     R1717 2
 '@S9S_MB_2U_LIB.S9S_MB_2U(SCH_1):PAGE264_I25@PURE_QUANTA.Q_RES(CHIPS)':
 'B': CDS_PINID='B';
NODE_NAME     R2399 1
 '@S9S_MB_2U_LIB.S9S_MB_2U(SCH_1):PAGE264_I43@PURE_QUANTA.Q_RES(CHIPS)':
 'A': CDS_PINID='A';
NET_NAME
'SVID_CLK1_CPU1'
 '@S9S_MB_2U_LIB.S9S_MB_2U(SCH_1):SVID_CLK1_CPU1':
 C_SIGNAL='@s9s_mb_2u_lib.s9s_mb_2u(sch_1):svid_clk1_cpu1';
NODE_NAME     U1 BF26
 '@S9S_MB_2U_LIB.S9S_MB_2U(SCH_1):PAGE45_I29@PURE_QUANTA.SOCKET4677_AZIF0045P001C01CS(CHIPS)':
 'SVIDCLK1': CDS_PINID='SVIDCLK1';
NODE_NAME     R59 1
 '@S9S_MB_2U_LIB.S9S_MB_2U(SCH_1):PAGE45_I52@PURE_QUANTA.Q_RES(CHIPS)':
 'A': CDS_PINID='A';
NET_NAME
'SVID_CLK1_CPU1_R'
 '@S9S_MB_2U_LIB.S9S_MB_2U(SCH_1):SVID_CLK1_CPU1_R':
 C_SIGNAL='@s9s_mb_2u_lib.s9s_mb_2u(sch_1):svid_clk1_cpu1_r';
NODE_NAME     R59 2
 '@S9S_MB_2U_LIB.S9S_MB_2U(SCH_1):PAGE45_I52@PURE_QUANTA.Q_RES(CHIPS)':
 'B': CDS_PINID='B';
NODE_NAME     R1718 2
 '@S9S_MB_2U_LIB.S9S_MB_2U(SCH_1):PAGE282_I33@PURE_QUANTA.Q_RES(CHIPS)':
 'B': CDS_PINID='B';
NODE_NAME     R2578 1
 '@S9S_MB_2U_LIB.S9S_MB_2U(SCH_1):PAGE282_I42@PURE_QUANTA.Q_RES(CHIPS)':
 'A': CDS_PINID='A';
NET_NAME
'SVID_CLK_PVCCD_HV_CPU0_R'
 '@S9S_MB_2U_LIB.S9S_MB_2U(SCH_1):SVID_CLK_PVCCD_HV_CPU0_R':
 C_SIGNAL='@s9s_mb_2u_lib.s9s_mb_2u(sch_1):svid_clk_pvccd_hv_cpu0_r';
NODE_NAME     PU35 17
 '@S9S_MB_2U_LIB.S9S_MB_2U(SCH_1):PAGE264_I53@PURE_QUANTA.ISL69260IRAZT(CHIPS)':
 'SVCLK': CDS_PINID='SVCLK';
NODE_NAME     R2399 2
 '@S9S_MB_2U_LIB.S9S_MB_2U(SCH_1):PAGE264_I43@PURE_QUANTA.Q_RES(CHIPS)':
 'B': CDS_PINID='B';
NET_NAME
'SVID_CLK_PVCCD_HV_CPU1_R'
 '@S9S_MB_2U_LIB.S9S_MB_2U(SCH_1):SVID_CLK_PVCCD_HV_CPU1_R':
 C_SIGNAL='@s9s_mb_2u_lib.s9s_mb_2u(sch_1):svid_clk_pvccd_hv_cpu1_r';
NODE_NAME     PU18 17
 '@S9S_MB_2U_LIB.S9S_MB_2U(SCH_1):PAGE282_I53@PURE_QUANTA.ISL69260IRAZT(CHIPS)':
 'SVCLK': CDS_PINID='SVCLK';
NODE_NAME     R2578 2
 '@S9S_MB_2U_LIB.S9S_MB_2U(SCH_1):PAGE282_I42@PURE_QUANTA.Q_RES(CHIPS)':
 'B': CDS_PINID='B';
NET_NAME
'SVID_CLK_PVCCINFAON_CPU0_R'
 '@S9S_MB_2U_LIB.S9S_MB_2U(SCH_1):SVID_CLK_PVCCINFAON_CPU0_R':
 C_SIGNAL='@s9s_mb_2u_lib.s9s_mb_2u(sch_1):svid_clk_pvccinfaon_cpu0_r';
NODE_NAME     PU5 17
 '@S9S_MB_2U_LIB.S9S_MB_2U(SCH_1):PAGE260_I65@PURE_QUANTA.ISL69260IRAZT(CHIPS)':
 'SVCLK': CDS_PINID='SVCLK';
NODE_NAME     R2596 2
 '@S9S_MB_2U_LIB.S9S_MB_2U(SCH_1):PAGE260_I56@PURE_QUANTA.Q_RES(CHIPS)':
 'B': CDS_PINID='B';
NET_NAME
'SVID_CLK_PVCCINFAON_CPU1_R'
 '@S9S_MB_2U_LIB.S9S_MB_2U(SCH_1):SVID_CLK_PVCCINFAON_CPU1_R':
 C_SIGNAL='@s9s_mb_2u_lib.s9s_mb_2u(sch_1):svid_clk_pvccinfaon_cpu1_r';
NODE_NAME     R2559 2
 '@S9S_MB_2U_LIB.S9S_MB_2U(SCH_1):PAGE278_I61@PURE_QUANTA.Q_RES(CHIPS)':
 'B': CDS_PINID='B';
NODE_NAME     PU22 17
 '@S9S_MB_2U_LIB.S9S_MB_2U(SCH_1):PAGE278_I38@PURE_QUANTA.ISL69260IRAZT(CHIPS)':
 'SVCLK': CDS_PINID='SVCLK';
NET_NAME
'SVID_CLK_PVCCIN_CPU0_R'
 '@S9S_MB_2U_LIB.S9S_MB_2U(SCH_1):SVID_CLK_PVCCIN_CPU0_R':
 C_SIGNAL='@s9s_mb_2u_lib.s9s_mb_2u(sch_1):svid_clk_pvccin_cpu0_r';
NODE_NAME     PU14 21
 '@S9S_MB_2U_LIB.S9S_MB_2U(SCH_1):PAGE252_I63@PURE_QUANTA.RAA229126GNPHA0(CHIPS)':
 'SVCLK': CDS_PINID='SVCLK';
NODE_NAME     R2368 2
 '@S9S_MB_2U_LIB.S9S_MB_2U(SCH_1):PAGE252_I44@PURE_QUANTA.Q_RES(CHIPS)':
 'B': CDS_PINID='B';
NET_NAME
'SVID_CLK_PVCCIN_CPU1_R'
 '@S9S_MB_2U_LIB.S9S_MB_2U(SCH_1):SVID_CLK_PVCCIN_CPU1_R':
 C_SIGNAL='@s9s_mb_2u_lib.s9s_mb_2u(sch_1):svid_clk_pvccin_cpu1_r';
NODE_NAME     R310 2
 '@S9S_MB_2U_LIB.S9S_MB_2U(SCH_1):PAGE270_I58@PURE_QUANTA.Q_RES(CHIPS)':
 'B': CDS_PINID='B';
NODE_NAME     PU29 21
 '@S9S_MB_2U_LIB.S9S_MB_2U(SCH_1):PAGE270_I33@PURE_QUANTA.RAA229126GNPHA0(CHIPS)':
 'SVCLK': CDS_PINID='SVCLK';
NET_NAME
'SVID_DIO0_CPU0'
 '@S9S_MB_2U_LIB.S9S_MB_2U(SCH_1):SVID_DIO0_CPU0':
 C_SIGNAL='@s9s_mb_2u_lib.s9s_mb_2u(sch_1):svid_dio0_cpu0';
NODE_NAME     U2 BD26
 '@S9S_MB_2U_LIB.S9S_MB_2U(SCH_1):PAGE14_I1@PURE_QUANTA.SOCKET4677_AZIF0045P001C01CS(CHIPS)':
 'SVIDDATA0': CDS_PINID='SVIDDATA0';
NODE_NAME     R12 1
 '@S9S_MB_2U_LIB.S9S_MB_2U(SCH_1):PAGE14_I59@PURE_QUANTA.Q_RES(CHIPS)':
 'A': CDS_PINID='A';
NET_NAME
'SVID_DIO0_CPU0_R'
 '@S9S_MB_2U_LIB.S9S_MB_2U(SCH_1):SVID_DIO0_CPU0_R':
 C_SIGNAL='@s9s_mb_2u_lib.s9s_mb_2u(sch_1):svid_dio0_cpu0_r';
NODE_NAME     R12 2
 '@S9S_MB_2U_LIB.S9S_MB_2U(SCH_1):PAGE14_I59@PURE_QUANTA.Q_RES(CHIPS)':
 'B': CDS_PINID='B';
NODE_NAME     R328 1
 '@S9S_MB_2U_LIB.S9S_MB_2U(SCH_1):PAGE14_I93@PURE_QUANTA.Q_RES(CHIPS)':
 'A': CDS_PINID='A';
NODE_NAME     R2386 2
 '@S9S_MB_2U_LIB.S9S_MB_2U(SCH_1):PAGE260_I37@PURE_QUANTA.Q_RES(CHIPS)':
 'B': CDS_PINID='B';
NODE_NAME     R2388 1
 '@S9S_MB_2U_LIB.S9S_MB_2U(SCH_1):PAGE260_I57@PURE_QUANTA.Q_RES(CHIPS)':
 'A': CDS_PINID='A';
NODE_NAME     R2369 1
 '@S9S_MB_2U_LIB.S9S_MB_2U(SCH_1):PAGE252_I43@PURE_QUANTA.Q_RES(CHIPS)':
 'A': CDS_PINID='A';
NODE_NAME     R2590 1
 '@S9S_MB_2U_LIB.S9S_MB_2U(SCH_1):PAGE252_I124@PURE_QUANTA.Q_RES(CHIPS)':
 'A': CDS_PINID='A';
NET_NAME
'SVID_DIO0_CPU1'
 '@S9S_MB_2U_LIB.S9S_MB_2U(SCH_1):SVID_DIO0_CPU1':
 C_SIGNAL='@s9s_mb_2u_lib.s9s_mb_2u(sch_1):svid_dio0_cpu1';
NODE_NAME     U1 BD26
 '@S9S_MB_2U_LIB.S9S_MB_2U(SCH_1):PAGE45_I29@PURE_QUANTA.SOCKET4677_AZIF0045P001C01CS(CHIPS)':
 'SVIDDATA0': CDS_PINID='SVIDDATA0';
NODE_NAME     R55 1
 '@S9S_MB_2U_LIB.S9S_MB_2U(SCH_1):PAGE45_I54@PURE_QUANTA.Q_RES(CHIPS)':
 'A': CDS_PINID='A';
NET_NAME
'SVID_DIO0_CPU1_R'
 '@S9S_MB_2U_LIB.S9S_MB_2U(SCH_1):SVID_DIO0_CPU1_R':
 C_SIGNAL='@s9s_mb_2u_lib.s9s_mb_2u(sch_1):svid_dio0_cpu1_r';
NODE_NAME     R55 2
 '@S9S_MB_2U_LIB.S9S_MB_2U(SCH_1):PAGE45_I54@PURE_QUANTA.Q_RES(CHIPS)':
 'B': CDS_PINID='B';
NODE_NAME     R557 1
 '@S9S_MB_2U_LIB.S9S_MB_2U(SCH_1):PAGE45_I74@PURE_QUANTA.Q_RES(CHIPS)':
 'A': CDS_PINID='A';
NODE_NAME     R2560 1
 '@S9S_MB_2U_LIB.S9S_MB_2U(SCH_1):PAGE278_I60@PURE_QUANTA.Q_RES(CHIPS)':
 'A': CDS_PINID='A';
NODE_NAME     R2354 2
 '@S9S_MB_2U_LIB.S9S_MB_2U(SCH_1):PAGE278_I14@PURE_QUANTA.Q_RES(CHIPS)':
 'B': CDS_PINID='B';
NODE_NAME     R311 1
 '@S9S_MB_2U_LIB.S9S_MB_2U(SCH_1):PAGE270_I56@PURE_QUANTA.Q_RES(CHIPS)':
 'A': CDS_PINID='A';
NODE_NAME     R2553 1
 '@S9S_MB_2U_LIB.S9S_MB_2U(SCH_1):PAGE270_I99@PURE_QUANTA.Q_RES(CHIPS)':
 'A': CDS_PINID='A';
NET_NAME
'SVID_DIO1_CPU0'
 '@S9S_MB_2U_LIB.S9S_MB_2U(SCH_1):SVID_DIO1_CPU0':
 C_SIGNAL='@s9s_mb_2u_lib.s9s_mb_2u(sch_1):svid_dio1_cpu0';
NODE_NAME     U2 BL25
 '@S9S_MB_2U_LIB.S9S_MB_2U(SCH_1):PAGE14_I1@PURE_QUANTA.SOCKET4677_AZIF0045P001C01CS(CHIPS)':
 'SVIDDATA1': CDS_PINID='SVIDDATA1';
NODE_NAME     R15 1
 '@S9S_MB_2U_LIB.S9S_MB_2U(SCH_1):PAGE14_I62@PURE_QUANTA.Q_RES(CHIPS)':
 'A': CDS_PINID='A';
NET_NAME
'SVID_DIO1_CPU0_R'
 '@S9S_MB_2U_LIB.S9S_MB_2U(SCH_1):SVID_DIO1_CPU0_R':
 C_SIGNAL='@s9s_mb_2u_lib.s9s_mb_2u(sch_1):svid_dio1_cpu0_r';
NODE_NAME     R15 2
 '@S9S_MB_2U_LIB.S9S_MB_2U(SCH_1):PAGE14_I62@PURE_QUANTA.Q_RES(CHIPS)':
 'B': CDS_PINID='B';
NODE_NAME     R555 1
 '@S9S_MB_2U_LIB.S9S_MB_2U(SCH_1):PAGE14_I98@PURE_QUANTA.Q_RES(CHIPS)':
 'A': CDS_PINID='A';
NODE_NAME     R2400 1
 '@S9S_MB_2U_LIB.S9S_MB_2U(SCH_1):PAGE264_I42@PURE_QUANTA.Q_RES(CHIPS)':
 'A': CDS_PINID='A';
NODE_NAME     R1735 2
 '@S9S_MB_2U_LIB.S9S_MB_2U(SCH_1):PAGE264_I24@PURE_QUANTA.Q_RES(CHIPS)':
 'B': CDS_PINID='B';
NET_NAME
'SVID_DIO1_CPU1'
 '@S9S_MB_2U_LIB.S9S_MB_2U(SCH_1):SVID_DIO1_CPU1':
 C_SIGNAL='@s9s_mb_2u_lib.s9s_mb_2u(sch_1):svid_dio1_cpu1';
NODE_NAME     U1 BL25
 '@S9S_MB_2U_LIB.S9S_MB_2U(SCH_1):PAGE45_I29@PURE_QUANTA.SOCKET4677_AZIF0045P001C01CS(CHIPS)':
 'SVIDDATA1': CDS_PINID='SVIDDATA1';
NODE_NAME     R58 1
 '@S9S_MB_2U_LIB.S9S_MB_2U(SCH_1):PAGE45_I51@PURE_QUANTA.Q_RES(CHIPS)':
 'A': CDS_PINID='A';
NET_NAME
'SVID_DIO1_CPU1_R'
 '@S9S_MB_2U_LIB.S9S_MB_2U(SCH_1):SVID_DIO1_CPU1_R':
 C_SIGNAL='@s9s_mb_2u_lib.s9s_mb_2u(sch_1):svid_dio1_cpu1_r';
NODE_NAME     R58 2
 '@S9S_MB_2U_LIB.S9S_MB_2U(SCH_1):PAGE45_I51@PURE_QUANTA.Q_RES(CHIPS)':
 'B': CDS_PINID='B';
NODE_NAME     R559 1
 '@S9S_MB_2U_LIB.S9S_MB_2U(SCH_1):PAGE45_I69@PURE_QUANTA.Q_RES(CHIPS)':
 'A': CDS_PINID='A';
NODE_NAME     R2593 2
 '@S9S_MB_2U_LIB.S9S_MB_2U(SCH_1):PAGE282_I29@PURE_QUANTA.Q_RES(CHIPS)':
 'B': CDS_PINID='B';
NODE_NAME     R2579 1
 '@S9S_MB_2U_LIB.S9S_MB_2U(SCH_1):PAGE282_I41@PURE_QUANTA.Q_RES(CHIPS)':
 'A': CDS_PINID='A';
NET_NAME
'SVID_DIO_PVCCD_HV_CPU0_R'
 '@S9S_MB_2U_LIB.S9S_MB_2U(SCH_1):SVID_DIO_PVCCD_HV_CPU0_R':
 C_SIGNAL='@s9s_mb_2u_lib.s9s_mb_2u(sch_1):svid_dio_pvccd_hv_cpu0_r';
NODE_NAME     PU35 18
 '@S9S_MB_2U_LIB.S9S_MB_2U(SCH_1):PAGE264_I53@PURE_QUANTA.ISL69260IRAZT(CHIPS)':
 'SVDATA': CDS_PINID='SVDATA';
NODE_NAME     R2400 2
 '@S9S_MB_2U_LIB.S9S_MB_2U(SCH_1):PAGE264_I42@PURE_QUANTA.Q_RES(CHIPS)':
 'B': CDS_PINID='B';
NET_NAME
'SVID_DIO_PVCCD_HV_CPU1_R'
 '@S9S_MB_2U_LIB.S9S_MB_2U(SCH_1):SVID_DIO_PVCCD_HV_CPU1_R':
 C_SIGNAL='@s9s_mb_2u_lib.s9s_mb_2u(sch_1):svid_dio_pvccd_hv_cpu1_r';
NODE_NAME     PU18 18
 '@S9S_MB_2U_LIB.S9S_MB_2U(SCH_1):PAGE282_I53@PURE_QUANTA.ISL69260IRAZT(CHIPS)':
 'SVDATA': CDS_PINID='SVDATA';
NODE_NAME     R2579 2
 '@S9S_MB_2U_LIB.S9S_MB_2U(SCH_1):PAGE282_I41@PURE_QUANTA.Q_RES(CHIPS)':
 'B': CDS_PINID='B';
NET_NAME
'SVID_DIO_PVCCINFAON_CPU0_R'
 '@S9S_MB_2U_LIB.S9S_MB_2U(SCH_1):SVID_DIO_PVCCINFAON_CPU0_R':
 C_SIGNAL='@s9s_mb_2u_lib.s9s_mb_2u(sch_1):svid_dio_pvccinfaon_cpu0_r';
NODE_NAME     PU5 18
 '@S9S_MB_2U_LIB.S9S_MB_2U(SCH_1):PAGE260_I65@PURE_QUANTA.ISL69260IRAZT(CHIPS)':
 'SVDATA': CDS_PINID='SVDATA';
NODE_NAME     R2388 2
 '@S9S_MB_2U_LIB.S9S_MB_2U(SCH_1):PAGE260_I57@PURE_QUANTA.Q_RES(CHIPS)':
 'B': CDS_PINID='B';
NET_NAME
'SVID_DIO_PVCCINFAON_CPU1_R'
 '@S9S_MB_2U_LIB.S9S_MB_2U(SCH_1):SVID_DIO_PVCCINFAON_CPU1_R':
 C_SIGNAL='@s9s_mb_2u_lib.s9s_mb_2u(sch_1):svid_dio_pvccinfaon_cpu1_r';
NODE_NAME     R2560 2
 '@S9S_MB_2U_LIB.S9S_MB_2U(SCH_1):PAGE278_I60@PURE_QUANTA.Q_RES(CHIPS)':
 'B': CDS_PINID='B';
NODE_NAME     PU22 18
 '@S9S_MB_2U_LIB.S9S_MB_2U(SCH_1):PAGE278_I38@PURE_QUANTA.ISL69260IRAZT(CHIPS)':
 'SVDATA': CDS_PINID='SVDATA';
NET_NAME
'SVID_DIO_PVCCIN_CPU0_R'
 '@S9S_MB_2U_LIB.S9S_MB_2U(SCH_1):SVID_DIO_PVCCIN_CPU0_R':
 C_SIGNAL='@s9s_mb_2u_lib.s9s_mb_2u(sch_1):svid_dio_pvccin_cpu0_r';
NODE_NAME     PU14 22
 '@S9S_MB_2U_LIB.S9S_MB_2U(SCH_1):PAGE252_I63@PURE_QUANTA.RAA229126GNPHA0(CHIPS)':
 'SVDATA': CDS_PINID='SVDATA';
NODE_NAME     R2369 2
 '@S9S_MB_2U_LIB.S9S_MB_2U(SCH_1):PAGE252_I43@PURE_QUANTA.Q_RES(CHIPS)':
 'B': CDS_PINID='B';
NET_NAME
'SVID_DIO_PVCCIN_CPU1_R'
 '@S9S_MB_2U_LIB.S9S_MB_2U(SCH_1):SVID_DIO_PVCCIN_CPU1_R':
 C_SIGNAL='@s9s_mb_2u_lib.s9s_mb_2u(sch_1):svid_dio_pvccin_cpu1_r';
NODE_NAME     PU29 22
 '@S9S_MB_2U_LIB.S9S_MB_2U(SCH_1):PAGE270_I33@PURE_QUANTA.RAA229126GNPHA0(CHIPS)':
 'SVDATA': CDS_PINID='SVDATA';
NODE_NAME     R311 2
 '@S9S_MB_2U_LIB.S9S_MB_2U(SCH_1):PAGE270_I56@PURE_QUANTA.Q_RES(CHIPS)':
 'B': CDS_PINID='B';
NET_NAME
'SWB_HSC_EN'
 '@S9S_MB_2U_LIB.S9S_MB_2U(SCH_1):SWB_HSC_EN':
 C_SIGNAL='@s9s_mb_2u_lib.s9s_mb_2u(sch_1):swb_hsc_en';
NODE_NAME     R4558 1
 '@S9S_MB_2U_LIB.S9S_MB_2U(SCH_1):PAGE312_I150@PURE_QUANTA.Q_RES(CHIPS)':
 'A': CDS_PINID='A';
NODE_NAME     U316 1
 '@S9S_MB_2U_LIB.S9S_MB_2U(SCH_1):PAGE139_I86@PURE_QUANTA.74LVC2G17GW(CHIPS)':
 'A0': CDS_PINID='A0';
NODE_NAME     R4548 1
 '@S9S_MB_2U_LIB.S9S_MB_2U(SCH_1):PAGE139_I87@PURE_QUANTA.Q_RES(CHIPS)':
 'A': CDS_PINID='A';
NODE_NAME     R4547 2
 '@S9S_MB_2U_LIB.S9S_MB_2U(SCH_1):PAGE139_I89@PURE_QUANTA.Q_RES(CHIPS)':
 'B': CDS_PINID='B';
NET_NAME
'SWB_HSC_EN_BUF'
 '@S9S_MB_2U_LIB.S9S_MB_2U(SCH_1):SWB_HSC_EN_BUF':
 C_SIGNAL='@s9s_mb_2u_lib.s9s_mb_2u(sch_1):swb_hsc_en_buf';
NODE_NAME     J107 N8
 '@S9S_MB_2U_LIB.S9S_MB_2U(SCH_1):PAGE317_I38@PURE_QUANTA.CONN112_10137002101LF(CHIPS)':
 'N8': CDS_PINID='N8';
NODE_NAME     R4550 2
 '@S9S_MB_2U_LIB.S9S_MB_2U(SCH_1):PAGE139_I110@PURE_QUANTA.Q_RES(CHIPS)':
 'B': CDS_PINID='B';
NET_NAME
'SWB_HSC_EN_BUF_R'
 '@S9S_MB_2U_LIB.S9S_MB_2U(SCH_1):SWB_HSC_EN_BUF_R':
 C_SIGNAL='@s9s_mb_2u_lib.s9s_mb_2u(sch_1):swb_hsc_en_buf_r';
NODE_NAME     U316 6
 '@S9S_MB_2U_LIB.S9S_MB_2U(SCH_1):PAGE139_I86@PURE_QUANTA.74LVC2G17GW(CHIPS)':
 'B0': CDS_PINID='B0';
NODE_NAME     R4549 2
 '@S9S_MB_2U_LIB.S9S_MB_2U(SCH_1):PAGE139_I98@PURE_QUANTA.Q_RES(CHIPS)':
 'B': CDS_PINID='B';
NODE_NAME     R4555 1
 '@S9S_MB_2U_LIB.S9S_MB_2U(SCH_1):PAGE139_I99@PURE_QUANTA.Q_RES(CHIPS)':
 'A': CDS_PINID='A';
NODE_NAME     R4550 1
 '@S9S_MB_2U_LIB.S9S_MB_2U(SCH_1):PAGE139_I110@PURE_QUANTA.Q_RES(CHIPS)':
 'A': CDS_PINID='A';
NET_NAME
'SWB_HSC_EN_R'
 '@S9S_MB_2U_LIB.S9S_MB_2U(SCH_1):SWB_HSC_EN_R':
 C_SIGNAL='@s9s_mb_2u_lib.s9s_mb_2u(sch_1):swb_hsc_en_r';
NODE_NAME     U249 Y19
 '@S9S_MB_2U_LIB.S9S_MB_2U(SCH_1):PAGE312_I1@PURE_QUANTA.LCMXO3LF9400C5BG484C(CHIPS)':
 'PB44C': CDS_PINID='PB44C';
NODE_NAME     R4558 2
 '@S9S_MB_2U_LIB.S9S_MB_2U(SCH_1):PAGE312_I150@PURE_QUANTA.Q_RES(CHIPS)':
 'B': CDS_PINID='B';
NET_NAME
'SWB_HSC_PWRGD'
 '@S9S_MB_2U_LIB.S9S_MB_2U(SCH_1):SWB_HSC_PWRGD':
 C_SIGNAL='@s9s_mb_2u_lib.s9s_mb_2u(sch_1):swb_hsc_pwrgd';
NODE_NAME     J107 A7
 '@S9S_MB_2U_LIB.S9S_MB_2U(SCH_1):PAGE317_I38@PURE_QUANTA.CONN112_10137002101LF(CHIPS)':
 'A7': CDS_PINID='A7';
NODE_NAME     Q146 2
 '@S9S_MB_2U_LIB.S9S_MB_2U(SCH_1):PAGE143_I126@PURE_QUANTA.MOSFET_NCH_DUAL(CHIPS)':
 'G1': CDS_PINID='G1';
NODE_NAME     R4559 1
 '@S9S_MB_2U_LIB.S9S_MB_2U(SCH_1):PAGE143_I129@PURE_QUANTA.Q_RES(CHIPS)':
 'A': CDS_PINID='A';
NODE_NAME     R4562 2
 '@S9S_MB_2U_LIB.S9S_MB_2U(SCH_1):PAGE143_I132@PURE_QUANTA.Q_RES(CHIPS)':
 'B': CDS_PINID='B';
NET_NAME
'SWB_HSC_PWRGD_ISO'
 '@S9S_MB_2U_LIB.S9S_MB_2U(SCH_1):SWB_HSC_PWRGD_ISO':
 C_SIGNAL='@s9s_mb_2u_lib.s9s_mb_2u(sch_1):swb_hsc_pwrgd_iso';
NODE_NAME     R4561 2
 '@S9S_MB_2U_LIB.S9S_MB_2U(SCH_1):PAGE143_I116@PURE_QUANTA.Q_RES(CHIPS)':
 'B': CDS_PINID='B';
NODE_NAME     C2343 1
 '@S9S_MB_2U_LIB.S9S_MB_2U(SCH_1):PAGE143_I118@PURE_QUANTA.Q_CAP(CHIPS)':
 'A': CDS_PINID='A';
NODE_NAME     Q146 3
 '@S9S_MB_2U_LIB.S9S_MB_2U(SCH_1):PAGE143_I121@PURE_QUANTA.MOSFET_NCH_DUAL(CHIPS)':
 'D2': CDS_PINID='D2';
NODE_NAME     R4563 2
 '@S9S_MB_2U_LIB.S9S_MB_2U(SCH_1):PAGE312_I158@PURE_QUANTA.Q_RES(CHIPS)':
 'B': CDS_PINID='B';
NET_NAME
'SWB_HSC_PWRGD_ISO_R'
 '@S9S_MB_2U_LIB.S9S_MB_2U(SCH_1):SWB_HSC_PWRGD_ISO_R':
 C_SIGNAL='@s9s_mb_2u_lib.s9s_mb_2u(sch_1):swb_hsc_pwrgd_iso_r';
NODE_NAME     U249 W18
 '@S9S_MB_2U_LIB.S9S_MB_2U(SCH_1):PAGE312_I1@PURE_QUANTA.LCMXO3LF9400C5BG484C(CHIPS)':
 'PB44D': CDS_PINID='PB44D';
NODE_NAME     R4563 1
 '@S9S_MB_2U_LIB.S9S_MB_2U(SCH_1):PAGE312_I158@PURE_QUANTA.Q_RES(CHIPS)':
 'A': CDS_PINID='A';
NET_NAME
'SWB_HSC_PWRGD_N'
 '@S9S_MB_2U_LIB.S9S_MB_2U(SCH_1):SWB_HSC_PWRGD_N':
 C_SIGNAL='@s9s_mb_2u_lib.s9s_mb_2u(sch_1):swb_hsc_pwrgd_n';
NODE_NAME     Q146 5
 '@S9S_MB_2U_LIB.S9S_MB_2U(SCH_1):PAGE143_I121@PURE_QUANTA.MOSFET_NCH_DUAL(CHIPS)':
 'G2': CDS_PINID='G2';
NODE_NAME     R4560 2
 '@S9S_MB_2U_LIB.S9S_MB_2U(SCH_1):PAGE143_I124@PURE_QUANTA.Q_RES(CHIPS)':
 'B': CDS_PINID='B';
NODE_NAME     Q146 6
 '@S9S_MB_2U_LIB.S9S_MB_2U(SCH_1):PAGE143_I126@PURE_QUANTA.MOSFET_NCH_DUAL(CHIPS)':
 'D1': CDS_PINID='D1';
NET_NAME
'SW_P12V_AUX_P1V05_PCH_AUX_FLT'
 '@S9S_MB_2U_LIB.S9S_MB_2U(SCH_1):SW_P12V_AUX_P1V05_PCH_AUX_FLT':
 C_SIGNAL='@s9s_mb_2u_lib.s9s_mb_2u(sch_1):sw_p12v_aux_p1v05_pch_aux_flt';
NODE_NAME     PC1219 1
 '@S9S_MB_2U_LIB.S9S_MB_2U(SCH_1):PAGE248_I30@PURE_QUANTA.Q_CAP(CHIPS)':
 'A': CDS_PINID='A';
NODE_NAME     PC1215 1
 '@S9S_MB_2U_LIB.S9S_MB_2U(SCH_1):PAGE248_I23@PURE_QUANTA.Q_CAPP(CHIPS)':
 'A': CDS_PINID='A';
NODE_NAME     PC1218 1
 '@S9S_MB_2U_LIB.S9S_MB_2U(SCH_1):PAGE248_I29@PURE_QUANTA.Q_CAP(CHIPS)':
 'A': CDS_PINID='A';
NODE_NAME     PU73 10
 '@S9S_MB_2U_LIB.S9S_MB_2U(SCH_1):PAGE248_I11@PURE_QUANTA.RS53319LR(CHIPS)':
 'VIN1': CDS_PINID='VIN1';
NODE_NAME     PU73 21
 '@S9S_MB_2U_LIB.S9S_MB_2U(SCH_1):PAGE248_I11@PURE_QUANTA.RS53319LR(CHIPS)':
 'VIN2': CDS_PINID='VIN2';
NODE_NAME     PC1217 1
 '@S9S_MB_2U_LIB.S9S_MB_2U(SCH_1):PAGE248_I28@PURE_QUANTA.Q_CAP(CHIPS)':
 'A': CDS_PINID='A';
NODE_NAME     PL110 2
 '@S9S_MB_2U_LIB.S9S_MB_2U(SCH_1):PAGE248_I19@PURE_QUANTA.Q_INDUCTOR(CHIPS)':
 '2': CDS_PINID='\2\';
NODE_NAME     PC1216 1
 '@S9S_MB_2U_LIB.S9S_MB_2U(SCH_1):PAGE248_I25@PURE_QUANTA.Q_CAP(CHIPS)':
 'A': CDS_PINID='A';
NET_NAME
'SW_P12V_PVCCFA_EHV_FIVRA_CPU0_L'
 '@S9S_MB_2U_LIB.S9S_MB_2U(SCH_1):SW_P12V_PVCCFA_EHV_FIVRA_CPU0_L':
 C_SIGNAL='@s9s_mb_2u_lib.s9s_mb_2u(sch_1):sw_p12v_pvccfa_ehv_fivra_cpu0_l',
 CDS_GLOBAL_NET='TRUE';
NODE_NAME     PC1182_P0_4 1
 '@S9S_MB_2U_LIB.S9S_MB_2U(SCH_1):PAGE258_I36@PURE_QUANTA.Q_CAP(CHIPS)':
 'A': CDS_PINID='A';
NODE_NAME     PC603_P0_2 1
 '@S9S_MB_2U_LIB.S9S_MB_2U(SCH_1):PAGE257_I27@PURE_QUANTA.Q_CAP(CHIPS)':
 'A': CDS_PINID='A';
NODE_NAME     PC723_P0_4 1
 '@S9S_MB_2U_LIB.S9S_MB_2U(SCH_1):PAGE258_I41@PURE_QUANTA.Q_CAP(CHIPS)':
 'A': CDS_PINID='A';
NODE_NAME     PC1670 1
 '@S9S_MB_2U_LIB.S9S_MB_2U(SCH_1):PAGE257_I84@PURE_QUANTA.Q_CAP(CHIPS)':
 'A': CDS_PINID='A';
NODE_NAME     PC1174_P0_4 1
 '@S9S_MB_2U_LIB.S9S_MB_2U(SCH_1):PAGE258_I31@PURE_QUANTA.Q_CAP(CHIPS)':
 'A': CDS_PINID='A';
NODE_NAME     PU70_P0_2 25_29
 '@S9S_MB_2U_LIB.S9S_MB_2U(SCH_1):PAGE257_I16@PURE_QUANTA.ISL99390FRZTR5935(CHIPS)':
 'VIN1': CDS_PINID='VIN1';
NODE_NAME     PU70_P0_2 30
 '@S9S_MB_2U_LIB.S9S_MB_2U(SCH_1):PAGE257_I16@PURE_QUANTA.ISL99390FRZTR5935(CHIPS)':
 'VIN2': CDS_PINID='VIN2';
NODE_NAME     PC609_P0_2 1
 '@S9S_MB_2U_LIB.S9S_MB_2U(SCH_1):PAGE257_I31@PURE_QUANTA.Q_CAP(CHIPS)':
 'A': CDS_PINID='A';
NODE_NAME     PL44 2
 '@S9S_MB_2U_LIB.S9S_MB_2U(SCH_1):PAGE257_I80@PURE_QUANTA.Q_INDUCTOR(CHIPS)':
 '2': CDS_PINID='\2\';
NODE_NAME     PC1669 1
 '@S9S_MB_2U_LIB.S9S_MB_2U(SCH_1):PAGE257_I83@PURE_QUANTA.Q_CAP(CHIPS)':
 'A': CDS_PINID='A';
NODE_NAME     PC1671 1
 '@S9S_MB_2U_LIB.S9S_MB_2U(SCH_1):PAGE257_I85@PURE_QUANTA.Q_CAP(CHIPS)':
 'A': CDS_PINID='A';
NODE_NAME     PC605_P0_2 1
 '@S9S_MB_2U_LIB.S9S_MB_2U(SCH_1):PAGE257_I28@PURE_QUANTA.Q_CAP(CHIPS)':
 'A': CDS_PINID='A';
NODE_NAME     PC611_P0_2 1
 '@S9S_MB_2U_LIB.S9S_MB_2U(SCH_1):PAGE257_I32@PURE_QUANTA.Q_CAP(CHIPS)':
 'A': CDS_PINID='A';
NODE_NAME     PC721_P0_2 1
 '@S9S_MB_2U_LIB.S9S_MB_2U(SCH_1):PAGE257_I55@PURE_QUANTA.Q_CAP(CHIPS)':
 'A': CDS_PINID='A';
NODE_NAME     PC1672 1
 '@S9S_MB_2U_LIB.S9S_MB_2U(SCH_1):PAGE257_I86@PURE_QUANTA.Q_CAP(CHIPS)':
 'A': CDS_PINID='A';
NODE_NAME     PC622 1
 '@S9S_MB_2U_LIB.S9S_MB_2U(SCH_1):PAGE257_I88@PURE_QUANTA.Q_CAPP(CHIPS)':
 'A': CDS_PINID='A';
NODE_NAME     PU72_P0_4 25_29
 '@S9S_MB_2U_LIB.S9S_MB_2U(SCH_1):PAGE258_I10@PURE_QUANTA.ISL99390FRZTR5935(CHIPS)':
 'VIN1': CDS_PINID='VIN1';
NODE_NAME     PU72_P0_4 30
 '@S9S_MB_2U_LIB.S9S_MB_2U(SCH_1):PAGE258_I10@PURE_QUANTA.ISL99390FRZTR5935(CHIPS)':
 'VIN2': CDS_PINID='VIN2';
NODE_NAME     PC1176_P0_4 1
 '@S9S_MB_2U_LIB.S9S_MB_2U(SCH_1):PAGE258_I34@PURE_QUANTA.Q_CAP(CHIPS)':
 'A': CDS_PINID='A';
NODE_NAME     PC1180_P0_4 1
 '@S9S_MB_2U_LIB.S9S_MB_2U(SCH_1):PAGE258_I35@PURE_QUANTA.Q_CAP(CHIPS)':
 'A': CDS_PINID='A';
NET_NAME
'SW_P12V_PVCCFA_EHV_FIVRA_CPU0_R'
 '@S9S_MB_2U_LIB.S9S_MB_2U(SCH_1):SW_P12V_PVCCFA_EHV_FIVRA_CPU0_R':
 C_SIGNAL='@s9s_mb_2u_lib.s9s_mb_2u(sch_1):sw_p12v_pvccfa_ehv_fivra_cpu0_r',
 CDS_GLOBAL_NET='TRUE';
NODE_NAME     PC610_P0_1 1
 '@S9S_MB_2U_LIB.S9S_MB_2U(SCH_1):PAGE257_I48@PURE_QUANTA.Q_CAP(CHIPS)':
 'A': CDS_PINID='A';
NODE_NAME     PC1173_P0_3 1
 '@S9S_MB_2U_LIB.S9S_MB_2U(SCH_1):PAGE258_I44@PURE_QUANTA.Q_CAP(CHIPS)':
 'A': CDS_PINID='A';
NODE_NAME     PC1175_P0_3 1
 '@S9S_MB_2U_LIB.S9S_MB_2U(SCH_1):PAGE258_I46@PURE_QUANTA.Q_CAP(CHIPS)':
 'A': CDS_PINID='A';
NODE_NAME     PC602_P0_1 1
 '@S9S_MB_2U_LIB.S9S_MB_2U(SCH_1):PAGE257_I44@PURE_QUANTA.Q_CAP(CHIPS)':
 'A': CDS_PINID='A';
NODE_NAME     PC604_P0_1 1
 '@S9S_MB_2U_LIB.S9S_MB_2U(SCH_1):PAGE257_I45@PURE_QUANTA.Q_CAP(CHIPS)':
 'A': CDS_PINID='A';
NODE_NAME     PC1675 1
 '@S9S_MB_2U_LIB.S9S_MB_2U(SCH_1):PAGE258_I77@PURE_QUANTA.Q_CAP(CHIPS)':
 'A': CDS_PINID='A';
NODE_NAME     PC608_P0_1 1
 '@S9S_MB_2U_LIB.S9S_MB_2U(SCH_1):PAGE257_I47@PURE_QUANTA.Q_CAP(CHIPS)':
 'A': CDS_PINID='A';
NODE_NAME     PC1674 1
 '@S9S_MB_2U_LIB.S9S_MB_2U(SCH_1):PAGE258_I76@PURE_QUANTA.Q_CAP(CHIPS)':
 'A': CDS_PINID='A';
NODE_NAME     PC1181_P0_3 1
 '@S9S_MB_2U_LIB.S9S_MB_2U(SCH_1):PAGE258_I48@PURE_QUANTA.Q_CAP(CHIPS)':
 'A': CDS_PINID='A';
NODE_NAME     PC1673 1
 '@S9S_MB_2U_LIB.S9S_MB_2U(SCH_1):PAGE258_I75@PURE_QUANTA.Q_CAP(CHIPS)':
 'A': CDS_PINID='A';
NODE_NAME     PC1189 1
 '@S9S_MB_2U_LIB.S9S_MB_2U(SCH_1):PAGE258_I80@PURE_QUANTA.Q_CAPP(CHIPS)':
 'A': CDS_PINID='A';
NODE_NAME     PU71_P0_3 25_29
 '@S9S_MB_2U_LIB.S9S_MB_2U(SCH_1):PAGE258_I82@PURE_QUANTA.ISL99390FRZTR5935(CHIPS)':
 'VIN1': CDS_PINID='VIN1';
NODE_NAME     PU71_P0_3 30
 '@S9S_MB_2U_LIB.S9S_MB_2U(SCH_1):PAGE258_I82@PURE_QUANTA.ISL99390FRZTR5935(CHIPS)':
 'VIN2': CDS_PINID='VIN2';
NODE_NAME     PU69_P0_1 25_29
 '@S9S_MB_2U_LIB.S9S_MB_2U(SCH_1):PAGE257_I25@PURE_QUANTA.ISL99390FRZTR5935(CHIPS)':
 'VIN1': CDS_PINID='VIN1';
NODE_NAME     PU69_P0_1 30
 '@S9S_MB_2U_LIB.S9S_MB_2U(SCH_1):PAGE257_I25@PURE_QUANTA.ISL99390FRZTR5935(CHIPS)':
 'VIN2': CDS_PINID='VIN2';
NODE_NAME     PC720_P0_1 1
 '@S9S_MB_2U_LIB.S9S_MB_2U(SCH_1):PAGE257_I73@PURE_QUANTA.Q_CAP(CHIPS)':
 'A': CDS_PINID='A';
NODE_NAME     PC1179_P0_3 1
 '@S9S_MB_2U_LIB.S9S_MB_2U(SCH_1):PAGE258_I47@PURE_QUANTA.Q_CAP(CHIPS)':
 'A': CDS_PINID='A';
NODE_NAME     PC722_P0_3 1
 '@S9S_MB_2U_LIB.S9S_MB_2U(SCH_1):PAGE258_I53@PURE_QUANTA.Q_CAP(CHIPS)':
 'A': CDS_PINID='A';
NODE_NAME     PL101 2
 '@S9S_MB_2U_LIB.S9S_MB_2U(SCH_1):PAGE258_I59@PURE_QUANTA.Q_INDUCTOR(CHIPS)':
 '2': CDS_PINID='\2\';
NODE_NAME     PC1676 1
 '@S9S_MB_2U_LIB.S9S_MB_2U(SCH_1):PAGE258_I79@PURE_QUANTA.Q_CAP(CHIPS)':
 'A': CDS_PINID='A';
NET_NAME
'SW_P12V_PVCCFA_EHV_FIVRA_CPU1_L'
 '@S9S_MB_2U_LIB.S9S_MB_2U(SCH_1):SW_P12V_PVCCFA_EHV_FIVRA_CPU1_L':
 C_SIGNAL='@s9s_mb_2u_lib.s9s_mb_2u(sch_1):sw_p12v_pvccfa_ehv_fivra_cpu1_l',
 CDS_GLOBAL_NET='TRUE';
NODE_NAME     PC1194_P1_4 1
 '@S9S_MB_2U_LIB.S9S_MB_2U(SCH_1):PAGE276_I33@PURE_QUANTA.Q_CAP(CHIPS)':
 'A': CDS_PINID='A';
NODE_NAME     PC1200_P1_4 1
 '@S9S_MB_2U_LIB.S9S_MB_2U(SCH_1):PAGE276_I36@PURE_QUANTA.Q_CAP(CHIPS)':
 'A': CDS_PINID='A';
NODE_NAME     PU76_P1_2 25_29
 '@S9S_MB_2U_LIB.S9S_MB_2U(SCH_1):PAGE275_I9@PURE_QUANTA.ISL99390FRZTR5935(CHIPS)':
 'VIN1': CDS_PINID='VIN1';
NODE_NAME     PU76_P1_2 30
 '@S9S_MB_2U_LIB.S9S_MB_2U(SCH_1):PAGE275_I9@PURE_QUANTA.ISL99390FRZTR5935(CHIPS)':
 'VIN2': CDS_PINID='VIN2';
NODE_NAME     PC398_P1_2 1
 '@S9S_MB_2U_LIB.S9S_MB_2U(SCH_1):PAGE275_I37@PURE_QUANTA.Q_CAP(CHIPS)':
 'A': CDS_PINID='A';
NODE_NAME     PC400_P1_2 1
 '@S9S_MB_2U_LIB.S9S_MB_2U(SCH_1):PAGE275_I39@PURE_QUANTA.Q_CAP(CHIPS)':
 'A': CDS_PINID='A';
NODE_NAME     PC725_P1_2 1
 '@S9S_MB_2U_LIB.S9S_MB_2U(SCH_1):PAGE275_I46@PURE_QUANTA.Q_CAP(CHIPS)':
 'A': CDS_PINID='A';
NODE_NAME     PC1679 1
 '@S9S_MB_2U_LIB.S9S_MB_2U(SCH_1):PAGE275_I84@PURE_QUANTA.Q_CAP(CHIPS)':
 'A': CDS_PINID='A';
NODE_NAME     PC404_P1_2 1
 '@S9S_MB_2U_LIB.S9S_MB_2U(SCH_1):PAGE275_I40@PURE_QUANTA.Q_CAP(CHIPS)':
 'A': CDS_PINID='A';
NODE_NAME     PC1678 1
 '@S9S_MB_2U_LIB.S9S_MB_2U(SCH_1):PAGE275_I83@PURE_QUANTA.Q_CAP(CHIPS)':
 'A': CDS_PINID='A';
NODE_NAME     PU78_P1_4 25_29
 '@S9S_MB_2U_LIB.S9S_MB_2U(SCH_1):PAGE276_I15@PURE_QUANTA.ISL99390FRZTR5935(CHIPS)':
 'VIN1': CDS_PINID='VIN1';
NODE_NAME     PU78_P1_4 30
 '@S9S_MB_2U_LIB.S9S_MB_2U(SCH_1):PAGE276_I15@PURE_QUANTA.ISL99390FRZTR5935(CHIPS)':
 'VIN2': CDS_PINID='VIN2';
NODE_NAME     PC1202_P1_4 1
 '@S9S_MB_2U_LIB.S9S_MB_2U(SCH_1):PAGE276_I37@PURE_QUANTA.Q_CAP(CHIPS)':
 'A': CDS_PINID='A';
NODE_NAME     PC1677 1
 '@S9S_MB_2U_LIB.S9S_MB_2U(SCH_1):PAGE275_I80@PURE_QUANTA.Q_CAP(CHIPS)':
 'A': CDS_PINID='A';
NODE_NAME     PC1196_P1_4 1
 '@S9S_MB_2U_LIB.S9S_MB_2U(SCH_1):PAGE276_I35@PURE_QUANTA.Q_CAP(CHIPS)':
 'A': CDS_PINID='A';
NODE_NAME     PC727_P1_4 1
 '@S9S_MB_2U_LIB.S9S_MB_2U(SCH_1):PAGE276_I52@PURE_QUANTA.Q_CAP(CHIPS)':
 'A': CDS_PINID='A';
NODE_NAME     PC406_P1_2 1
 '@S9S_MB_2U_LIB.S9S_MB_2U(SCH_1):PAGE275_I42@PURE_QUANTA.Q_CAP(CHIPS)':
 'A': CDS_PINID='A';
NODE_NAME     PL43 2
 '@S9S_MB_2U_LIB.S9S_MB_2U(SCH_1):PAGE275_I79@PURE_QUANTA.Q_INDUCTOR(CHIPS)':
 '2': CDS_PINID='\2\';
NODE_NAME     PC1680 1
 '@S9S_MB_2U_LIB.S9S_MB_2U(SCH_1):PAGE275_I85@PURE_QUANTA.Q_CAP(CHIPS)':
 'A': CDS_PINID='A';
NODE_NAME     PC417 1
 '@S9S_MB_2U_LIB.S9S_MB_2U(SCH_1):PAGE275_I87@PURE_QUANTA.Q_CAPP(CHIPS)':
 'A': CDS_PINID='A';
NET_NAME
'SW_P12V_PVCCFA_EHV_FIVRA_CPU1_R'
 '@S9S_MB_2U_LIB.S9S_MB_2U(SCH_1):SW_P12V_PVCCFA_EHV_FIVRA_CPU1_R':
 C_SIGNAL='@s9s_mb_2u_lib.s9s_mb_2u(sch_1):sw_p12v_pvccfa_ehv_fivra_cpu1_r',
 CDS_GLOBAL_NET='TRUE';
NODE_NAME     PC1682 1
 '@S9S_MB_2U_LIB.S9S_MB_2U(SCH_1):PAGE276_I77@PURE_QUANTA.Q_CAP(CHIPS)':
 'A': CDS_PINID='A';
NODE_NAME     PC397_P1_1 1
 '@S9S_MB_2U_LIB.S9S_MB_2U(SCH_1):PAGE275_I49@PURE_QUANTA.Q_CAP(CHIPS)':
 'A': CDS_PINID='A';
NODE_NAME     PC1193_P1_3 1
 '@S9S_MB_2U_LIB.S9S_MB_2U(SCH_1):PAGE276_I38@PURE_QUANTA.Q_CAP(CHIPS)':
 'A': CDS_PINID='A';
NODE_NAME     PC1199_P1_3 1
 '@S9S_MB_2U_LIB.S9S_MB_2U(SCH_1):PAGE276_I41@PURE_QUANTA.Q_CAP(CHIPS)':
 'A': CDS_PINID='A';
NODE_NAME     PC399_P1_1 1
 '@S9S_MB_2U_LIB.S9S_MB_2U(SCH_1):PAGE275_I51@PURE_QUANTA.Q_CAP(CHIPS)':
 'A': CDS_PINID='A';
NODE_NAME     PC403_P1_1 1
 '@S9S_MB_2U_LIB.S9S_MB_2U(SCH_1):PAGE275_I52@PURE_QUANTA.Q_CAP(CHIPS)':
 'A': CDS_PINID='A';
NODE_NAME     PC1195_P1_3 1
 '@S9S_MB_2U_LIB.S9S_MB_2U(SCH_1):PAGE276_I39@PURE_QUANTA.Q_CAP(CHIPS)':
 'A': CDS_PINID='A';
NODE_NAME     PC1201_P1_3 1
 '@S9S_MB_2U_LIB.S9S_MB_2U(SCH_1):PAGE276_I42@PURE_QUANTA.Q_CAP(CHIPS)':
 'A': CDS_PINID='A';
NODE_NAME     PL14 2
 '@S9S_MB_2U_LIB.S9S_MB_2U(SCH_1):PAGE276_I64@PURE_QUANTA.Q_INDUCTOR(CHIPS)':
 '2': CDS_PINID='\2\';
NODE_NAME     PC1684 1
 '@S9S_MB_2U_LIB.S9S_MB_2U(SCH_1):PAGE276_I80@PURE_QUANTA.Q_CAP(CHIPS)':
 'A': CDS_PINID='A';
NODE_NAME     PC405_P1_1 1
 '@S9S_MB_2U_LIB.S9S_MB_2U(SCH_1):PAGE275_I56@PURE_QUANTA.Q_CAP(CHIPS)':
 'A': CDS_PINID='A';
NODE_NAME     PU77_P1_3 25_29
 '@S9S_MB_2U_LIB.S9S_MB_2U(SCH_1):PAGE276_I24@PURE_QUANTA.ISL99390FRZTR5935(CHIPS)':
 'VIN1': CDS_PINID='VIN1';
NODE_NAME     PU77_P1_3 30
 '@S9S_MB_2U_LIB.S9S_MB_2U(SCH_1):PAGE276_I24@PURE_QUANTA.ISL99390FRZTR5935(CHIPS)':
 'VIN2': CDS_PINID='VIN2';
NODE_NAME     PC724_P1_1 1
 '@S9S_MB_2U_LIB.S9S_MB_2U(SCH_1):PAGE275_I58@PURE_QUANTA.Q_CAP(CHIPS)':
 'A': CDS_PINID='A';
NODE_NAME     PU75_P1_1 25_29
 '@S9S_MB_2U_LIB.S9S_MB_2U(SCH_1):PAGE275_I89@PURE_QUANTA.ISL99390FRZTR5935(CHIPS)':
 'VIN1': CDS_PINID='VIN1';
NODE_NAME     PU75_P1_1 30
 '@S9S_MB_2U_LIB.S9S_MB_2U(SCH_1):PAGE275_I89@PURE_QUANTA.ISL99390FRZTR5935(CHIPS)':
 'VIN2': CDS_PINID='VIN2';
NODE_NAME     PC726_P1_3 1
 '@S9S_MB_2U_LIB.S9S_MB_2U(SCH_1):PAGE276_I60@PURE_QUANTA.Q_CAP(CHIPS)':
 'A': CDS_PINID='A';
NODE_NAME     PC1681 1
 '@S9S_MB_2U_LIB.S9S_MB_2U(SCH_1):PAGE276_I75@PURE_QUANTA.Q_CAP(CHIPS)':
 'A': CDS_PINID='A';
NODE_NAME     PC1683 1
 '@S9S_MB_2U_LIB.S9S_MB_2U(SCH_1):PAGE276_I78@PURE_QUANTA.Q_CAP(CHIPS)':
 'A': CDS_PINID='A';
NODE_NAME     PC1210 1
 '@S9S_MB_2U_LIB.S9S_MB_2U(SCH_1):PAGE276_I81@PURE_QUANTA.Q_CAPP(CHIPS)':
 'A': CDS_PINID='A';
NET_NAME
'SW_P12V_PVCCINFAON_CPU0_FLT'
 '@S9S_MB_2U_LIB.S9S_MB_2U(SCH_1):SW_P12V_PVCCINFAON_CPU0_FLT':
 C_SIGNAL='@s9s_mb_2u_lib.s9s_mb_2u(sch_1):sw_p12v_pvccinfaon_cpu0_flt',
 CDS_GLOBAL_NET='TRUE';
NODE_NAME     PC176 1
 '@S9S_MB_2U_LIB.S9S_MB_2U(SCH_1):PAGE262_I24@PURE_QUANTA.Q_CAP(CHIPS)':
 'A': CDS_PINID='A';
NODE_NAME     PC177 1
 '@S9S_MB_2U_LIB.S9S_MB_2U(SCH_1):PAGE262_I25@PURE_QUANTA.Q_CAP(CHIPS)':
 'A': CDS_PINID='A';
NODE_NAME     PC180 1
 '@S9S_MB_2U_LIB.S9S_MB_2U(SCH_1):PAGE262_I27@PURE_QUANTA.Q_CAP(CHIPS)':
 'A': CDS_PINID='A';
NODE_NAME     PU44_P0_2 25_29
 '@S9S_MB_2U_LIB.S9S_MB_2U(SCH_1):PAGE261_I12@PURE_QUANTA.ISL99390FRZTR5935(CHIPS)':
 'VIN1': CDS_PINID='VIN1';
NODE_NAME     PU44_P0_2 30
 '@S9S_MB_2U_LIB.S9S_MB_2U(SCH_1):PAGE261_I12@PURE_QUANTA.ISL99390FRZTR5935(CHIPS)':
 'VIN2': CDS_PINID='VIN2';
NODE_NAME     PC190_P0_2 1
 '@S9S_MB_2U_LIB.S9S_MB_2U(SCH_1):PAGE261_I32@PURE_QUANTA.Q_CAP(CHIPS)':
 'A': CDS_PINID='A';
NODE_NAME     PC192_P0_2 1
 '@S9S_MB_2U_LIB.S9S_MB_2U(SCH_1):PAGE261_I35@PURE_QUANTA.Q_CAP(CHIPS)':
 'A': CDS_PINID='A';
NODE_NAME     PC196_P0_2 1
 '@S9S_MB_2U_LIB.S9S_MB_2U(SCH_1):PAGE261_I36@PURE_QUANTA.Q_CAP(CHIPS)':
 'A': CDS_PINID='A';
NODE_NAME     PC198_P0_2 1
 '@S9S_MB_2U_LIB.S9S_MB_2U(SCH_1):PAGE261_I37@PURE_QUANTA.Q_CAP(CHIPS)':
 'A': CDS_PINID='A';
NODE_NAME     PC189_P0_1 1
 '@S9S_MB_2U_LIB.S9S_MB_2U(SCH_1):PAGE261_I45@PURE_QUANTA.Q_CAP(CHIPS)':
 'A': CDS_PINID='A';
NODE_NAME     PC191_P0_1 1
 '@S9S_MB_2U_LIB.S9S_MB_2U(SCH_1):PAGE261_I48@PURE_QUANTA.Q_CAP(CHIPS)':
 'A': CDS_PINID='A';
NODE_NAME     PC195_P0_1 1
 '@S9S_MB_2U_LIB.S9S_MB_2U(SCH_1):PAGE261_I49@PURE_QUANTA.Q_CAP(CHIPS)':
 'A': CDS_PINID='A';
NODE_NAME     PC197_P0_1 1
 '@S9S_MB_2U_LIB.S9S_MB_2U(SCH_1):PAGE261_I50@PURE_QUANTA.Q_CAP(CHIPS)':
 'A': CDS_PINID='A';
NODE_NAME     PC207 1
 '@S9S_MB_2U_LIB.S9S_MB_2U(SCH_1):PAGE261_I74@PURE_QUANTA.Q_CAPP(CHIPS)':
 'A': CDS_PINID='A';
NODE_NAME     PU36 25_29
 '@S9S_MB_2U_LIB.S9S_MB_2U(SCH_1):PAGE265_I8@PURE_QUANTA.ISL99390FRZTR5935(CHIPS)':
 'VIN1': CDS_PINID='VIN1';
NODE_NAME     PU36 30
 '@S9S_MB_2U_LIB.S9S_MB_2U(SCH_1):PAGE265_I8@PURE_QUANTA.ISL99390FRZTR5935(CHIPS)':
 'VIN2': CDS_PINID='VIN2';
NODE_NAME     PC634 1
 '@S9S_MB_2U_LIB.S9S_MB_2U(SCH_1):PAGE265_I18@PURE_QUANTA.Q_CAP(CHIPS)':
 'A': CDS_PINID='A';
NODE_NAME     PC635 1
 '@S9S_MB_2U_LIB.S9S_MB_2U(SCH_1):PAGE265_I20@PURE_QUANTA.Q_CAP(CHIPS)':
 'A': CDS_PINID='A';
NODE_NAME     PC637 1
 '@S9S_MB_2U_LIB.S9S_MB_2U(SCH_1):PAGE265_I21@PURE_QUANTA.Q_CAP(CHIPS)':
 'A': CDS_PINID='A';
NODE_NAME     PC638 1
 '@S9S_MB_2U_LIB.S9S_MB_2U(SCH_1):PAGE265_I23@PURE_QUANTA.Q_CAP(CHIPS)':
 'A': CDS_PINID='A';
NODE_NAME     PL6 2
 '@S9S_MB_2U_LIB.S9S_MB_2U(SCH_1):PAGE261_I62@PURE_QUANTA.Q_INDUCTOR(CHIPS)':
 '2': CDS_PINID='\2\';
NODE_NAME     PC208 1
 '@S9S_MB_2U_LIB.S9S_MB_2U(SCH_1):PAGE261_I75@PURE_QUANTA.Q_CAPP(CHIPS)':
 'A': CDS_PINID='A';
NODE_NAME     PU43_P0_1 25_29
 '@S9S_MB_2U_LIB.S9S_MB_2U(SCH_1):PAGE261_I79@PURE_QUANTA.ISL99390FRZTR5935(CHIPS)':
 'VIN1': CDS_PINID='VIN1';
NODE_NAME     PU43_P0_1 30
 '@S9S_MB_2U_LIB.S9S_MB_2U(SCH_1):PAGE261_I79@PURE_QUANTA.ISL99390FRZTR5935(CHIPS)':
 'VIN2': CDS_PINID='VIN2';
NODE_NAME     PC179 1
 '@S9S_MB_2U_LIB.S9S_MB_2U(SCH_1):PAGE262_I26@PURE_QUANTA.Q_CAP(CHIPS)':
 'A': CDS_PINID='A';
NODE_NAME     PU42 16_18-28
 '@S9S_MB_2U_LIB.S9S_MB_2U(SCH_1):PAGE262_I14@PURE_QUANTA.RAA2213404GNPHB0(CHIPS)':
 'VIN': CDS_PINID='VIN';
NODE_NAME     PC1273 1
 '@S9S_MB_2U_LIB.S9S_MB_2U(SCH_1):PAGE268_I15@PURE_QUANTA.Q_CAP(CHIPS)':
 'A': CDS_PINID='A';
NODE_NAME     PC1274 1
 '@S9S_MB_2U_LIB.S9S_MB_2U(SCH_1):PAGE268_I23@PURE_QUANTA.Q_CAP(CHIPS)':
 'A': CDS_PINID='A';
NODE_NAME     PC1272 1
 '@S9S_MB_2U_LIB.S9S_MB_2U(SCH_1):PAGE268_I13@PURE_QUANTA.Q_CAP(CHIPS)':
 'A': CDS_PINID='A';
NODE_NAME     PU81 3
 '@S9S_MB_2U_LIB.S9S_MB_2U(SCH_1):PAGE268_I22@PURE_QUANTA.RS53317LR(CHIPS)':
 'VIN': CDS_PINID='VIN';
NET_NAME
'SW_P12V_PVCCINFAON_CPU1_FLT'
 '@S9S_MB_2U_LIB.S9S_MB_2U(SCH_1):SW_P12V_PVCCINFAON_CPU1_FLT':
 C_SIGNAL='@s9s_mb_2u_lib.s9s_mb_2u(sch_1):sw_p12v_pvccinfaon_cpu1_flt',
 CDS_GLOBAL_NET='TRUE';
NODE_NAME     PC443_P1_2 1
 '@S9S_MB_2U_LIB.S9S_MB_2U(SCH_1):PAGE279_I36@PURE_QUANTA.Q_CAP(CHIPS)':
 'A': CDS_PINID='A';
NODE_NAME     PU50_P1_1 25_29
 '@S9S_MB_2U_LIB.S9S_MB_2U(SCH_1):PAGE279_I38@PURE_QUANTA.ISL99390FRZTR5935(CHIPS)':
 'VIN1': CDS_PINID='VIN1';
NODE_NAME     PU50_P1_1 30
 '@S9S_MB_2U_LIB.S9S_MB_2U(SCH_1):PAGE279_I38@PURE_QUANTA.ISL99390FRZTR5935(CHIPS)':
 'VIN2': CDS_PINID='VIN2';
NODE_NAME     PC444_P1_1 1
 '@S9S_MB_2U_LIB.S9S_MB_2U(SCH_1):PAGE279_I41@PURE_QUANTA.Q_CAP(CHIPS)':
 'A': CDS_PINID='A';
NODE_NAME     PC449_P1_2 1
 '@S9S_MB_2U_LIB.S9S_MB_2U(SCH_1):PAGE279_I43@PURE_QUANTA.Q_CAP(CHIPS)':
 'A': CDS_PINID='A';
NODE_NAME     PC448_P1_1 1
 '@S9S_MB_2U_LIB.S9S_MB_2U(SCH_1):PAGE279_I51@PURE_QUANTA.Q_CAP(CHIPS)':
 'A': CDS_PINID='A';
NODE_NAME     PC460 1
 '@S9S_MB_2U_LIB.S9S_MB_2U(SCH_1):PAGE279_I69@PURE_QUANTA.Q_CAPP(CHIPS)':
 'A': CDS_PINID='A';
NODE_NAME     PU49 16_18-28
 '@S9S_MB_2U_LIB.S9S_MB_2U(SCH_1):PAGE280_I14@PURE_QUANTA.RAA2213404GNPHB0(CHIPS)':
 'VIN': CDS_PINID='VIN';
NODE_NAME     PC429 1
 '@S9S_MB_2U_LIB.S9S_MB_2U(SCH_1):PAGE280_I24@PURE_QUANTA.Q_CAP(CHIPS)':
 'A': CDS_PINID='A';
NODE_NAME     PC432 1
 '@S9S_MB_2U_LIB.S9S_MB_2U(SCH_1):PAGE280_I27@PURE_QUANTA.Q_CAP(CHIPS)':
 'A': CDS_PINID='A';
NODE_NAME     PC374 1
 '@S9S_MB_2U_LIB.S9S_MB_2U(SCH_1):PAGE283_I20@PURE_QUANTA.Q_CAP(CHIPS)':
 'A': CDS_PINID='A';
NODE_NAME     PC377 1
 '@S9S_MB_2U_LIB.S9S_MB_2U(SCH_1):PAGE283_I23@PURE_QUANTA.Q_CAP(CHIPS)':
 'A': CDS_PINID='A';
NODE_NAME     PU51_P1_2 25_29
 '@S9S_MB_2U_LIB.S9S_MB_2U(SCH_1):PAGE279_I29@PURE_QUANTA.ISL99390FRZTR5935(CHIPS)':
 'VIN1': CDS_PINID='VIN1';
NODE_NAME     PU51_P1_2 30
 '@S9S_MB_2U_LIB.S9S_MB_2U(SCH_1):PAGE279_I29@PURE_QUANTA.ISL99390FRZTR5935(CHIPS)':
 'VIN2': CDS_PINID='VIN2';
NODE_NAME     PC445_P1_2 1
 '@S9S_MB_2U_LIB.S9S_MB_2U(SCH_1):PAGE279_I37@PURE_QUANTA.Q_CAP(CHIPS)':
 'A': CDS_PINID='A';
NODE_NAME     PC451_P1_2 1
 '@S9S_MB_2U_LIB.S9S_MB_2U(SCH_1):PAGE279_I45@PURE_QUANTA.Q_CAP(CHIPS)':
 'A': CDS_PINID='A';
NODE_NAME     PC450_P1_1 1
 '@S9S_MB_2U_LIB.S9S_MB_2U(SCH_1):PAGE279_I53@PURE_QUANTA.Q_CAP(CHIPS)':
 'A': CDS_PINID='A';
NODE_NAME     PC461 1
 '@S9S_MB_2U_LIB.S9S_MB_2U(SCH_1):PAGE279_I70@PURE_QUANTA.Q_CAPP(CHIPS)':
 'A': CDS_PINID='A';
NODE_NAME     PC430 1
 '@S9S_MB_2U_LIB.S9S_MB_2U(SCH_1):PAGE280_I26@PURE_QUANTA.Q_CAP(CHIPS)':
 'A': CDS_PINID='A';
NODE_NAME     PC433 1
 '@S9S_MB_2U_LIB.S9S_MB_2U(SCH_1):PAGE280_I28@PURE_QUANTA.Q_CAP(CHIPS)':
 'A': CDS_PINID='A';
NODE_NAME     PC375 1
 '@S9S_MB_2U_LIB.S9S_MB_2U(SCH_1):PAGE283_I22@PURE_QUANTA.Q_CAP(CHIPS)':
 'A': CDS_PINID='A';
NODE_NAME     PC442_P1_1 1
 '@S9S_MB_2U_LIB.S9S_MB_2U(SCH_1):PAGE279_I40@PURE_QUANTA.Q_CAP(CHIPS)':
 'A': CDS_PINID='A';
NODE_NAME     PC1282 1
 '@S9S_MB_2U_LIB.S9S_MB_2U(SCH_1):PAGE286_I16@PURE_QUANTA.Q_CAP(CHIPS)':
 'A': CDS_PINID='A';
NODE_NAME     PU17 25_29
 '@S9S_MB_2U_LIB.S9S_MB_2U(SCH_1):PAGE283_I10@PURE_QUANTA.ISL99390FRZTR5935(CHIPS)':
 'VIN1': CDS_PINID='VIN1';
NODE_NAME     PU17 30
 '@S9S_MB_2U_LIB.S9S_MB_2U(SCH_1):PAGE283_I10@PURE_QUANTA.ISL99390FRZTR5935(CHIPS)':
 'VIN2': CDS_PINID='VIN2';
NODE_NAME     PC1280 1
 '@S9S_MB_2U_LIB.S9S_MB_2U(SCH_1):PAGE286_I9@PURE_QUANTA.Q_CAP(CHIPS)':
 'A': CDS_PINID='A';
NODE_NAME     PU82 3
 '@S9S_MB_2U_LIB.S9S_MB_2U(SCH_1):PAGE286_I20@PURE_QUANTA.RS53317LR(CHIPS)':
 'VIN': CDS_PINID='VIN';
NODE_NAME     PC378 1
 '@S9S_MB_2U_LIB.S9S_MB_2U(SCH_1):PAGE283_I24@PURE_QUANTA.Q_CAP(CHIPS)':
 'A': CDS_PINID='A';
NODE_NAME     PL23 2
 '@S9S_MB_2U_LIB.S9S_MB_2U(SCH_1):PAGE279_I78@PURE_QUANTA.Q_INDUCTOR(CHIPS)':
 '2': CDS_PINID='\2\';
NODE_NAME     PC1281 1
 '@S9S_MB_2U_LIB.S9S_MB_2U(SCH_1):PAGE286_I14@PURE_QUANTA.Q_CAP(CHIPS)':
 'A': CDS_PINID='A';
NET_NAME
'SW_P12V_PVCCIN_CPU0_FLT'
 '@S9S_MB_2U_LIB.S9S_MB_2U(SCH_1):SW_P12V_PVCCIN_CPU0_FLT':
 C_SIGNAL='@s9s_mb_2u_lib.s9s_mb_2u(sch_1):sw_p12v_pvccin_cpu0_flt',
 CDS_GLOBAL_NET='TRUE';
NODE_NAME     PC298_P0_2 1
 '@S9S_MB_2U_LIB.S9S_MB_2U(SCH_1):PAGE253_I22@PURE_QUANTA.Q_CAP(CHIPS)':
 'A': CDS_PINID='A';
NODE_NAME     PC304_P0_2 1
 '@S9S_MB_2U_LIB.S9S_MB_2U(SCH_1):PAGE253_I24@PURE_QUANTA.Q_CAP(CHIPS)':
 'A': CDS_PINID='A';
NODE_NAME     PU13_P0_1 25_29
 '@S9S_MB_2U_LIB.S9S_MB_2U(SCH_1):PAGE253_I40@PURE_QUANTA.ISL99390FRZTR5935(CHIPS)':
 'VIN1': CDS_PINID='VIN1';
NODE_NAME     PU13_P0_1 30
 '@S9S_MB_2U_LIB.S9S_MB_2U(SCH_1):PAGE253_I40@PURE_QUANTA.ISL99390FRZTR5935(CHIPS)':
 'VIN2': CDS_PINID='VIN2';
NODE_NAME     PC306_P0_2 1
 '@S9S_MB_2U_LIB.S9S_MB_2U(SCH_1):PAGE253_I54@PURE_QUANTA.Q_CAP(CHIPS)':
 'A': CDS_PINID='A';
NODE_NAME     PU10_P0_4 25_29
 '@S9S_MB_2U_LIB.S9S_MB_2U(SCH_1):PAGE254_I13@PURE_QUANTA.ISL99390FRZTR5935(CHIPS)':
 'VIN1': CDS_PINID='VIN1';
NODE_NAME     PU10_P0_4 30
 '@S9S_MB_2U_LIB.S9S_MB_2U(SCH_1):PAGE254_I13@PURE_QUANTA.ISL99390FRZTR5935(CHIPS)':
 'VIN2': CDS_PINID='VIN2';
NODE_NAME     PC274_P0_4 1
 '@S9S_MB_2U_LIB.S9S_MB_2U(SCH_1):PAGE254_I35@PURE_QUANTA.Q_CAP(CHIPS)':
 'A': CDS_PINID='A';
NODE_NAME     PC276_P0_4 1
 '@S9S_MB_2U_LIB.S9S_MB_2U(SCH_1):PAGE254_I38@PURE_QUANTA.Q_CAP(CHIPS)':
 'A': CDS_PINID='A';
NODE_NAME     PC280_P0_4 1
 '@S9S_MB_2U_LIB.S9S_MB_2U(SCH_1):PAGE254_I39@PURE_QUANTA.Q_CAP(CHIPS)':
 'A': CDS_PINID='A';
NODE_NAME     PC282_P0_4 1
 '@S9S_MB_2U_LIB.S9S_MB_2U(SCH_1):PAGE254_I40@PURE_QUANTA.Q_CAP(CHIPS)':
 'A': CDS_PINID='A';
NODE_NAME     PC275_P0_3 1
 '@S9S_MB_2U_LIB.S9S_MB_2U(SCH_1):PAGE254_I48@PURE_QUANTA.Q_CAP(CHIPS)':
 'A': CDS_PINID='A';
NODE_NAME     PC281_P0_3 1
 '@S9S_MB_2U_LIB.S9S_MB_2U(SCH_1):PAGE254_I53@PURE_QUANTA.Q_CAP(CHIPS)':
 'A': CDS_PINID='A';
NODE_NAME     PC285_P0_3 1
 '@S9S_MB_2U_LIB.S9S_MB_2U(SCH_1):PAGE254_I56@PURE_QUANTA.Q_CAP(CHIPS)':
 'A': CDS_PINID='A';
NODE_NAME     PU8_P0_6 25_29
 '@S9S_MB_2U_LIB.S9S_MB_2U(SCH_1):PAGE255_I12@PURE_QUANTA.ISL99390FRZTR5935(CHIPS)':
 'VIN1': CDS_PINID='VIN1';
NODE_NAME     PU8_P0_6 30
 '@S9S_MB_2U_LIB.S9S_MB_2U(SCH_1):PAGE255_I12@PURE_QUANTA.ISL99390FRZTR5935(CHIPS)':
 'VIN2': CDS_PINID='VIN2';
NODE_NAME     PC252_P0_6 1
 '@S9S_MB_2U_LIB.S9S_MB_2U(SCH_1):PAGE255_I34@PURE_QUANTA.Q_CAP(CHIPS)':
 'A': CDS_PINID='A';
NODE_NAME     PC254_P0_6 1
 '@S9S_MB_2U_LIB.S9S_MB_2U(SCH_1):PAGE255_I37@PURE_QUANTA.Q_CAP(CHIPS)':
 'A': CDS_PINID='A';
NODE_NAME     PC258_P0_6 1
 '@S9S_MB_2U_LIB.S9S_MB_2U(SCH_1):PAGE255_I38@PURE_QUANTA.Q_CAP(CHIPS)':
 'A': CDS_PINID='A';
NODE_NAME     PC260_P0_6 1
 '@S9S_MB_2U_LIB.S9S_MB_2U(SCH_1):PAGE255_I39@PURE_QUANTA.Q_CAP(CHIPS)':
 'A': CDS_PINID='A';
NODE_NAME     PU6_P0_8 25_29
 '@S9S_MB_2U_LIB.S9S_MB_2U(SCH_1):PAGE256_I2@PURE_QUANTA.ISL99390FRZTR5935(CHIPS)':
 'VIN1': CDS_PINID='VIN1';
NODE_NAME     PU6_P0_8 30
 '@S9S_MB_2U_LIB.S9S_MB_2U(SCH_1):PAGE256_I2@PURE_QUANTA.ISL99390FRZTR5935(CHIPS)':
 'VIN2': CDS_PINID='VIN2';
NODE_NAME     PC232_P0_8 1
 '@S9S_MB_2U_LIB.S9S_MB_2U(SCH_1):PAGE256_I20@PURE_QUANTA.Q_CAP(CHIPS)':
 'A': CDS_PINID='A';
NODE_NAME     PC241_P0_7 1
 '@S9S_MB_2U_LIB.S9S_MB_2U(SCH_1):PAGE256_I64@PURE_QUANTA.Q_CAP(CHIPS)':
 'A': CDS_PINID='A';
NODE_NAME     PC1248 1
 '@S9S_MB_2U_LIB.S9S_MB_2U(SCH_1):PAGE267_I16@PURE_QUANTA.Q_CAP(CHIPS)':
 'A': CDS_PINID='A';
NODE_NAME     PC1249 1
 '@S9S_MB_2U_LIB.S9S_MB_2U(SCH_1):PAGE267_I17@PURE_QUANTA.Q_CAP(CHIPS)':
 'A': CDS_PINID='A';
NODE_NAME     PC305_P0_1 1
 '@S9S_MB_2U_LIB.S9S_MB_2U(SCH_1):PAGE253_I50@PURE_QUANTA.Q_CAP(CHIPS)':
 'A': CDS_PINID='A';
NODE_NAME     PC315 1
 '@S9S_MB_2U_LIB.S9S_MB_2U(SCH_1):PAGE253_I91@PURE_QUANTA.Q_CAPP(CHIPS)':
 'A': CDS_PINID='A';
NODE_NAME     PC318 1
 '@S9S_MB_2U_LIB.S9S_MB_2U(SCH_1):PAGE253_I92@PURE_QUANTA.Q_CAPP(CHIPS)':
 'A': CDS_PINID='A';
NODE_NAME     PC2345 1
 '@S9S_MB_2U_LIB.S9S_MB_2U(SCH_1):PAGE253_I95@PURE_QUANTA.Q_CAPP(CHIPS)':
 'A': CDS_PINID='A';
NODE_NAME     PU11_P0_3 25_29
 '@S9S_MB_2U_LIB.S9S_MB_2U(SCH_1):PAGE254_I20@PURE_QUANTA.ISL99390FRZTR5935(CHIPS)':
 'VIN1': CDS_PINID='VIN1';
NODE_NAME     PU11_P0_3 30
 '@S9S_MB_2U_LIB.S9S_MB_2U(SCH_1):PAGE254_I20@PURE_QUANTA.ISL99390FRZTR5935(CHIPS)':
 'VIN2': CDS_PINID='VIN2';
NODE_NAME     PC284_P0_4 1
 '@S9S_MB_2U_LIB.S9S_MB_2U(SCH_1):PAGE254_I43@PURE_QUANTA.Q_CAP(CHIPS)':
 'A': CDS_PINID='A';
NODE_NAME     PC277_P0_3 1
 '@S9S_MB_2U_LIB.S9S_MB_2U(SCH_1):PAGE254_I52@PURE_QUANTA.Q_CAP(CHIPS)':
 'A': CDS_PINID='A';
NODE_NAME     PC283_P0_3 1
 '@S9S_MB_2U_LIB.S9S_MB_2U(SCH_1):PAGE254_I54@PURE_QUANTA.Q_CAP(CHIPS)':
 'A': CDS_PINID='A';
NODE_NAME     PC262_P0_6 1
 '@S9S_MB_2U_LIB.S9S_MB_2U(SCH_1):PAGE255_I43@PURE_QUANTA.Q_CAP(CHIPS)':
 'A': CDS_PINID='A';
NODE_NAME     PC253_P0_5 1
 '@S9S_MB_2U_LIB.S9S_MB_2U(SCH_1):PAGE255_I48@PURE_QUANTA.Q_CAP(CHIPS)':
 'A': CDS_PINID='A';
NODE_NAME     PC255_P0_5 1
 '@S9S_MB_2U_LIB.S9S_MB_2U(SCH_1):PAGE255_I52@PURE_QUANTA.Q_CAP(CHIPS)':
 'A': CDS_PINID='A';
NODE_NAME     PC259_P0_5 1
 '@S9S_MB_2U_LIB.S9S_MB_2U(SCH_1):PAGE255_I53@PURE_QUANTA.Q_CAP(CHIPS)':
 'A': CDS_PINID='A';
NODE_NAME     PC261_P0_5 1
 '@S9S_MB_2U_LIB.S9S_MB_2U(SCH_1):PAGE255_I54@PURE_QUANTA.Q_CAP(CHIPS)':
 'A': CDS_PINID='A';
NODE_NAME     PC263_P0_5 1
 '@S9S_MB_2U_LIB.S9S_MB_2U(SCH_1):PAGE255_I56@PURE_QUANTA.Q_CAP(CHIPS)':
 'A': CDS_PINID='A';
NODE_NAME     PU9_P0_5 25_29
 '@S9S_MB_2U_LIB.S9S_MB_2U(SCH_1):PAGE255_I66@PURE_QUANTA.ISL99390FRZTR5935(CHIPS)':
 'VIN1': CDS_PINID='VIN1';
NODE_NAME     PU9_P0_5 30
 '@S9S_MB_2U_LIB.S9S_MB_2U(SCH_1):PAGE255_I66@PURE_QUANTA.ISL99390FRZTR5935(CHIPS)':
 'VIN2': CDS_PINID='VIN2';
NODE_NAME     PC230_P0_8 1
 '@S9S_MB_2U_LIB.S9S_MB_2U(SCH_1):PAGE256_I17@PURE_QUANTA.Q_CAP(CHIPS)':
 'A': CDS_PINID='A';
NODE_NAME     PC236_P0_8 1
 '@S9S_MB_2U_LIB.S9S_MB_2U(SCH_1):PAGE256_I21@PURE_QUANTA.Q_CAP(CHIPS)':
 'A': CDS_PINID='A';
NODE_NAME     PU7_P0_7 25_29
 '@S9S_MB_2U_LIB.S9S_MB_2U(SCH_1):PAGE256_I32@PURE_QUANTA.ISL99390FRZTR5935(CHIPS)':
 'VIN1': CDS_PINID='VIN1';
NODE_NAME     PU7_P0_7 30
 '@S9S_MB_2U_LIB.S9S_MB_2U(SCH_1):PAGE256_I32@PURE_QUANTA.ISL99390FRZTR5935(CHIPS)':
 'VIN2': CDS_PINID='VIN2';
NODE_NAME     PC231_P0_7 1
 '@S9S_MB_2U_LIB.S9S_MB_2U(SCH_1):PAGE256_I41@PURE_QUANTA.Q_CAP(CHIPS)':
 'A': CDS_PINID='A';
NODE_NAME     PC233_P0_7 1
 '@S9S_MB_2U_LIB.S9S_MB_2U(SCH_1):PAGE256_I42@PURE_QUANTA.Q_CAP(CHIPS)':
 'A': CDS_PINID='A';
NODE_NAME     PC237_P0_7 1
 '@S9S_MB_2U_LIB.S9S_MB_2U(SCH_1):PAGE256_I43@PURE_QUANTA.Q_CAP(CHIPS)':
 'A': CDS_PINID='A';
NODE_NAME     PC238_P0_8 1
 '@S9S_MB_2U_LIB.S9S_MB_2U(SCH_1):PAGE256_I47@PURE_QUANTA.Q_CAP(CHIPS)':
 'A': CDS_PINID='A';
NODE_NAME     PC240_P0_8 1
 '@S9S_MB_2U_LIB.S9S_MB_2U(SCH_1):PAGE256_I48@PURE_QUANTA.Q_CAP(CHIPS)':
 'A': CDS_PINID='A';
NODE_NAME     PC239_P0_7 1
 '@S9S_MB_2U_LIB.S9S_MB_2U(SCH_1):PAGE256_I63@PURE_QUANTA.Q_CAP(CHIPS)':
 'A': CDS_PINID='A';
NODE_NAME     PC296_P0_2 1
 '@S9S_MB_2U_LIB.S9S_MB_2U(SCH_1):PAGE253_I19@PURE_QUANTA.Q_CAP(CHIPS)':
 'A': CDS_PINID='A';
NODE_NAME     PC303_P0_1 1
 '@S9S_MB_2U_LIB.S9S_MB_2U(SCH_1):PAGE253_I49@PURE_QUANTA.Q_CAP(CHIPS)':
 'A': CDS_PINID='A';
NODE_NAME     PC307_P0_1 1
 '@S9S_MB_2U_LIB.S9S_MB_2U(SCH_1):PAGE253_I75@PURE_QUANTA.Q_CAP(CHIPS)':
 'A': CDS_PINID='A';
NODE_NAME     PR2554 2
 '@S9S_MB_2U_LIB.S9S_MB_2U(SCH_1):PAGE253_I81@PURE_QUANTA.Q_RES(CHIPS)':
 'B': CDS_PINID='B';
NODE_NAME     PU12_P0_2 25_29
 '@S9S_MB_2U_LIB.S9S_MB_2U(SCH_1):PAGE253_I6@PURE_QUANTA.ISL99390FRZTR5935(CHIPS)':
 'VIN1': CDS_PINID='VIN1';
NODE_NAME     PU12_P0_2 30
 '@S9S_MB_2U_LIB.S9S_MB_2U(SCH_1):PAGE253_I6@PURE_QUANTA.ISL99390FRZTR5935(CHIPS)':
 'VIN2': CDS_PINID='VIN2';
NODE_NAME     PC302_P0_2 1
 '@S9S_MB_2U_LIB.S9S_MB_2U(SCH_1):PAGE253_I23@PURE_QUANTA.Q_CAP(CHIPS)':
 'A': CDS_PINID='A';
NODE_NAME     PC297_P0_1 1
 '@S9S_MB_2U_LIB.S9S_MB_2U(SCH_1):PAGE253_I44@PURE_QUANTA.Q_CAP(CHIPS)':
 'A': CDS_PINID='A';
NODE_NAME     PC299_P0_1 1
 '@S9S_MB_2U_LIB.S9S_MB_2U(SCH_1):PAGE253_I47@PURE_QUANTA.Q_CAP(CHIPS)':
 'A': CDS_PINID='A';
NODE_NAME     PL15 2
 '@S9S_MB_2U_LIB.S9S_MB_2U(SCH_1):PAGE253_I82@PURE_QUANTA.Q_INDUCTOR(CHIPS)':
 '2': CDS_PINID='\2\';
NODE_NAME     PC321 1
 '@S9S_MB_2U_LIB.S9S_MB_2U(SCH_1):PAGE253_I93@PURE_QUANTA.Q_CAPP(CHIPS)':
 'A': CDS_PINID='A';
NODE_NAME     PC324 1
 '@S9S_MB_2U_LIB.S9S_MB_2U(SCH_1):PAGE253_I94@PURE_QUANTA.Q_CAPP(CHIPS)':
 'A': CDS_PINID='A';
NODE_NAME     PC831 1
 '@S9S_MB_2U_LIB.S9S_MB_2U(SCH_1):PAGE267_I7@PURE_QUANTA.Q_CAP(CHIPS)':
 'A': CDS_PINID='A';
NODE_NAME     PC1247 1
 '@S9S_MB_2U_LIB.S9S_MB_2U(SCH_1):PAGE267_I10@PURE_QUANTA.Q_CAP(CHIPS)':
 'A': CDS_PINID='A';
NODE_NAME     PU79 10
 '@S9S_MB_2U_LIB.S9S_MB_2U(SCH_1):PAGE267_I19@PURE_QUANTA.RS53318LR(CHIPS)':
 'VIN1': CDS_PINID='VIN1';
NODE_NAME     PU79 21
 '@S9S_MB_2U_LIB.S9S_MB_2U(SCH_1):PAGE267_I19@PURE_QUANTA.RS53318LR(CHIPS)':
 'VIN2': CDS_PINID='VIN2';
NET_NAME
'SW_P12V_PVCCIN_CPU1_FLT'
 '@S9S_MB_2U_LIB.S9S_MB_2U(SCH_1):SW_P12V_PVCCIN_CPU1_FLT':
 C_SIGNAL='@s9s_mb_2u_lib.s9s_mb_2u(sch_1):sw_p12v_pvccin_cpu1_flt',
 CDS_GLOBAL_NET='TRUE';
NODE_NAME     PC566_P1_2 1
 '@S9S_MB_2U_LIB.S9S_MB_2U(SCH_1):PAGE271_I22@PURE_QUANTA.Q_CAP(CHIPS)':
 'A': CDS_PINID='A';
NODE_NAME     PL32 2
 '@S9S_MB_2U_LIB.S9S_MB_2U(SCH_1):PAGE271_I83@PURE_QUANTA.Q_INDUCTOR(CHIPS)':
 '2': CDS_PINID='\2\';
NODE_NAME     PC529_P1_4 1
 '@S9S_MB_2U_LIB.S9S_MB_2U(SCH_1):PAGE272_I35@PURE_QUANTA.Q_CAP(CHIPS)':
 'A': CDS_PINID='A';
NODE_NAME     PC533_P1_4 1
 '@S9S_MB_2U_LIB.S9S_MB_2U(SCH_1):PAGE272_I36@PURE_QUANTA.Q_CAP(CHIPS)':
 'A': CDS_PINID='A';
NODE_NAME     PC535_P1_4 1
 '@S9S_MB_2U_LIB.S9S_MB_2U(SCH_1):PAGE272_I41@PURE_QUANTA.Q_CAP(CHIPS)':
 'A': CDS_PINID='A';
NODE_NAME     PC537_P1_4 1
 '@S9S_MB_2U_LIB.S9S_MB_2U(SCH_1):PAGE272_I42@PURE_QUANTA.Q_CAP(CHIPS)':
 'A': CDS_PINID='A';
NODE_NAME     PC528_P1_3 1
 '@S9S_MB_2U_LIB.S9S_MB_2U(SCH_1):PAGE272_I48@PURE_QUANTA.Q_CAP(CHIPS)':
 'A': CDS_PINID='A';
NODE_NAME     PC530_P1_3 1
 '@S9S_MB_2U_LIB.S9S_MB_2U(SCH_1):PAGE272_I49@PURE_QUANTA.Q_CAP(CHIPS)':
 'A': CDS_PINID='A';
NODE_NAME     PC536_P1_3 1
 '@S9S_MB_2U_LIB.S9S_MB_2U(SCH_1):PAGE272_I54@PURE_QUANTA.Q_CAP(CHIPS)':
 'A': CDS_PINID='A';
NODE_NAME     PU26_P1_5 25_29
 '@S9S_MB_2U_LIB.S9S_MB_2U(SCH_1):PAGE273_I23@PURE_QUANTA.ISL99390FRZTR5935(CHIPS)':
 'VIN1': CDS_PINID='VIN1';
NODE_NAME     PU26_P1_5 30
 '@S9S_MB_2U_LIB.S9S_MB_2U(SCH_1):PAGE273_I23@PURE_QUANTA.ISL99390FRZTR5935(CHIPS)':
 'VIN2': CDS_PINID='VIN2';
NODE_NAME     PC505_P1_6 1
 '@S9S_MB_2U_LIB.S9S_MB_2U(SCH_1):PAGE273_I29@PURE_QUANTA.Q_CAP(CHIPS)':
 'A': CDS_PINID='A';
NODE_NAME     PC507_P1_6 1
 '@S9S_MB_2U_LIB.S9S_MB_2U(SCH_1):PAGE273_I31@PURE_QUANTA.Q_CAP(CHIPS)':
 'A': CDS_PINID='A';
NODE_NAME     PC513_P1_6 1
 '@S9S_MB_2U_LIB.S9S_MB_2U(SCH_1):PAGE273_I34@PURE_QUANTA.Q_CAP(CHIPS)':
 'A': CDS_PINID='A';
NODE_NAME     PC506_P1_5 1
 '@S9S_MB_2U_LIB.S9S_MB_2U(SCH_1):PAGE273_I45@PURE_QUANTA.Q_CAP(CHIPS)':
 'A': CDS_PINID='A';
NODE_NAME     PC512_P1_5 1
 '@S9S_MB_2U_LIB.S9S_MB_2U(SCH_1):PAGE273_I50@PURE_QUANTA.Q_CAP(CHIPS)':
 'A': CDS_PINID='A';
NODE_NAME     PC489_P1_8 1
 '@S9S_MB_2U_LIB.S9S_MB_2U(SCH_1):PAGE274_I28@PURE_QUANTA.Q_CAP(CHIPS)':
 'A': CDS_PINID='A';
NODE_NAME     PC484_P1_7 1
 '@S9S_MB_2U_LIB.S9S_MB_2U(SCH_1):PAGE274_I37@PURE_QUANTA.Q_CAP(CHIPS)':
 'A': CDS_PINID='A';
NODE_NAME     PC486_P1_7 1
 '@S9S_MB_2U_LIB.S9S_MB_2U(SCH_1):PAGE274_I40@PURE_QUANTA.Q_CAP(CHIPS)':
 'A': CDS_PINID='A';
NODE_NAME     PC490_P1_7 1
 '@S9S_MB_2U_LIB.S9S_MB_2U(SCH_1):PAGE274_I41@PURE_QUANTA.Q_CAP(CHIPS)':
 'A': CDS_PINID='A';
NODE_NAME     PC491_P1_8 1
 '@S9S_MB_2U_LIB.S9S_MB_2U(SCH_1):PAGE274_I46@PURE_QUANTA.Q_CAP(CHIPS)':
 'A': CDS_PINID='A';
NODE_NAME     PC493_P1_8 1
 '@S9S_MB_2U_LIB.S9S_MB_2U(SCH_1):PAGE274_I47@PURE_QUANTA.Q_CAP(CHIPS)':
 'A': CDS_PINID='A';
NODE_NAME     PC1260 1
 '@S9S_MB_2U_LIB.S9S_MB_2U(SCH_1):PAGE285_I15@PURE_QUANTA.Q_CAP(CHIPS)':
 'A': CDS_PINID='A';
NODE_NAME     PC568_P1_2 1
 '@S9S_MB_2U_LIB.S9S_MB_2U(SCH_1):PAGE271_I24@PURE_QUANTA.Q_CAP(CHIPS)':
 'A': CDS_PINID='A';
NODE_NAME     PC563_P1_1 1
 '@S9S_MB_2U_LIB.S9S_MB_2U(SCH_1):PAGE271_I47@PURE_QUANTA.Q_CAP(CHIPS)':
 'A': CDS_PINID='A';
NODE_NAME     PC567_P1_1 1
 '@S9S_MB_2U_LIB.S9S_MB_2U(SCH_1):PAGE271_I48@PURE_QUANTA.Q_CAP(CHIPS)':
 'A': CDS_PINID='A';
NODE_NAME     PC569_P1_1 1
 '@S9S_MB_2U_LIB.S9S_MB_2U(SCH_1):PAGE271_I50@PURE_QUANTA.Q_CAP(CHIPS)':
 'A': CDS_PINID='A';
NODE_NAME     PR2556 2
 '@S9S_MB_2U_LIB.S9S_MB_2U(SCH_1):PAGE271_I82@PURE_QUANTA.Q_RES(CHIPS)':
 'B': CDS_PINID='B';
NODE_NAME     PU27_P1_4 25_29
 '@S9S_MB_2U_LIB.S9S_MB_2U(SCH_1):PAGE272_I10@PURE_QUANTA.ISL99390FRZTR5935(CHIPS)':
 'VIN1': CDS_PINID='VIN1';
NODE_NAME     PU27_P1_4 30
 '@S9S_MB_2U_LIB.S9S_MB_2U(SCH_1):PAGE272_I10@PURE_QUANTA.ISL99390FRZTR5935(CHIPS)':
 'VIN2': CDS_PINID='VIN2';
NODE_NAME     PC527_P1_4 1
 '@S9S_MB_2U_LIB.S9S_MB_2U(SCH_1):PAGE272_I33@PURE_QUANTA.Q_CAP(CHIPS)':
 'A': CDS_PINID='A';
NODE_NAME     PC534_P1_3 1
 '@S9S_MB_2U_LIB.S9S_MB_2U(SCH_1):PAGE272_I50@PURE_QUANTA.Q_CAP(CHIPS)':
 'A': CDS_PINID='A';
NODE_NAME     PC538_P1_3 1
 '@S9S_MB_2U_LIB.S9S_MB_2U(SCH_1):PAGE272_I55@PURE_QUANTA.Q_CAP(CHIPS)':
 'A': CDS_PINID='A';
NODE_NAME     PU28_P1_3 25_29
 '@S9S_MB_2U_LIB.S9S_MB_2U(SCH_1):PAGE272_I66@PURE_QUANTA.ISL99390FRZTR5935(CHIPS)':
 'VIN1': CDS_PINID='VIN1';
NODE_NAME     PU28_P1_3 30
 '@S9S_MB_2U_LIB.S9S_MB_2U(SCH_1):PAGE272_I66@PURE_QUANTA.ISL99390FRZTR5935(CHIPS)':
 'VIN2': CDS_PINID='VIN2';
NODE_NAME     PU25_P1_6 25_29
 '@S9S_MB_2U_LIB.S9S_MB_2U(SCH_1):PAGE273_I16@PURE_QUANTA.ISL99390FRZTR5935(CHIPS)':
 'VIN1': CDS_PINID='VIN1';
NODE_NAME     PU25_P1_6 30
 '@S9S_MB_2U_LIB.S9S_MB_2U(SCH_1):PAGE273_I16@PURE_QUANTA.ISL99390FRZTR5935(CHIPS)':
 'VIN2': CDS_PINID='VIN2';
NODE_NAME     PC511_P1_6 1
 '@S9S_MB_2U_LIB.S9S_MB_2U(SCH_1):PAGE273_I33@PURE_QUANTA.Q_CAP(CHIPS)':
 'A': CDS_PINID='A';
NODE_NAME     PC515_P1_6 1
 '@S9S_MB_2U_LIB.S9S_MB_2U(SCH_1):PAGE273_I35@PURE_QUANTA.Q_CAP(CHIPS)':
 'A': CDS_PINID='A';
NODE_NAME     PC508_P1_5 1
 '@S9S_MB_2U_LIB.S9S_MB_2U(SCH_1):PAGE273_I46@PURE_QUANTA.Q_CAP(CHIPS)':
 'A': CDS_PINID='A';
NODE_NAME     PC514_P1_5 1
 '@S9S_MB_2U_LIB.S9S_MB_2U(SCH_1):PAGE273_I51@PURE_QUANTA.Q_CAP(CHIPS)':
 'A': CDS_PINID='A';
NODE_NAME     PC516_P1_5 1
 '@S9S_MB_2U_LIB.S9S_MB_2U(SCH_1):PAGE273_I52@PURE_QUANTA.Q_CAP(CHIPS)':
 'A': CDS_PINID='A';
NODE_NAME     PU23_P1_8 25_29
 '@S9S_MB_2U_LIB.S9S_MB_2U(SCH_1):PAGE274_I11@PURE_QUANTA.ISL99390FRZTR5935(CHIPS)':
 'VIN1': CDS_PINID='VIN1';
NODE_NAME     PU23_P1_8 30
 '@S9S_MB_2U_LIB.S9S_MB_2U(SCH_1):PAGE274_I11@PURE_QUANTA.ISL99390FRZTR5935(CHIPS)':
 'VIN2': CDS_PINID='VIN2';
NODE_NAME     PU24_P1_7 25_29
 '@S9S_MB_2U_LIB.S9S_MB_2U(SCH_1):PAGE274_I20@PURE_QUANTA.ISL99390FRZTR5935(CHIPS)':
 'VIN1': CDS_PINID='VIN1';
NODE_NAME     PU24_P1_7 30
 '@S9S_MB_2U_LIB.S9S_MB_2U(SCH_1):PAGE274_I20@PURE_QUANTA.ISL99390FRZTR5935(CHIPS)':
 'VIN2': CDS_PINID='VIN2';
NODE_NAME     PC483_P1_8 1
 '@S9S_MB_2U_LIB.S9S_MB_2U(SCH_1):PAGE274_I24@PURE_QUANTA.Q_CAP(CHIPS)':
 'A': CDS_PINID='A';
NODE_NAME     PC485_P1_8 1
 '@S9S_MB_2U_LIB.S9S_MB_2U(SCH_1):PAGE274_I27@PURE_QUANTA.Q_CAP(CHIPS)':
 'A': CDS_PINID='A';
NODE_NAME     PC492_P1_7 1
 '@S9S_MB_2U_LIB.S9S_MB_2U(SCH_1):PAGE274_I61@PURE_QUANTA.Q_CAP(CHIPS)':
 'A': CDS_PINID='A';
NODE_NAME     PC494_P1_7 1
 '@S9S_MB_2U_LIB.S9S_MB_2U(SCH_1):PAGE274_I62@PURE_QUANTA.Q_CAP(CHIPS)':
 'A': CDS_PINID='A';
NODE_NAME     PC1262 1
 '@S9S_MB_2U_LIB.S9S_MB_2U(SCH_1):PAGE285_I17@PURE_QUANTA.Q_CAP(CHIPS)':
 'A': CDS_PINID='A';
NODE_NAME     PC560_P1_2 1
 '@S9S_MB_2U_LIB.S9S_MB_2U(SCH_1):PAGE271_I19@PURE_QUANTA.Q_CAP(CHIPS)':
 'A': CDS_PINID='A';
NODE_NAME     PC562_P1_2 1
 '@S9S_MB_2U_LIB.S9S_MB_2U(SCH_1):PAGE271_I21@PURE_QUANTA.Q_CAP(CHIPS)':
 'A': CDS_PINID='A';
NODE_NAME     PU31_P1_1 25_29
 '@S9S_MB_2U_LIB.S9S_MB_2U(SCH_1):PAGE271_I40@PURE_QUANTA.ISL99390FRZTR5935(CHIPS)':
 'VIN1': CDS_PINID='VIN1';
NODE_NAME     PU31_P1_1 30
 '@S9S_MB_2U_LIB.S9S_MB_2U(SCH_1):PAGE271_I40@PURE_QUANTA.ISL99390FRZTR5935(CHIPS)':
 'VIN2': CDS_PINID='VIN2';
NODE_NAME     PC582 1
 '@S9S_MB_2U_LIB.S9S_MB_2U(SCH_1):PAGE271_I87@PURE_QUANTA.Q_CAPP(CHIPS)':
 'A': CDS_PINID='A';
NODE_NAME     PC2346 1
 '@S9S_MB_2U_LIB.S9S_MB_2U(SCH_1):PAGE271_I96@PURE_QUANTA.Q_CAPP(CHIPS)':
 'A': CDS_PINID='A';
NODE_NAME     PU80 10
 '@S9S_MB_2U_LIB.S9S_MB_2U(SCH_1):PAGE285_I25@PURE_QUANTA.RS53318LR(CHIPS)':
 'VIN1': CDS_PINID='VIN1';
NODE_NAME     PU80 21
 '@S9S_MB_2U_LIB.S9S_MB_2U(SCH_1):PAGE285_I25@PURE_QUANTA.RS53318LR(CHIPS)':
 'VIN2': CDS_PINID='VIN2';
NODE_NAME     PU30_P1_2 25_29
 '@S9S_MB_2U_LIB.S9S_MB_2U(SCH_1):PAGE271_I7@PURE_QUANTA.ISL99390FRZTR5935(CHIPS)':
 'VIN1': CDS_PINID='VIN1';
NODE_NAME     PU30_P1_2 30
 '@S9S_MB_2U_LIB.S9S_MB_2U(SCH_1):PAGE271_I7@PURE_QUANTA.ISL99390FRZTR5935(CHIPS)':
 'VIN2': CDS_PINID='VIN2';
NODE_NAME     PC561_P1_1 1
 '@S9S_MB_2U_LIB.S9S_MB_2U(SCH_1):PAGE271_I44@PURE_QUANTA.Q_CAP(CHIPS)':
 'A': CDS_PINID='A';
NODE_NAME     PC570_P1_2 1
 '@S9S_MB_2U_LIB.S9S_MB_2U(SCH_1):PAGE271_I53@PURE_QUANTA.Q_CAP(CHIPS)':
 'A': CDS_PINID='A';
NODE_NAME     PC571_P1_1 1
 '@S9S_MB_2U_LIB.S9S_MB_2U(SCH_1):PAGE271_I76@PURE_QUANTA.Q_CAP(CHIPS)':
 'A': CDS_PINID='A';
NODE_NAME     PC579 1
 '@S9S_MB_2U_LIB.S9S_MB_2U(SCH_1):PAGE271_I86@PURE_QUANTA.Q_CAPP(CHIPS)':
 'A': CDS_PINID='A';
NODE_NAME     PC585 1
 '@S9S_MB_2U_LIB.S9S_MB_2U(SCH_1):PAGE271_I92@PURE_QUANTA.Q_CAPP(CHIPS)':
 'A': CDS_PINID='A';
NODE_NAME     PC588 1
 '@S9S_MB_2U_LIB.S9S_MB_2U(SCH_1):PAGE271_I94@PURE_QUANTA.Q_CAPP(CHIPS)':
 'A': CDS_PINID='A';
NODE_NAME     PC1261 1
 '@S9S_MB_2U_LIB.S9S_MB_2U(SCH_1):PAGE285_I16@PURE_QUANTA.Q_CAP(CHIPS)':
 'A': CDS_PINID='A';
NODE_NAME     PC1259 1
 '@S9S_MB_2U_LIB.S9S_MB_2U(SCH_1):PAGE285_I8@PURE_QUANTA.Q_CAP(CHIPS)':
 'A': CDS_PINID='A';
NET_NAME
'SW_P1V05_PCH_AUX_BST'
 '@S9S_MB_2U_LIB.S9S_MB_2U(SCH_1):SW_P1V05_PCH_AUX_BST':
 C_SIGNAL='@s9s_mb_2u_lib.s9s_mb_2u(sch_1):sw_p1v05_pch_aux_bst';
NODE_NAME     PC1222 1
 '@S9S_MB_2U_LIB.S9S_MB_2U(SCH_1):PAGE248_I31@PURE_QUANTA.Q_CAP(CHIPS)':
 'A': CDS_PINID='A';
NODE_NAME     PU73 1
 '@S9S_MB_2U_LIB.S9S_MB_2U(SCH_1):PAGE248_I11@PURE_QUANTA.RS53319LR(CHIPS)':
 'BST': CDS_PINID='BST';
NET_NAME
'SW_P1V05_PCH_AUX_SW'
 '@S9S_MB_2U_LIB.S9S_MB_2U(SCH_1):SW_P1V05_PCH_AUX_SW':
 C_SIGNAL='@s9s_mb_2u_lib.s9s_mb_2u(sch_1):sw_p1v05_pch_aux_sw';
NODE_NAME     PC1222 2
 '@S9S_MB_2U_LIB.S9S_MB_2U(SCH_1):PAGE248_I31@PURE_QUANTA.Q_CAP(CHIPS)':
 'B': CDS_PINID='B';
NODE_NAME     PL150 1
 '@S9S_MB_2U_LIB.S9S_MB_2U(SCH_1):PAGE248_I53@PURE_QUANTA.Q_INDUCTOR(CHIPS)':
 '1': CDS_PINID='\1\';
NODE_NAME     PU73 20
 '@S9S_MB_2U_LIB.S9S_MB_2U(SCH_1):PAGE248_I11@PURE_QUANTA.RS53319LR(CHIPS)':
 'SW': CDS_PINID='SW';
NET_NAME
'SW_P1V8_PCH_AUX_BST'
 '@S9S_MB_2U_LIB.S9S_MB_2U(SCH_1):SW_P1V8_PCH_AUX_BST':
 C_SIGNAL='@s9s_mb_2u_lib.s9s_mb_2u(sch_1):sw_p1v8_pch_aux_bst';
NODE_NAME     PU74 9
 '@S9S_MB_2U_LIB.S9S_MB_2U(SCH_1):PAGE249_I26@PURE_QUANTA.NB682GDZ(CHIPS)':
 'BST': CDS_PINID='BST';
NODE_NAME     PC1235 1
 '@S9S_MB_2U_LIB.S9S_MB_2U(SCH_1):PAGE249_I30@PURE_QUANTA.Q_CAP(CHIPS)':
 'A': CDS_PINID='A';
NET_NAME
'SW_P1V8_PCH_AUX_FLT'
 '@S9S_MB_2U_LIB.S9S_MB_2U(SCH_1):SW_P1V8_PCH_AUX_FLT':
 C_SIGNAL='@s9s_mb_2u_lib.s9s_mb_2u(sch_1):sw_p1v8_pch_aux_flt';
NODE_NAME     PU74 1
 '@S9S_MB_2U_LIB.S9S_MB_2U(SCH_1):PAGE249_I26@PURE_QUANTA.NB682GDZ(CHIPS)':
 'VIN': CDS_PINID='VIN';
NODE_NAME     PC1234 1
 '@S9S_MB_2U_LIB.S9S_MB_2U(SCH_1):PAGE249_I21@PURE_QUANTA.Q_CAP(CHIPS)':
 'A': CDS_PINID='A';
NODE_NAME     PL16 2
 '@S9S_MB_2U_LIB.S9S_MB_2U(SCH_1):PAGE249_I16@PURE_QUANTA.Q_INDUCTOR(CHIPS)':
 '2': CDS_PINID='\2\';
NODE_NAME     PC1232 1
 '@S9S_MB_2U_LIB.S9S_MB_2U(SCH_1):PAGE249_I19@PURE_QUANTA.Q_CAP(CHIPS)':
 'A': CDS_PINID='A';
NODE_NAME     PC1233 1
 '@S9S_MB_2U_LIB.S9S_MB_2U(SCH_1):PAGE249_I20@PURE_QUANTA.Q_CAP(CHIPS)':
 'A': CDS_PINID='A';
NET_NAME
'SW_P1V8_PCH_AUX_SW'
 '@S9S_MB_2U_LIB.S9S_MB_2U(SCH_1):SW_P1V8_PCH_AUX_SW':
 C_SIGNAL='@s9s_mb_2u_lib.s9s_mb_2u(sch_1):sw_p1v8_pch_aux_sw';
NODE_NAME     PU74 8
 '@S9S_MB_2U_LIB.S9S_MB_2U(SCH_1):PAGE249_I26@PURE_QUANTA.NB682GDZ(CHIPS)':
 'SW': CDS_PINID='SW';
NODE_NAME     PC1235 2
 '@S9S_MB_2U_LIB.S9S_MB_2U(SCH_1):PAGE249_I30@PURE_QUANTA.Q_CAP(CHIPS)':
 'B': CDS_PINID='B';
NODE_NAME     PL170 1
 '@S9S_MB_2U_LIB.S9S_MB_2U(SCH_1):PAGE249_I45@PURE_QUANTA.Q_INDUCTOR(CHIPS)':
 '1': CDS_PINID='\1\';
NET_NAME
'SW_P3V3_AUX_BOOT'
 '@S9S_MB_2U_LIB.S9S_MB_2U(SCH_1):SW_P3V3_AUX_BOOT':
 C_SIGNAL='@s9s_mb_2u_lib.s9s_mb_2u(sch_1):sw_p3v3_aux_boot';
NODE_NAME     PU9 26
 '@S9S_MB_2U_LIB.S9S_MB_2U(SCH_1):PAGE245_I95@PURE_QUANTA.IR3889MTRPBF(CHIPS)':
 'BOOT': CDS_PINID='BOOT';
NODE_NAME     PR835 1
 '@S9S_MB_2U_LIB.S9S_MB_2U(SCH_1):PAGE245_I123@PURE_QUANTA.Q_RES(CHIPS)':
 'A': CDS_PINID='A';
NET_NAME
'SW_P3V3_AUX_BOOTR'
 '@S9S_MB_2U_LIB.S9S_MB_2U(SCH_1):SW_P3V3_AUX_BOOTR':
 C_SIGNAL='@s9s_mb_2u_lib.s9s_mb_2u(sch_1):sw_p3v3_aux_bootr';
NODE_NAME     PU9 25
 '@S9S_MB_2U_LIB.S9S_MB_2U(SCH_1):PAGE245_I95@PURE_QUANTA.IR3889MTRPBF(CHIPS)':
 'PHASE': CDS_PINID='PHASE';
NODE_NAME     PC568 1
 '@S9S_MB_2U_LIB.S9S_MB_2U(SCH_1):PAGE245_I122@PURE_QUANTA.Q_CAP(CHIPS)':
 'A': CDS_PINID='A';
NET_NAME
'SW_P3V3_AUX_BOOT_R'
 '@S9S_MB_2U_LIB.S9S_MB_2U(SCH_1):SW_P3V3_AUX_BOOT_R':
 C_SIGNAL='@s9s_mb_2u_lib.s9s_mb_2u(sch_1):sw_p3v3_aux_boot_r';
NODE_NAME     PC568 2
 '@S9S_MB_2U_LIB.S9S_MB_2U(SCH_1):PAGE245_I122@PURE_QUANTA.Q_CAP(CHIPS)':
 'B': CDS_PINID='B';
NODE_NAME     PR835 2
 '@S9S_MB_2U_LIB.S9S_MB_2U(SCH_1):PAGE245_I123@PURE_QUANTA.Q_RES(CHIPS)':
 'B': CDS_PINID='B';
NET_NAME
'SW_P3V3_AUX_FLT'
 '@S9S_MB_2U_LIB.S9S_MB_2U(SCH_1):SW_P3V3_AUX_FLT':
 C_SIGNAL='@s9s_mb_2u_lib.s9s_mb_2u(sch_1):sw_p3v3_aux_flt';
NODE_NAME     PU9 20_24
 '@S9S_MB_2U_LIB.S9S_MB_2U(SCH_1):PAGE245_I95@PURE_QUANTA.IR3889MTRPBF(CHIPS)':
 'PVIN': CDS_PINID='PVIN';
NODE_NAME     PL45 2
 '@S9S_MB_2U_LIB.S9S_MB_2U(SCH_1):PAGE245_I98@PURE_QUANTA.Q_INDUCTOR(CHIPS)':
 '2': CDS_PINID='\2\';
NODE_NAME     PC2260 1
 '@S9S_MB_2U_LIB.S9S_MB_2U(SCH_1):PAGE245_I100@PURE_QUANTA.Q_CAP(CHIPS)':
 'A': CDS_PINID='A';
NODE_NAME     PC2261 1
 '@S9S_MB_2U_LIB.S9S_MB_2U(SCH_1):PAGE245_I101@PURE_QUANTA.Q_CAP(CHIPS)':
 'A': CDS_PINID='A';
NODE_NAME     PC3 1
 '@S9S_MB_2U_LIB.S9S_MB_2U(SCH_1):PAGE245_I103@PURE_QUANTA.Q_CAPP(CHIPS)':
 'A': CDS_PINID='A';
NODE_NAME     PC566 1
 '@S9S_MB_2U_LIB.S9S_MB_2U(SCH_1):PAGE245_I104@PURE_QUANTA.Q_CAPP(CHIPS)':
 'A': CDS_PINID='A';
NODE_NAME     PC2262 1
 '@S9S_MB_2U_LIB.S9S_MB_2U(SCH_1):PAGE245_I105@PURE_QUANTA.Q_CAP(CHIPS)':
 'A': CDS_PINID='A';
NODE_NAME     PC567 1
 '@S9S_MB_2U_LIB.S9S_MB_2U(SCH_1):PAGE245_I106@PURE_QUANTA.Q_CAP(CHIPS)':
 'A': CDS_PINID='A';
NODE_NAME     PC2263 1
 '@S9S_MB_2U_LIB.S9S_MB_2U(SCH_1):PAGE245_I107@PURE_QUANTA.Q_CAP(CHIPS)':
 'A': CDS_PINID='A';
NODE_NAME     PC2342 1
 '@S9S_MB_2U_LIB.S9S_MB_2U(SCH_1):PAGE245_I108@PURE_QUANTA.Q_CAP(CHIPS)':
 'A': CDS_PINID='A';
NODE_NAME     PC570 1
 '@S9S_MB_2U_LIB.S9S_MB_2U(SCH_1):PAGE245_I109@PURE_QUANTA.Q_CAP(CHIPS)':
 'A': CDS_PINID='A';
NODE_NAME     PC571 1
 '@S9S_MB_2U_LIB.S9S_MB_2U(SCH_1):PAGE245_I110@PURE_QUANTA.Q_CAP(CHIPS)':
 'A': CDS_PINID='A';
NODE_NAME     PC2343 1
 '@S9S_MB_2U_LIB.S9S_MB_2U(SCH_1):PAGE245_I111@PURE_QUANTA.Q_CAP(CHIPS)':
 'A': CDS_PINID='A';
NODE_NAME     PC2344 1
 '@S9S_MB_2U_LIB.S9S_MB_2U(SCH_1):PAGE245_I112@PURE_QUANTA.Q_CAP(CHIPS)':
 'A': CDS_PINID='A';
NODE_NAME     PC576 1
 '@S9S_MB_2U_LIB.S9S_MB_2U(SCH_1):PAGE245_I113@PURE_QUANTA.Q_CAP(CHIPS)':
 'A': CDS_PINID='A';
NODE_NAME     PC71 1
 '@S9S_MB_2U_LIB.S9S_MB_2U(SCH_1):PAGE245_I114@PURE_QUANTA.Q_CAP(CHIPS)':
 'A': CDS_PINID='A';
NODE_NAME     PC577 1
 '@S9S_MB_2U_LIB.S9S_MB_2U(SCH_1):PAGE245_I115@PURE_QUANTA.Q_CAP(CHIPS)':
 'A': CDS_PINID='A';
NET_NAME
'SW_P3V3_AUX_SW'
 '@S9S_MB_2U_LIB.S9S_MB_2U(SCH_1):SW_P3V3_AUX_SW':
 C_SIGNAL='@s9s_mb_2u_lib.s9s_mb_2u(sch_1):sw_p3v3_aux_sw';
NODE_NAME     PU9 11_18
 '@S9S_MB_2U_LIB.S9S_MB_2U(SCH_1):PAGE245_I95@PURE_QUANTA.IR3889MTRPBF(CHIPS)':
 'SW': CDS_PINID='SW';
NODE_NAME     PL66 1
 '@S9S_MB_2U_LIB.S9S_MB_2U(SCH_1):PAGE245_I129@PURE_QUANTA.Q_INDUCTOR(CHIPS)':
 '1': CDS_PINID='\1\';
NET_NAME
'SW_P5V_AUX_BST'
 '@S9S_MB_2U_LIB.S9S_MB_2U(SCH_1):SW_P5V_AUX_BST':
 C_SIGNAL='@s9s_mb_2u_lib.s9s_mb_2u(sch_1):sw_p5v_aux_bst';
NODE_NAME     PC1847 1
 '@S9S_MB_2U_LIB.S9S_MB_2U(SCH_1):PAGE244_I26@PURE_QUANTA.Q_CAP(CHIPS)':
 'A': CDS_PINID='A';
NODE_NAME     PU181 1
 '@S9S_MB_2U_LIB.S9S_MB_2U(SCH_1):PAGE244_I20@PURE_QUANTA.RS53318LR(CHIPS)':
 'BST': CDS_PINID='BST';
NET_NAME
'SW_P5V_AUX_FLT'
 '@S9S_MB_2U_LIB.S9S_MB_2U(SCH_1):SW_P5V_AUX_FLT':
 C_SIGNAL='@s9s_mb_2u_lib.s9s_mb_2u(sch_1):sw_p5v_aux_flt';
NODE_NAME     PC1898 1
 '@S9S_MB_2U_LIB.S9S_MB_2U(SCH_1):PAGE244_I12@PURE_QUANTA.Q_CAP(CHIPS)':
 'A': CDS_PINID='A';
NODE_NAME     PL64 2
 '@S9S_MB_2U_LIB.S9S_MB_2U(SCH_1):PAGE244_I5@PURE_QUANTA.Q_INDUCTOR(CHIPS)':
 '2': CDS_PINID='\2\';
NODE_NAME     PC1849 1
 '@S9S_MB_2U_LIB.S9S_MB_2U(SCH_1):PAGE244_I7@PURE_QUANTA.Q_CAP(CHIPS)':
 'A': CDS_PINID='A';
NODE_NAME     PC1850 1
 '@S9S_MB_2U_LIB.S9S_MB_2U(SCH_1):PAGE244_I11@PURE_QUANTA.Q_CAP(CHIPS)':
 'A': CDS_PINID='A';
NODE_NAME     PC1846 1
 '@S9S_MB_2U_LIB.S9S_MB_2U(SCH_1):PAGE244_I14@PURE_QUANTA.Q_CAP(CHIPS)':
 'A': CDS_PINID='A';
NODE_NAME     PU181 10
 '@S9S_MB_2U_LIB.S9S_MB_2U(SCH_1):PAGE244_I20@PURE_QUANTA.RS53318LR(CHIPS)':
 'VIN1': CDS_PINID='VIN1';
NODE_NAME     PU181 21
 '@S9S_MB_2U_LIB.S9S_MB_2U(SCH_1):PAGE244_I20@PURE_QUANTA.RS53318LR(CHIPS)':
 'VIN2': CDS_PINID='VIN2';
NET_NAME
'SW_P5V_AUX_SW'
 '@S9S_MB_2U_LIB.S9S_MB_2U(SCH_1):SW_P5V_AUX_SW':
 C_SIGNAL='@s9s_mb_2u_lib.s9s_mb_2u(sch_1):sw_p5v_aux_sw';
NODE_NAME     PL65 1
 '@S9S_MB_2U_LIB.S9S_MB_2U(SCH_1):PAGE244_I30@PURE_QUANTA.Q_INDUCTOR(CHIPS)':
 '1': CDS_PINID='\1\';
NODE_NAME     PC1847 2
 '@S9S_MB_2U_LIB.S9S_MB_2U(SCH_1):PAGE244_I26@PURE_QUANTA.Q_CAP(CHIPS)':
 'B': CDS_PINID='B';
NODE_NAME     PU181 20
 '@S9S_MB_2U_LIB.S9S_MB_2U(SCH_1):PAGE244_I20@PURE_QUANTA.RS53318LR(CHIPS)':
 'SW': CDS_PINID='SW';
NET_NAME
'SW_PVCCD_HV_CPU0_BOOT1'
 '@S9S_MB_2U_LIB.S9S_MB_2U(SCH_1):SW_PVCCD_HV_CPU0_BOOT1':
 C_SIGNAL='@s9s_mb_2u_lib.s9s_mb_2u(sch_1):sw_pvccd_hv_cpu0_boot1';
NODE_NAME     PU36 33
 '@S9S_MB_2U_LIB.S9S_MB_2U(SCH_1):PAGE265_I8@PURE_QUANTA.ISL99390FRZTR5935(CHIPS)':
 'BOOT': CDS_PINID='BOOT';
NODE_NAME     PR1784 1
 '@S9S_MB_2U_LIB.S9S_MB_2U(SCH_1):PAGE265_I19@PURE_QUANTA.Q_RES(CHIPS)':
 'A': CDS_PINID='A';
NET_NAME
'SW_PVCCD_HV_CPU0_BOOT1_R'
 '@S9S_MB_2U_LIB.S9S_MB_2U(SCH_1):SW_PVCCD_HV_CPU0_BOOT1_R':
 C_SIGNAL='@s9s_mb_2u_lib.s9s_mb_2u(sch_1):sw_pvccd_hv_cpu0_boot1_r';
NODE_NAME     PR1784 2
 '@S9S_MB_2U_LIB.S9S_MB_2U(SCH_1):PAGE265_I19@PURE_QUANTA.Q_RES(CHIPS)':
 'B': CDS_PINID='B';
NODE_NAME     PC636 1
 '@S9S_MB_2U_LIB.S9S_MB_2U(SCH_1):PAGE265_I22@PURE_QUANTA.Q_CAP(CHIPS)':
 'A': CDS_PINID='A';
NET_NAME
'SW_PVCCD_HV_CPU0_BOOTR1'
 '@S9S_MB_2U_LIB.S9S_MB_2U(SCH_1):SW_PVCCD_HV_CPU0_BOOTR1':
 C_SIGNAL='@s9s_mb_2u_lib.s9s_mb_2u(sch_1):sw_pvccd_hv_cpu0_bootr1';
NODE_NAME     PU36 32
 '@S9S_MB_2U_LIB.S9S_MB_2U(SCH_1):PAGE265_I8@PURE_QUANTA.ISL99390FRZTR5935(CHIPS)':
 'PHASE': CDS_PINID='PHASE';
NODE_NAME     PC636 2
 '@S9S_MB_2U_LIB.S9S_MB_2U(SCH_1):PAGE265_I22@PURE_QUANTA.Q_CAP(CHIPS)':
 'B': CDS_PINID='B';
NET_NAME
'SW_PVCCD_HV_CPU0_SW1'
 '@S9S_MB_2U_LIB.S9S_MB_2U(SCH_1):SW_PVCCD_HV_CPU0_SW1':
 C_SIGNAL='@s9s_mb_2u_lib.s9s_mb_2u(sch_1):sw_pvccd_hv_cpu0_sw1';
NODE_NAME     PU36 10_19
 '@S9S_MB_2U_LIB.S9S_MB_2U(SCH_1):PAGE265_I8@PURE_QUANTA.ISL99390FRZTR5935(CHIPS)':
 'SW': CDS_PINID='SW';
NODE_NAME     PL35 1
 '@S9S_MB_2U_LIB.S9S_MB_2U(SCH_1):PAGE265_I30@PURE_QUANTA.Q_INDUCTOR(CHIPS)':
 '1': CDS_PINID='\1\';
NET_NAME
'SW_PVCCD_HV_CPU1_BOOT1'
 '@S9S_MB_2U_LIB.S9S_MB_2U(SCH_1):SW_PVCCD_HV_CPU1_BOOT1':
 C_SIGNAL='@s9s_mb_2u_lib.s9s_mb_2u(sch_1):sw_pvccd_hv_cpu1_boot1';
NODE_NAME     PR1804 1
 '@S9S_MB_2U_LIB.S9S_MB_2U(SCH_1):PAGE283_I21@PURE_QUANTA.Q_RES(CHIPS)':
 'A': CDS_PINID='A';
NODE_NAME     PU17 33
 '@S9S_MB_2U_LIB.S9S_MB_2U(SCH_1):PAGE283_I10@PURE_QUANTA.ISL99390FRZTR5935(CHIPS)':
 'BOOT': CDS_PINID='BOOT';
NET_NAME
'SW_PVCCD_HV_CPU1_BOOT1_R'
 '@S9S_MB_2U_LIB.S9S_MB_2U(SCH_1):SW_PVCCD_HV_CPU1_BOOT1_R':
 C_SIGNAL='@s9s_mb_2u_lib.s9s_mb_2u(sch_1):sw_pvccd_hv_cpu1_boot1_r';
NODE_NAME     PR1804 2
 '@S9S_MB_2U_LIB.S9S_MB_2U(SCH_1):PAGE283_I21@PURE_QUANTA.Q_RES(CHIPS)':
 'B': CDS_PINID='B';
NODE_NAME     PC376 1
 '@S9S_MB_2U_LIB.S9S_MB_2U(SCH_1):PAGE283_I13@PURE_QUANTA.Q_CAP(CHIPS)':
 'A': CDS_PINID='A';
NET_NAME
'SW_PVCCD_HV_CPU1_BOOTR1'
 '@S9S_MB_2U_LIB.S9S_MB_2U(SCH_1):SW_PVCCD_HV_CPU1_BOOTR1':
 C_SIGNAL='@s9s_mb_2u_lib.s9s_mb_2u(sch_1):sw_pvccd_hv_cpu1_bootr1';
NODE_NAME     PU17 32
 '@S9S_MB_2U_LIB.S9S_MB_2U(SCH_1):PAGE283_I10@PURE_QUANTA.ISL99390FRZTR5935(CHIPS)':
 'PHASE': CDS_PINID='PHASE';
NODE_NAME     PC376 2
 '@S9S_MB_2U_LIB.S9S_MB_2U(SCH_1):PAGE283_I13@PURE_QUANTA.Q_CAP(CHIPS)':
 'B': CDS_PINID='B';
NET_NAME
'SW_PVCCD_HV_CPU1_SW1'
 '@S9S_MB_2U_LIB.S9S_MB_2U(SCH_1):SW_PVCCD_HV_CPU1_SW1':
 C_SIGNAL='@s9s_mb_2u_lib.s9s_mb_2u(sch_1):sw_pvccd_hv_cpu1_sw1';
NODE_NAME     PL17 1
 '@S9S_MB_2U_LIB.S9S_MB_2U(SCH_1):PAGE283_I14@PURE_QUANTA.Q_INDUCTOR(CHIPS)':
 '1': CDS_PINID='\1\';
NODE_NAME     PU17 10_19
 '@S9S_MB_2U_LIB.S9S_MB_2U(SCH_1):PAGE283_I10@PURE_QUANTA.ISL99390FRZTR5935(CHIPS)':
 'SW': CDS_PINID='SW';
NET_NAME
'SW_PVCCFA_EHV_CPU0_BOOT1'
 '@S9S_MB_2U_LIB.S9S_MB_2U(SCH_1):SW_PVCCFA_EHV_CPU0_BOOT1':
 C_SIGNAL='@s9s_mb_2u_lib.s9s_mb_2u(sch_1):sw_pvccfa_ehv_cpu0_boot1';
NODE_NAME     PR1778 1
 '@S9S_MB_2U_LIB.S9S_MB_2U(SCH_1):PAGE262_I17@PURE_QUANTA.Q_RES(CHIPS)':
 'A': CDS_PINID='A';
NODE_NAME     PU42 20
 '@S9S_MB_2U_LIB.S9S_MB_2U(SCH_1):PAGE262_I14@PURE_QUANTA.RAA2213404GNPHB0(CHIPS)':
 'BOOT': CDS_PINID='BOOT';
NET_NAME
'SW_PVCCFA_EHV_CPU0_BOOT1_R'
 '@S9S_MB_2U_LIB.S9S_MB_2U(SCH_1):SW_PVCCFA_EHV_CPU0_BOOT1_R':
 C_SIGNAL='@s9s_mb_2u_lib.s9s_mb_2u(sch_1):sw_pvccfa_ehv_cpu0_boot1_r';
NODE_NAME     PR1778 2
 '@S9S_MB_2U_LIB.S9S_MB_2U(SCH_1):PAGE262_I17@PURE_QUANTA.Q_RES(CHIPS)':
 'B': CDS_PINID='B';
NODE_NAME     PC178 1
 '@S9S_MB_2U_LIB.S9S_MB_2U(SCH_1):PAGE262_I20@PURE_QUANTA.Q_CAP(CHIPS)':
 'A': CDS_PINID='A';
NET_NAME
'SW_PVCCFA_EHV_CPU0_BOOTR1'
 '@S9S_MB_2U_LIB.S9S_MB_2U(SCH_1):SW_PVCCFA_EHV_CPU0_BOOTR1':
 C_SIGNAL='@s9s_mb_2u_lib.s9s_mb_2u(sch_1):sw_pvccfa_ehv_cpu0_bootr1';
NODE_NAME     PU42 19
 '@S9S_MB_2U_LIB.S9S_MB_2U(SCH_1):PAGE262_I14@PURE_QUANTA.RAA2213404GNPHB0(CHIPS)':
 'PHASE': CDS_PINID='PHASE';
NODE_NAME     PC178 2
 '@S9S_MB_2U_LIB.S9S_MB_2U(SCH_1):PAGE262_I20@PURE_QUANTA.Q_CAP(CHIPS)':
 'B': CDS_PINID='B';
NET_NAME
'SW_PVCCFA_EHV_CPU0_SW1'
 '@S9S_MB_2U_LIB.S9S_MB_2U(SCH_1):SW_PVCCFA_EHV_CPU0_SW1':
 C_SIGNAL='@s9s_mb_2u_lib.s9s_mb_2u(sch_1):sw_pvccfa_ehv_cpu0_sw1';
NODE_NAME     PL3 1
 '@S9S_MB_2U_LIB.S9S_MB_2U(SCH_1):PAGE262_I29@PURE_QUANTA.Q_INDUCTOR(CHIPS)':
 '1': CDS_PINID='\1\';
NODE_NAME     PU42 8_12
 '@S9S_MB_2U_LIB.S9S_MB_2U(SCH_1):PAGE262_I14@PURE_QUANTA.RAA2213404GNPHB0(CHIPS)':
 'SW': CDS_PINID='SW';
NET_NAME
'SW_PVCCFA_EHV_CPU1_BOOT1'
 '@S9S_MB_2U_LIB.S9S_MB_2U(SCH_1):SW_PVCCFA_EHV_CPU1_BOOT1':
 C_SIGNAL='@s9s_mb_2u_lib.s9s_mb_2u(sch_1):sw_pvccfa_ehv_cpu1_boot1';
NODE_NAME     PU49 20
 '@S9S_MB_2U_LIB.S9S_MB_2U(SCH_1):PAGE280_I14@PURE_QUANTA.RAA2213404GNPHB0(CHIPS)':
 'BOOT': CDS_PINID='BOOT';
NODE_NAME     PR1798 1
 '@S9S_MB_2U_LIB.S9S_MB_2U(SCH_1):PAGE280_I25@PURE_QUANTA.Q_RES(CHIPS)':
 'A': CDS_PINID='A';
NET_NAME
'SW_PVCCFA_EHV_CPU1_BOOT1_R'
 '@S9S_MB_2U_LIB.S9S_MB_2U(SCH_1):SW_PVCCFA_EHV_CPU1_BOOT1_R':
 C_SIGNAL='@s9s_mb_2u_lib.s9s_mb_2u(sch_1):sw_pvccfa_ehv_cpu1_boot1_r';
NODE_NAME     PC431 1
 '@S9S_MB_2U_LIB.S9S_MB_2U(SCH_1):PAGE280_I22@PURE_QUANTA.Q_CAP(CHIPS)':
 'A': CDS_PINID='A';
NODE_NAME     PR1798 2
 '@S9S_MB_2U_LIB.S9S_MB_2U(SCH_1):PAGE280_I25@PURE_QUANTA.Q_RES(CHIPS)':
 'B': CDS_PINID='B';
NET_NAME
'SW_PVCCFA_EHV_CPU1_BOOTR1'
 '@S9S_MB_2U_LIB.S9S_MB_2U(SCH_1):SW_PVCCFA_EHV_CPU1_BOOTR1':
 C_SIGNAL='@s9s_mb_2u_lib.s9s_mb_2u(sch_1):sw_pvccfa_ehv_cpu1_bootr1';
NODE_NAME     PU49 19
 '@S9S_MB_2U_LIB.S9S_MB_2U(SCH_1):PAGE280_I14@PURE_QUANTA.RAA2213404GNPHB0(CHIPS)':
 'PHASE': CDS_PINID='PHASE';
NODE_NAME     PC431 2
 '@S9S_MB_2U_LIB.S9S_MB_2U(SCH_1):PAGE280_I22@PURE_QUANTA.Q_CAP(CHIPS)':
 'B': CDS_PINID='B';
NET_NAME
'SW_PVCCFA_EHV_CPU1_SW1'
 '@S9S_MB_2U_LIB.S9S_MB_2U(SCH_1):SW_PVCCFA_EHV_CPU1_SW1':
 C_SIGNAL='@s9s_mb_2u_lib.s9s_mb_2u(sch_1):sw_pvccfa_ehv_cpu1_sw1';
NODE_NAME     PU49 8_12
 '@S9S_MB_2U_LIB.S9S_MB_2U(SCH_1):PAGE280_I14@PURE_QUANTA.RAA2213404GNPHB0(CHIPS)':
 'SW': CDS_PINID='SW';
NODE_NAME     PL20 1
 '@S9S_MB_2U_LIB.S9S_MB_2U(SCH_1):PAGE280_I23@PURE_QUANTA.Q_INDUCTOR(CHIPS)':
 '1': CDS_PINID='\1\';
NET_NAME
'SW_PVCCFA_EHV_FIVRA_CPU0_BOOT1'
 '@S9S_MB_2U_LIB.S9S_MB_2U(SCH_1):SW_PVCCFA_EHV_FIVRA_CPU0_BOOT1':
 C_SIGNAL='@s9s_mb_2u_lib.s9s_mb_2u(sch_1):sw_pvccfa_ehv_fivra_cpu0_boot1';
NODE_NAME     PR1780 1
 '@S9S_MB_2U_LIB.S9S_MB_2U(SCH_1):PAGE257_I46@PURE_QUANTA.Q_RES(CHIPS)':
 'A': CDS_PINID='A';
NODE_NAME     PU69_P0_1 33
 '@S9S_MB_2U_LIB.S9S_MB_2U(SCH_1):PAGE257_I25@PURE_QUANTA.ISL99390FRZTR5935(CHIPS)':
 'BOOT': CDS_PINID='BOOT';
NET_NAME
'SW_PVCCFA_EHV_FIVRA_CPU0_BOOT1_'
 '@S9S_MB_2U_LIB.S9S_MB_2U(SCH_1):SW_PVCCFA_EHV_FIVRA_CPU0_BOOT1_R':
 C_SIGNAL='@s9s_mb_2u_lib.s9s_mb_2u(sch_1):sw_pvccfa_ehv_fivra_cpu0_boot1_r';
NODE_NAME     PR1780 2
 '@S9S_MB_2U_LIB.S9S_MB_2U(SCH_1):PAGE257_I46@PURE_QUANTA.Q_RES(CHIPS)':
 'B': CDS_PINID='B';
NODE_NAME     PC606 1
 '@S9S_MB_2U_LIB.S9S_MB_2U(SCH_1):PAGE257_I71@PURE_QUANTA.Q_CAP(CHIPS)':
 'A': CDS_PINID='A';
NET_NAME
'SW_PVCCFA_EHV_FIVRA_CPU0_BOOT2'
 '@S9S_MB_2U_LIB.S9S_MB_2U(SCH_1):SW_PVCCFA_EHV_FIVRA_CPU0_BOOT2':
 C_SIGNAL='@s9s_mb_2u_lib.s9s_mb_2u(sch_1):sw_pvccfa_ehv_fivra_cpu0_boot2';
NODE_NAME     PU70_P0_2 33
 '@S9S_MB_2U_LIB.S9S_MB_2U(SCH_1):PAGE257_I16@PURE_QUANTA.ISL99390FRZTR5935(CHIPS)':
 'BOOT': CDS_PINID='BOOT';
NODE_NAME     PR1781 1
 '@S9S_MB_2U_LIB.S9S_MB_2U(SCH_1):PAGE257_I30@PURE_QUANTA.Q_RES(CHIPS)':
 'A': CDS_PINID='A';
NET_NAME
'SW_PVCCFA_EHV_FIVRA_CPU0_BOOT2_'
 '@S9S_MB_2U_LIB.S9S_MB_2U(SCH_1):SW_PVCCFA_EHV_FIVRA_CPU0_BOOT2_R':
 C_SIGNAL='@s9s_mb_2u_lib.s9s_mb_2u(sch_1):sw_pvccfa_ehv_fivra_cpu0_boot2_r';
NODE_NAME     PR1781 2
 '@S9S_MB_2U_LIB.S9S_MB_2U(SCH_1):PAGE257_I30@PURE_QUANTA.Q_RES(CHIPS)':
 'B': CDS_PINID='B';
NODE_NAME     PC607 1
 '@S9S_MB_2U_LIB.S9S_MB_2U(SCH_1):PAGE257_I53@PURE_QUANTA.Q_CAP(CHIPS)':
 'A': CDS_PINID='A';
NET_NAME
'SW_PVCCFA_EHV_FIVRA_CPU0_BOOT3'
 '@S9S_MB_2U_LIB.S9S_MB_2U(SCH_1):SW_PVCCFA_EHV_FIVRA_CPU0_BOOT3':
 C_SIGNAL='@s9s_mb_2u_lib.s9s_mb_2u(sch_1):sw_pvccfa_ehv_fivra_cpu0_boot3';
NODE_NAME     PR1782 1
 '@S9S_MB_2U_LIB.S9S_MB_2U(SCH_1):PAGE258_I45@PURE_QUANTA.Q_RES(CHIPS)':
 'A': CDS_PINID='A';
NODE_NAME     PU71_P0_3 33
 '@S9S_MB_2U_LIB.S9S_MB_2U(SCH_1):PAGE258_I82@PURE_QUANTA.ISL99390FRZTR5935(CHIPS)':
 'BOOT': CDS_PINID='BOOT';
NET_NAME
'SW_PVCCFA_EHV_FIVRA_CPU0_BOOT3_'
 '@S9S_MB_2U_LIB.S9S_MB_2U(SCH_1):SW_PVCCFA_EHV_FIVRA_CPU0_BOOT3_R':
 C_SIGNAL='@s9s_mb_2u_lib.s9s_mb_2u(sch_1):sw_pvccfa_ehv_fivra_cpu0_boot3_r';
NODE_NAME     PR1782 2
 '@S9S_MB_2U_LIB.S9S_MB_2U(SCH_1):PAGE258_I45@PURE_QUANTA.Q_RES(CHIPS)':
 'B': CDS_PINID='B';
NODE_NAME     PC1177 1
 '@S9S_MB_2U_LIB.S9S_MB_2U(SCH_1):PAGE258_I49@PURE_QUANTA.Q_CAP(CHIPS)':
 'A': CDS_PINID='A';
NET_NAME
'SW_PVCCFA_EHV_FIVRA_CPU0_BOOT4'
 '@S9S_MB_2U_LIB.S9S_MB_2U(SCH_1):SW_PVCCFA_EHV_FIVRA_CPU0_BOOT4':
 C_SIGNAL='@s9s_mb_2u_lib.s9s_mb_2u(sch_1):sw_pvccfa_ehv_fivra_cpu0_boot4';
NODE_NAME     PR1783 1
 '@S9S_MB_2U_LIB.S9S_MB_2U(SCH_1):PAGE258_I33@PURE_QUANTA.Q_RES(CHIPS)':
 'A': CDS_PINID='A';
NODE_NAME     PU72_P0_4 33
 '@S9S_MB_2U_LIB.S9S_MB_2U(SCH_1):PAGE258_I10@PURE_QUANTA.ISL99390FRZTR5935(CHIPS)':
 'BOOT': CDS_PINID='BOOT';
NET_NAME
'SW_PVCCFA_EHV_FIVRA_CPU0_BOOT4_'
 '@S9S_MB_2U_LIB.S9S_MB_2U(SCH_1):SW_PVCCFA_EHV_FIVRA_CPU0_BOOT4_R':
 C_SIGNAL='@s9s_mb_2u_lib.s9s_mb_2u(sch_1):sw_pvccfa_ehv_fivra_cpu0_boot4_r';
NODE_NAME     PR1783 2
 '@S9S_MB_2U_LIB.S9S_MB_2U(SCH_1):PAGE258_I33@PURE_QUANTA.Q_RES(CHIPS)':
 'B': CDS_PINID='B';
NODE_NAME     PC1178 1
 '@S9S_MB_2U_LIB.S9S_MB_2U(SCH_1):PAGE258_I37@PURE_QUANTA.Q_CAP(CHIPS)':
 'A': CDS_PINID='A';
NET_NAME
'SW_PVCCFA_EHV_FIVRA_CPU0_BOOTR1'
 '@S9S_MB_2U_LIB.S9S_MB_2U(SCH_1):SW_PVCCFA_EHV_FIVRA_CPU0_BOOTR1':
 C_SIGNAL='@s9s_mb_2u_lib.s9s_mb_2u(sch_1):sw_pvccfa_ehv_fivra_cpu0_bootr1';
NODE_NAME     PU69_P0_1 32
 '@S9S_MB_2U_LIB.S9S_MB_2U(SCH_1):PAGE257_I25@PURE_QUANTA.ISL99390FRZTR5935(CHIPS)':
 'PHASE': CDS_PINID='PHASE';
NODE_NAME     PC606 2
 '@S9S_MB_2U_LIB.S9S_MB_2U(SCH_1):PAGE257_I71@PURE_QUANTA.Q_CAP(CHIPS)':
 'B': CDS_PINID='B';
NET_NAME
'SW_PVCCFA_EHV_FIVRA_CPU0_BOOTR2'
 '@S9S_MB_2U_LIB.S9S_MB_2U(SCH_1):SW_PVCCFA_EHV_FIVRA_CPU0_BOOTR2':
 C_SIGNAL='@s9s_mb_2u_lib.s9s_mb_2u(sch_1):sw_pvccfa_ehv_fivra_cpu0_bootr2';
NODE_NAME     PU70_P0_2 32
 '@S9S_MB_2U_LIB.S9S_MB_2U(SCH_1):PAGE257_I16@PURE_QUANTA.ISL99390FRZTR5935(CHIPS)':
 'PHASE': CDS_PINID='PHASE';
NODE_NAME     PC607 2
 '@S9S_MB_2U_LIB.S9S_MB_2U(SCH_1):PAGE257_I53@PURE_QUANTA.Q_CAP(CHIPS)':
 'B': CDS_PINID='B';
NET_NAME
'SW_PVCCFA_EHV_FIVRA_CPU0_BOOTR3'
 '@S9S_MB_2U_LIB.S9S_MB_2U(SCH_1):SW_PVCCFA_EHV_FIVRA_CPU0_BOOTR3':
 C_SIGNAL='@s9s_mb_2u_lib.s9s_mb_2u(sch_1):sw_pvccfa_ehv_fivra_cpu0_bootr3';
NODE_NAME     PU71_P0_3 32
 '@S9S_MB_2U_LIB.S9S_MB_2U(SCH_1):PAGE258_I82@PURE_QUANTA.ISL99390FRZTR5935(CHIPS)':
 'PHASE': CDS_PINID='PHASE';
NODE_NAME     PC1177 2
 '@S9S_MB_2U_LIB.S9S_MB_2U(SCH_1):PAGE258_I49@PURE_QUANTA.Q_CAP(CHIPS)':
 'B': CDS_PINID='B';
NET_NAME
'SW_PVCCFA_EHV_FIVRA_CPU0_BOOTR4'
 '@S9S_MB_2U_LIB.S9S_MB_2U(SCH_1):SW_PVCCFA_EHV_FIVRA_CPU0_BOOTR4':
 C_SIGNAL='@s9s_mb_2u_lib.s9s_mb_2u(sch_1):sw_pvccfa_ehv_fivra_cpu0_bootr4';
NODE_NAME     PC1178 2
 '@S9S_MB_2U_LIB.S9S_MB_2U(SCH_1):PAGE258_I37@PURE_QUANTA.Q_CAP(CHIPS)':
 'B': CDS_PINID='B';
NODE_NAME     PU72_P0_4 32
 '@S9S_MB_2U_LIB.S9S_MB_2U(SCH_1):PAGE258_I10@PURE_QUANTA.ISL99390FRZTR5935(CHIPS)':
 'PHASE': CDS_PINID='PHASE';
NET_NAME
'SW_PVCCFA_EHV_FIVRA_CPU0_SW1'
 '@S9S_MB_2U_LIB.S9S_MB_2U(SCH_1):SW_PVCCFA_EHV_FIVRA_CPU0_SW1':
 C_SIGNAL='@s9s_mb_2u_lib.s9s_mb_2u(sch_1):sw_pvccfa_ehv_fivra_cpu0_sw1';
NODE_NAME     PL33 1
 '@S9S_MB_2U_LIB.S9S_MB_2U(SCH_1):PAGE257_I70@PURE_QUANTA.Q_INDUCTOR(CHIPS)':
 '1': CDS_PINID='\1\';
NODE_NAME     PU69_P0_1 10_19
 '@S9S_MB_2U_LIB.S9S_MB_2U(SCH_1):PAGE257_I25@PURE_QUANTA.ISL99390FRZTR5935(CHIPS)':
 'SW': CDS_PINID='SW';
NET_NAME
'SW_PVCCFA_EHV_FIVRA_CPU0_SW2'
 '@S9S_MB_2U_LIB.S9S_MB_2U(SCH_1):SW_PVCCFA_EHV_FIVRA_CPU0_SW2':
 C_SIGNAL='@s9s_mb_2u_lib.s9s_mb_2u(sch_1):sw_pvccfa_ehv_fivra_cpu0_sw2';
NODE_NAME     PL34 1
 '@S9S_MB_2U_LIB.S9S_MB_2U(SCH_1):PAGE257_I49@PURE_QUANTA.Q_INDUCTOR(CHIPS)':
 '1': CDS_PINID='\1\';
NODE_NAME     PU70_P0_2 10_19
 '@S9S_MB_2U_LIB.S9S_MB_2U(SCH_1):PAGE257_I16@PURE_QUANTA.ISL99390FRZTR5935(CHIPS)':
 'SW': CDS_PINID='SW';
NET_NAME
'SW_PVCCFA_EHV_FIVRA_CPU0_SW3'
 '@S9S_MB_2U_LIB.S9S_MB_2U(SCH_1):SW_PVCCFA_EHV_FIVRA_CPU0_SW3':
 C_SIGNAL='@s9s_mb_2u_lib.s9s_mb_2u(sch_1):sw_pvccfa_ehv_fivra_cpu0_sw3';
NODE_NAME     PL2 1
 '@S9S_MB_2U_LIB.S9S_MB_2U(SCH_1):PAGE258_I51@PURE_QUANTA.Q_INDUCTOR(CHIPS)':
 '1': CDS_PINID='\1\';
NODE_NAME     PU71_P0_3 10_19
 '@S9S_MB_2U_LIB.S9S_MB_2U(SCH_1):PAGE258_I82@PURE_QUANTA.ISL99390FRZTR5935(CHIPS)':
 'SW': CDS_PINID='SW';
NET_NAME
'SW_PVCCFA_EHV_FIVRA_CPU0_SW4'
 '@S9S_MB_2U_LIB.S9S_MB_2U(SCH_1):SW_PVCCFA_EHV_FIVRA_CPU0_SW4':
 C_SIGNAL='@s9s_mb_2u_lib.s9s_mb_2u(sch_1):sw_pvccfa_ehv_fivra_cpu0_sw4';
NODE_NAME     PL210 1
 '@S9S_MB_2U_LIB.S9S_MB_2U(SCH_1):PAGE258_I39@PURE_QUANTA.Q_INDUCTOR(CHIPS)':
 '1': CDS_PINID='\1\';
NODE_NAME     PU72_P0_4 10_19
 '@S9S_MB_2U_LIB.S9S_MB_2U(SCH_1):PAGE258_I10@PURE_QUANTA.ISL99390FRZTR5935(CHIPS)':
 'SW': CDS_PINID='SW';
NET_NAME
'SW_PVCCFA_EHV_FIVRA_CPU1_BOOT1'
 '@S9S_MB_2U_LIB.S9S_MB_2U(SCH_1):SW_PVCCFA_EHV_FIVRA_CPU1_BOOT1':
 C_SIGNAL='@s9s_mb_2u_lib.s9s_mb_2u(sch_1):sw_pvccfa_ehv_fivra_cpu1_boot1';
NODE_NAME     PR1800 1
 '@S9S_MB_2U_LIB.S9S_MB_2U(SCH_1):PAGE275_I50@PURE_QUANTA.Q_RES(CHIPS)':
 'A': CDS_PINID='A';
NODE_NAME     PU75_P1_1 33
 '@S9S_MB_2U_LIB.S9S_MB_2U(SCH_1):PAGE275_I89@PURE_QUANTA.ISL99390FRZTR5935(CHIPS)':
 'BOOT': CDS_PINID='BOOT';
NET_NAME
'SW_PVCCFA_EHV_FIVRA_CPU1_BOOT1_'
 '@S9S_MB_2U_LIB.S9S_MB_2U(SCH_1):SW_PVCCFA_EHV_FIVRA_CPU1_BOOT1_R':
 C_SIGNAL='@s9s_mb_2u_lib.s9s_mb_2u(sch_1):sw_pvccfa_ehv_fivra_cpu1_boot1_r';
NODE_NAME     PR1800 2
 '@S9S_MB_2U_LIB.S9S_MB_2U(SCH_1):PAGE275_I50@PURE_QUANTA.Q_RES(CHIPS)':
 'B': CDS_PINID='B';
NODE_NAME     PC401 1
 '@S9S_MB_2U_LIB.S9S_MB_2U(SCH_1):PAGE275_I54@PURE_QUANTA.Q_CAP(CHIPS)':
 'A': CDS_PINID='A';
NET_NAME
'SW_PVCCFA_EHV_FIVRA_CPU1_BOOT2'
 '@S9S_MB_2U_LIB.S9S_MB_2U(SCH_1):SW_PVCCFA_EHV_FIVRA_CPU1_BOOT2':
 C_SIGNAL='@s9s_mb_2u_lib.s9s_mb_2u(sch_1):sw_pvccfa_ehv_fivra_cpu1_boot2';
NODE_NAME     PU76_P1_2 33
 '@S9S_MB_2U_LIB.S9S_MB_2U(SCH_1):PAGE275_I9@PURE_QUANTA.ISL99390FRZTR5935(CHIPS)':
 'BOOT': CDS_PINID='BOOT';
NODE_NAME     PR1801 1
 '@S9S_MB_2U_LIB.S9S_MB_2U(SCH_1):PAGE275_I38@PURE_QUANTA.Q_RES(CHIPS)':
 'A': CDS_PINID='A';
NET_NAME
'SW_PVCCFA_EHV_FIVRA_CPU1_BOOT2_'
 '@S9S_MB_2U_LIB.S9S_MB_2U(SCH_1):SW_PVCCFA_EHV_FIVRA_CPU1_BOOT2_R':
 C_SIGNAL='@s9s_mb_2u_lib.s9s_mb_2u(sch_1):sw_pvccfa_ehv_fivra_cpu1_boot2_r';
NODE_NAME     PR1801 2
 '@S9S_MB_2U_LIB.S9S_MB_2U(SCH_1):PAGE275_I38@PURE_QUANTA.Q_RES(CHIPS)':
 'B': CDS_PINID='B';
NODE_NAME     PC402 1
 '@S9S_MB_2U_LIB.S9S_MB_2U(SCH_1):PAGE275_I43@PURE_QUANTA.Q_CAP(CHIPS)':
 'A': CDS_PINID='A';
NET_NAME
'SW_PVCCFA_EHV_FIVRA_CPU1_BOOT3'
 '@S9S_MB_2U_LIB.S9S_MB_2U(SCH_1):SW_PVCCFA_EHV_FIVRA_CPU1_BOOT3':
 C_SIGNAL='@s9s_mb_2u_lib.s9s_mb_2u(sch_1):sw_pvccfa_ehv_fivra_cpu1_boot3';
NODE_NAME     PR1802 1
 '@S9S_MB_2U_LIB.S9S_MB_2U(SCH_1):PAGE276_I40@PURE_QUANTA.Q_RES(CHIPS)':
 'A': CDS_PINID='A';
NODE_NAME     PU77_P1_3 33
 '@S9S_MB_2U_LIB.S9S_MB_2U(SCH_1):PAGE276_I24@PURE_QUANTA.ISL99390FRZTR5935(CHIPS)':
 'BOOT': CDS_PINID='BOOT';
NET_NAME
'SW_PVCCFA_EHV_FIVRA_CPU1_BOOT3_'
 '@S9S_MB_2U_LIB.S9S_MB_2U(SCH_1):SW_PVCCFA_EHV_FIVRA_CPU1_BOOT3_R':
 C_SIGNAL='@s9s_mb_2u_lib.s9s_mb_2u(sch_1):sw_pvccfa_ehv_fivra_cpu1_boot3_r';
NODE_NAME     PR1802 2
 '@S9S_MB_2U_LIB.S9S_MB_2U(SCH_1):PAGE276_I40@PURE_QUANTA.Q_RES(CHIPS)':
 'B': CDS_PINID='B';
NODE_NAME     PC1197 1
 '@S9S_MB_2U_LIB.S9S_MB_2U(SCH_1):PAGE276_I58@PURE_QUANTA.Q_CAP(CHIPS)':
 'A': CDS_PINID='A';
NET_NAME
'SW_PVCCFA_EHV_FIVRA_CPU1_BOOT4'
 '@S9S_MB_2U_LIB.S9S_MB_2U(SCH_1):SW_PVCCFA_EHV_FIVRA_CPU1_BOOT4':
 C_SIGNAL='@s9s_mb_2u_lib.s9s_mb_2u(sch_1):sw_pvccfa_ehv_fivra_cpu1_boot4';
NODE_NAME     PU78_P1_4 33
 '@S9S_MB_2U_LIB.S9S_MB_2U(SCH_1):PAGE276_I15@PURE_QUANTA.ISL99390FRZTR5935(CHIPS)':
 'BOOT': CDS_PINID='BOOT';
NODE_NAME     PR1803 1
 '@S9S_MB_2U_LIB.S9S_MB_2U(SCH_1):PAGE276_I17@PURE_QUANTA.Q_RES(CHIPS)':
 'A': CDS_PINID='A';
NET_NAME
'SW_PVCCFA_EHV_FIVRA_CPU1_BOOT4_'
 '@S9S_MB_2U_LIB.S9S_MB_2U(SCH_1):SW_PVCCFA_EHV_FIVRA_CPU1_BOOT4_R':
 C_SIGNAL='@s9s_mb_2u_lib.s9s_mb_2u(sch_1):sw_pvccfa_ehv_fivra_cpu1_boot4_r';
NODE_NAME     PC1198 1
 '@S9S_MB_2U_LIB.S9S_MB_2U(SCH_1):PAGE276_I45@PURE_QUANTA.Q_CAP(CHIPS)':
 'A': CDS_PINID='A';
NODE_NAME     PR1803 2
 '@S9S_MB_2U_LIB.S9S_MB_2U(SCH_1):PAGE276_I17@PURE_QUANTA.Q_RES(CHIPS)':
 'B': CDS_PINID='B';
NET_NAME
'SW_PVCCFA_EHV_FIVRA_CPU1_BOOTR1'
 '@S9S_MB_2U_LIB.S9S_MB_2U(SCH_1):SW_PVCCFA_EHV_FIVRA_CPU1_BOOTR1':
 C_SIGNAL='@s9s_mb_2u_lib.s9s_mb_2u(sch_1):sw_pvccfa_ehv_fivra_cpu1_bootr1';
NODE_NAME     PC401 2
 '@S9S_MB_2U_LIB.S9S_MB_2U(SCH_1):PAGE275_I54@PURE_QUANTA.Q_CAP(CHIPS)':
 'B': CDS_PINID='B';
NODE_NAME     PU75_P1_1 32
 '@S9S_MB_2U_LIB.S9S_MB_2U(SCH_1):PAGE275_I89@PURE_QUANTA.ISL99390FRZTR5935(CHIPS)':
 'PHASE': CDS_PINID='PHASE';
NET_NAME
'SW_PVCCFA_EHV_FIVRA_CPU1_BOOTR2'
 '@S9S_MB_2U_LIB.S9S_MB_2U(SCH_1):SW_PVCCFA_EHV_FIVRA_CPU1_BOOTR2':
 C_SIGNAL='@s9s_mb_2u_lib.s9s_mb_2u(sch_1):sw_pvccfa_ehv_fivra_cpu1_bootr2';
NODE_NAME     PU76_P1_2 32
 '@S9S_MB_2U_LIB.S9S_MB_2U(SCH_1):PAGE275_I9@PURE_QUANTA.ISL99390FRZTR5935(CHIPS)':
 'PHASE': CDS_PINID='PHASE';
NODE_NAME     PC402 2
 '@S9S_MB_2U_LIB.S9S_MB_2U(SCH_1):PAGE275_I43@PURE_QUANTA.Q_CAP(CHIPS)':
 'B': CDS_PINID='B';
NET_NAME
'SW_PVCCFA_EHV_FIVRA_CPU1_BOOTR3'
 '@S9S_MB_2U_LIB.S9S_MB_2U(SCH_1):SW_PVCCFA_EHV_FIVRA_CPU1_BOOTR3':
 C_SIGNAL='@s9s_mb_2u_lib.s9s_mb_2u(sch_1):sw_pvccfa_ehv_fivra_cpu1_bootr3';
NODE_NAME     PU77_P1_3 32
 '@S9S_MB_2U_LIB.S9S_MB_2U(SCH_1):PAGE276_I24@PURE_QUANTA.ISL99390FRZTR5935(CHIPS)':
 'PHASE': CDS_PINID='PHASE';
NODE_NAME     PC1197 2
 '@S9S_MB_2U_LIB.S9S_MB_2U(SCH_1):PAGE276_I58@PURE_QUANTA.Q_CAP(CHIPS)':
 'B': CDS_PINID='B';
NET_NAME
'SW_PVCCFA_EHV_FIVRA_CPU1_BOOTR4'
 '@S9S_MB_2U_LIB.S9S_MB_2U(SCH_1):SW_PVCCFA_EHV_FIVRA_CPU1_BOOTR4':
 C_SIGNAL='@s9s_mb_2u_lib.s9s_mb_2u(sch_1):sw_pvccfa_ehv_fivra_cpu1_bootr4';
NODE_NAME     PC1198 2
 '@S9S_MB_2U_LIB.S9S_MB_2U(SCH_1):PAGE276_I45@PURE_QUANTA.Q_CAP(CHIPS)':
 'B': CDS_PINID='B';
NODE_NAME     PU78_P1_4 32
 '@S9S_MB_2U_LIB.S9S_MB_2U(SCH_1):PAGE276_I15@PURE_QUANTA.ISL99390FRZTR5935(CHIPS)':
 'PHASE': CDS_PINID='PHASE';
NET_NAME
'SW_PVCCFA_EHV_FIVRA_CPU1_SW1'
 '@S9S_MB_2U_LIB.S9S_MB_2U(SCH_1):SW_PVCCFA_EHV_FIVRA_CPU1_SW1':
 C_SIGNAL='@s9s_mb_2u_lib.s9s_mb_2u(sch_1):sw_pvccfa_ehv_fivra_cpu1_sw1';
NODE_NAME     PL18 1
 '@S9S_MB_2U_LIB.S9S_MB_2U(SCH_1):PAGE275_I55@PURE_QUANTA.Q_INDUCTOR(CHIPS)':
 '1': CDS_PINID='\1\';
NODE_NAME     PU75_P1_1 10_19
 '@S9S_MB_2U_LIB.S9S_MB_2U(SCH_1):PAGE275_I89@PURE_QUANTA.ISL99390FRZTR5935(CHIPS)':
 'SW': CDS_PINID='SW';
NET_NAME
'SW_PVCCFA_EHV_FIVRA_CPU1_SW2'
 '@S9S_MB_2U_LIB.S9S_MB_2U(SCH_1):SW_PVCCFA_EHV_FIVRA_CPU1_SW2':
 C_SIGNAL='@s9s_mb_2u_lib.s9s_mb_2u(sch_1):sw_pvccfa_ehv_fivra_cpu1_sw2';
NODE_NAME     PU76_P1_2 10_19
 '@S9S_MB_2U_LIB.S9S_MB_2U(SCH_1):PAGE275_I9@PURE_QUANTA.ISL99390FRZTR5935(CHIPS)':
 'SW': CDS_PINID='SW';
NODE_NAME     PL19 1
 '@S9S_MB_2U_LIB.S9S_MB_2U(SCH_1):PAGE275_I44@PURE_QUANTA.Q_INDUCTOR(CHIPS)':
 '1': CDS_PINID='\1\';
NET_NAME
'SW_PVCCFA_EHV_FIVRA_CPU1_SW3'
 '@S9S_MB_2U_LIB.S9S_MB_2U(SCH_1):SW_PVCCFA_EHV_FIVRA_CPU1_SW3':
 C_SIGNAL='@s9s_mb_2u_lib.s9s_mb_2u(sch_1):sw_pvccfa_ehv_fivra_cpu1_sw3';
NODE_NAME     PL12 1
 '@S9S_MB_2U_LIB.S9S_MB_2U(SCH_1):PAGE276_I57@PURE_QUANTA.Q_INDUCTOR(CHIPS)':
 '1': CDS_PINID='\1\';
NODE_NAME     PU77_P1_3 10_19
 '@S9S_MB_2U_LIB.S9S_MB_2U(SCH_1):PAGE276_I24@PURE_QUANTA.ISL99390FRZTR5935(CHIPS)':
 'SW': CDS_PINID='SW';
NET_NAME
'SW_PVCCFA_EHV_FIVRA_CPU1_SW4'
 '@S9S_MB_2U_LIB.S9S_MB_2U(SCH_1):SW_PVCCFA_EHV_FIVRA_CPU1_SW4':
 C_SIGNAL='@s9s_mb_2u_lib.s9s_mb_2u(sch_1):sw_pvccfa_ehv_fivra_cpu1_sw4';
NODE_NAME     PL113 1
 '@S9S_MB_2U_LIB.S9S_MB_2U(SCH_1):PAGE276_I44@PURE_QUANTA.Q_INDUCTOR(CHIPS)':
 '1': CDS_PINID='\1\';
NODE_NAME     PU78_P1_4 10_19
 '@S9S_MB_2U_LIB.S9S_MB_2U(SCH_1):PAGE276_I15@PURE_QUANTA.ISL99390FRZTR5935(CHIPS)':
 'SW': CDS_PINID='SW';
NET_NAME
'SW_PVCCINFAON_CPU0_BOOT1'
 '@S9S_MB_2U_LIB.S9S_MB_2U(SCH_1):SW_PVCCINFAON_CPU0_BOOT1':
 C_SIGNAL='@s9s_mb_2u_lib.s9s_mb_2u(sch_1):sw_pvccinfaon_cpu0_boot1';
NODE_NAME     PR1774 1
 '@S9S_MB_2U_LIB.S9S_MB_2U(SCH_1):PAGE261_I47@PURE_QUANTA.Q_RES(CHIPS)':
 'A': CDS_PINID='A';
NODE_NAME     PU43_P0_1 33
 '@S9S_MB_2U_LIB.S9S_MB_2U(SCH_1):PAGE261_I79@PURE_QUANTA.ISL99390FRZTR5935(CHIPS)':
 'BOOT': CDS_PINID='BOOT';
NET_NAME
'SW_PVCCINFAON_CPU0_BOOT1_R'
 '@S9S_MB_2U_LIB.S9S_MB_2U(SCH_1):SW_PVCCINFAON_CPU0_BOOT1_R':
 C_SIGNAL='@s9s_mb_2u_lib.s9s_mb_2u(sch_1):sw_pvccinfaon_cpu0_boot1_r';
NODE_NAME     PR1774 2
 '@S9S_MB_2U_LIB.S9S_MB_2U(SCH_1):PAGE261_I47@PURE_QUANTA.Q_RES(CHIPS)':
 'B': CDS_PINID='B';
NODE_NAME     PC193 1
 '@S9S_MB_2U_LIB.S9S_MB_2U(SCH_1):PAGE261_I51@PURE_QUANTA.Q_CAP(CHIPS)':
 'A': CDS_PINID='A';
NET_NAME
'SW_PVCCINFAON_CPU0_BOOT2'
 '@S9S_MB_2U_LIB.S9S_MB_2U(SCH_1):SW_PVCCINFAON_CPU0_BOOT2':
 C_SIGNAL='@s9s_mb_2u_lib.s9s_mb_2u(sch_1):sw_pvccinfaon_cpu0_boot2';
NODE_NAME     PU44_P0_2 33
 '@S9S_MB_2U_LIB.S9S_MB_2U(SCH_1):PAGE261_I12@PURE_QUANTA.ISL99390FRZTR5935(CHIPS)':
 'BOOT': CDS_PINID='BOOT';
NODE_NAME     PR1775 1
 '@S9S_MB_2U_LIB.S9S_MB_2U(SCH_1):PAGE261_I34@PURE_QUANTA.Q_RES(CHIPS)':
 'A': CDS_PINID='A';
NET_NAME
'SW_PVCCINFAON_CPU0_BOOT2_R'
 '@S9S_MB_2U_LIB.S9S_MB_2U(SCH_1):SW_PVCCINFAON_CPU0_BOOT2_R':
 C_SIGNAL='@s9s_mb_2u_lib.s9s_mb_2u(sch_1):sw_pvccinfaon_cpu0_boot2_r';
NODE_NAME     PR1775 2
 '@S9S_MB_2U_LIB.S9S_MB_2U(SCH_1):PAGE261_I34@PURE_QUANTA.Q_RES(CHIPS)':
 'B': CDS_PINID='B';
NODE_NAME     PC194 1
 '@S9S_MB_2U_LIB.S9S_MB_2U(SCH_1):PAGE261_I38@PURE_QUANTA.Q_CAP(CHIPS)':
 'A': CDS_PINID='A';
NET_NAME
'SW_PVCCINFAON_CPU0_BOOTR1'
 '@S9S_MB_2U_LIB.S9S_MB_2U(SCH_1):SW_PVCCINFAON_CPU0_BOOTR1':
 C_SIGNAL='@s9s_mb_2u_lib.s9s_mb_2u(sch_1):sw_pvccinfaon_cpu0_bootr1';
NODE_NAME     PC193 2
 '@S9S_MB_2U_LIB.S9S_MB_2U(SCH_1):PAGE261_I51@PURE_QUANTA.Q_CAP(CHIPS)':
 'B': CDS_PINID='B';
NODE_NAME     PU43_P0_1 32
 '@S9S_MB_2U_LIB.S9S_MB_2U(SCH_1):PAGE261_I79@PURE_QUANTA.ISL99390FRZTR5935(CHIPS)':
 'PHASE': CDS_PINID='PHASE';
NET_NAME
'SW_PVCCINFAON_CPU0_BOOTR2'
 '@S9S_MB_2U_LIB.S9S_MB_2U(SCH_1):SW_PVCCINFAON_CPU0_BOOTR2':
 C_SIGNAL='@s9s_mb_2u_lib.s9s_mb_2u(sch_1):sw_pvccinfaon_cpu0_bootr2';
NODE_NAME     PU44_P0_2 32
 '@S9S_MB_2U_LIB.S9S_MB_2U(SCH_1):PAGE261_I12@PURE_QUANTA.ISL99390FRZTR5935(CHIPS)':
 'PHASE': CDS_PINID='PHASE';
NODE_NAME     PC194 2
 '@S9S_MB_2U_LIB.S9S_MB_2U(SCH_1):PAGE261_I38@PURE_QUANTA.Q_CAP(CHIPS)':
 'B': CDS_PINID='B';
NET_NAME
'SW_PVCCINFAON_CPU0_SW1'
 '@S9S_MB_2U_LIB.S9S_MB_2U(SCH_1):SW_PVCCINFAON_CPU0_SW1':
 C_SIGNAL='@s9s_mb_2u_lib.s9s_mb_2u(sch_1):sw_pvccinfaon_cpu0_sw1';
NODE_NAME     PL4 1
 '@S9S_MB_2U_LIB.S9S_MB_2U(SCH_1):PAGE261_I52@PURE_QUANTA.Q_INDUCTOR(CHIPS)':
 '1': CDS_PINID='\1\';
NODE_NAME     PU43_P0_1 10_19
 '@S9S_MB_2U_LIB.S9S_MB_2U(SCH_1):PAGE261_I79@PURE_QUANTA.ISL99390FRZTR5935(CHIPS)':
 'SW': CDS_PINID='SW';
NET_NAME
'SW_PVCCINFAON_CPU0_SW2'
 '@S9S_MB_2U_LIB.S9S_MB_2U(SCH_1):SW_PVCCINFAON_CPU0_SW2':
 C_SIGNAL='@s9s_mb_2u_lib.s9s_mb_2u(sch_1):sw_pvccinfaon_cpu0_sw2';
NODE_NAME     PU44_P0_2 10_19
 '@S9S_MB_2U_LIB.S9S_MB_2U(SCH_1):PAGE261_I12@PURE_QUANTA.ISL99390FRZTR5935(CHIPS)':
 'SW': CDS_PINID='SW';
NODE_NAME     PL5 1
 '@S9S_MB_2U_LIB.S9S_MB_2U(SCH_1):PAGE261_I39@PURE_QUANTA.Q_INDUCTOR(CHIPS)':
 '1': CDS_PINID='\1\';
NET_NAME
'SW_PVCCINFAON_CPU1_BOOT1'
 '@S9S_MB_2U_LIB.S9S_MB_2U(SCH_1):SW_PVCCINFAON_CPU1_BOOT1':
 C_SIGNAL='@s9s_mb_2u_lib.s9s_mb_2u(sch_1):sw_pvccinfaon_cpu1_boot1';
NODE_NAME     PU50_P1_1 33
 '@S9S_MB_2U_LIB.S9S_MB_2U(SCH_1):PAGE279_I38@PURE_QUANTA.ISL99390FRZTR5935(CHIPS)':
 'BOOT': CDS_PINID='BOOT';
NODE_NAME     PR1794 1
 '@S9S_MB_2U_LIB.S9S_MB_2U(SCH_1):PAGE279_I50@PURE_QUANTA.Q_RES(CHIPS)':
 'A': CDS_PINID='A';
NET_NAME
'SW_PVCCINFAON_CPU1_BOOT1_R'
 '@S9S_MB_2U_LIB.S9S_MB_2U(SCH_1):SW_PVCCINFAON_CPU1_BOOT1_R':
 C_SIGNAL='@s9s_mb_2u_lib.s9s_mb_2u(sch_1):sw_pvccinfaon_cpu1_boot1_r';
NODE_NAME     PC446 1
 '@S9S_MB_2U_LIB.S9S_MB_2U(SCH_1):PAGE279_I52@PURE_QUANTA.Q_CAP(CHIPS)':
 'A': CDS_PINID='A';
NODE_NAME     PR1794 2
 '@S9S_MB_2U_LIB.S9S_MB_2U(SCH_1):PAGE279_I50@PURE_QUANTA.Q_RES(CHIPS)':
 'B': CDS_PINID='B';
NET_NAME
'SW_PVCCINFAON_CPU1_BOOT2'
 '@S9S_MB_2U_LIB.S9S_MB_2U(SCH_1):SW_PVCCINFAON_CPU1_BOOT2':
 C_SIGNAL='@s9s_mb_2u_lib.s9s_mb_2u(sch_1):sw_pvccinfaon_cpu1_boot2';
NODE_NAME     PU51_P1_2 33
 '@S9S_MB_2U_LIB.S9S_MB_2U(SCH_1):PAGE279_I29@PURE_QUANTA.ISL99390FRZTR5935(CHIPS)':
 'BOOT': CDS_PINID='BOOT';
NODE_NAME     PR1795 1
 '@S9S_MB_2U_LIB.S9S_MB_2U(SCH_1):PAGE279_I42@PURE_QUANTA.Q_RES(CHIPS)':
 'A': CDS_PINID='A';
NET_NAME
'SW_PVCCINFAON_CPU1_BOOT2_R'
 '@S9S_MB_2U_LIB.S9S_MB_2U(SCH_1):SW_PVCCINFAON_CPU1_BOOT2_R':
 C_SIGNAL='@s9s_mb_2u_lib.s9s_mb_2u(sch_1):sw_pvccinfaon_cpu1_boot2_r';
NODE_NAME     PR1795 2
 '@S9S_MB_2U_LIB.S9S_MB_2U(SCH_1):PAGE279_I42@PURE_QUANTA.Q_RES(CHIPS)':
 'B': CDS_PINID='B';
NODE_NAME     PC447 1
 '@S9S_MB_2U_LIB.S9S_MB_2U(SCH_1):PAGE279_I44@PURE_QUANTA.Q_CAP(CHIPS)':
 'A': CDS_PINID='A';
NET_NAME
'SW_PVCCINFAON_CPU1_BOOTR1'
 '@S9S_MB_2U_LIB.S9S_MB_2U(SCH_1):SW_PVCCINFAON_CPU1_BOOTR1':
 C_SIGNAL='@s9s_mb_2u_lib.s9s_mb_2u(sch_1):sw_pvccinfaon_cpu1_bootr1';
NODE_NAME     PU50_P1_1 32
 '@S9S_MB_2U_LIB.S9S_MB_2U(SCH_1):PAGE279_I38@PURE_QUANTA.ISL99390FRZTR5935(CHIPS)':
 'PHASE': CDS_PINID='PHASE';
NODE_NAME     PC446 2
 '@S9S_MB_2U_LIB.S9S_MB_2U(SCH_1):PAGE279_I52@PURE_QUANTA.Q_CAP(CHIPS)':
 'B': CDS_PINID='B';
NET_NAME
'SW_PVCCINFAON_CPU1_BOOTR2'
 '@S9S_MB_2U_LIB.S9S_MB_2U(SCH_1):SW_PVCCINFAON_CPU1_BOOTR2':
 C_SIGNAL='@s9s_mb_2u_lib.s9s_mb_2u(sch_1):sw_pvccinfaon_cpu1_bootr2';
NODE_NAME     PU51_P1_2 32
 '@S9S_MB_2U_LIB.S9S_MB_2U(SCH_1):PAGE279_I29@PURE_QUANTA.ISL99390FRZTR5935(CHIPS)':
 'PHASE': CDS_PINID='PHASE';
NODE_NAME     PC447 2
 '@S9S_MB_2U_LIB.S9S_MB_2U(SCH_1):PAGE279_I44@PURE_QUANTA.Q_CAP(CHIPS)':
 'B': CDS_PINID='B';
NET_NAME
'SW_PVCCINFAON_CPU1_SW1'
 '@S9S_MB_2U_LIB.S9S_MB_2U(SCH_1):SW_PVCCINFAON_CPU1_SW1':
 C_SIGNAL='@s9s_mb_2u_lib.s9s_mb_2u(sch_1):sw_pvccinfaon_cpu1_sw1';
NODE_NAME     PU50_P1_1 10_19
 '@S9S_MB_2U_LIB.S9S_MB_2U(SCH_1):PAGE279_I38@PURE_QUANTA.ISL99390FRZTR5935(CHIPS)':
 'SW': CDS_PINID='SW';
NODE_NAME     PL21 1
 '@S9S_MB_2U_LIB.S9S_MB_2U(SCH_1):PAGE279_I54@PURE_QUANTA.Q_INDUCTOR(CHIPS)':
 '1': CDS_PINID='\1\';
NET_NAME
'SW_PVCCINFAON_CPU1_SW2'
 '@S9S_MB_2U_LIB.S9S_MB_2U(SCH_1):SW_PVCCINFAON_CPU1_SW2':
 C_SIGNAL='@s9s_mb_2u_lib.s9s_mb_2u(sch_1):sw_pvccinfaon_cpu1_sw2';
NODE_NAME     PU51_P1_2 10_19
 '@S9S_MB_2U_LIB.S9S_MB_2U(SCH_1):PAGE279_I29@PURE_QUANTA.ISL99390FRZTR5935(CHIPS)':
 'SW': CDS_PINID='SW';
NODE_NAME     PL22 1
 '@S9S_MB_2U_LIB.S9S_MB_2U(SCH_1):PAGE279_I46@PURE_QUANTA.Q_INDUCTOR(CHIPS)':
 '1': CDS_PINID='\1\';
NET_NAME
'SW_PVCCIN_CPU0_BOOT1'
 '@S9S_MB_2U_LIB.S9S_MB_2U(SCH_1):SW_PVCCIN_CPU0_BOOT1':
 C_SIGNAL='@s9s_mb_2u_lib.s9s_mb_2u(sch_1):sw_pvccin_cpu0_boot1';
NODE_NAME     PU13_P0_1 33
 '@S9S_MB_2U_LIB.S9S_MB_2U(SCH_1):PAGE253_I40@PURE_QUANTA.ISL99390FRZTR5935(CHIPS)':
 'BOOT': CDS_PINID='BOOT';
NODE_NAME     PR1787 1
 '@S9S_MB_2U_LIB.S9S_MB_2U(SCH_1):PAGE253_I97@PURE_QUANTA.Q_RES(CHIPS)':
 'A': CDS_PINID='A';
NET_NAME
'SW_PVCCIN_CPU0_BOOT1_R'
 '@S9S_MB_2U_LIB.S9S_MB_2U(SCH_1):SW_PVCCIN_CPU0_BOOT1_R':
 C_SIGNAL='@s9s_mb_2u_lib.s9s_mb_2u(sch_1):sw_pvccin_cpu0_boot1_r';
NODE_NAME     PC301 1
 '@S9S_MB_2U_LIB.S9S_MB_2U(SCH_1):PAGE253_I48@PURE_QUANTA.Q_CAP(CHIPS)':
 'A': CDS_PINID='A';
NODE_NAME     PR1787 2
 '@S9S_MB_2U_LIB.S9S_MB_2U(SCH_1):PAGE253_I97@PURE_QUANTA.Q_RES(CHIPS)':
 'B': CDS_PINID='B';
NET_NAME
'SW_PVCCIN_CPU0_BOOT2'
 '@S9S_MB_2U_LIB.S9S_MB_2U(SCH_1):SW_PVCCIN_CPU0_BOOT2':
 C_SIGNAL='@s9s_mb_2u_lib.s9s_mb_2u(sch_1):sw_pvccin_cpu0_boot2';
NODE_NAME     PU12_P0_2 33
 '@S9S_MB_2U_LIB.S9S_MB_2U(SCH_1):PAGE253_I6@PURE_QUANTA.ISL99390FRZTR5935(CHIPS)':
 'BOOT': CDS_PINID='BOOT';
NODE_NAME     PR1786 1
 '@S9S_MB_2U_LIB.S9S_MB_2U(SCH_1):PAGE253_I18@PURE_QUANTA.Q_RES(CHIPS)':
 'A': CDS_PINID='A';
NET_NAME
'SW_PVCCIN_CPU0_BOOT2_R'
 '@S9S_MB_2U_LIB.S9S_MB_2U(SCH_1):SW_PVCCIN_CPU0_BOOT2_R':
 C_SIGNAL='@s9s_mb_2u_lib.s9s_mb_2u(sch_1):sw_pvccin_cpu0_boot2_r';
NODE_NAME     PR1786 2
 '@S9S_MB_2U_LIB.S9S_MB_2U(SCH_1):PAGE253_I18@PURE_QUANTA.Q_RES(CHIPS)':
 'B': CDS_PINID='B';
NODE_NAME     PC300 1
 '@S9S_MB_2U_LIB.S9S_MB_2U(SCH_1):PAGE253_I20@PURE_QUANTA.Q_CAP(CHIPS)':
 'A': CDS_PINID='A';
NET_NAME
'SW_PVCCIN_CPU0_BOOT3'
 '@S9S_MB_2U_LIB.S9S_MB_2U(SCH_1):SW_PVCCIN_CPU0_BOOT3':
 C_SIGNAL='@s9s_mb_2u_lib.s9s_mb_2u(sch_1):sw_pvccin_cpu0_boot3';
NODE_NAME     PR1769 1
 '@S9S_MB_2U_LIB.S9S_MB_2U(SCH_1):PAGE254_I49@PURE_QUANTA.Q_RES(CHIPS)':
 'A': CDS_PINID='A';
NODE_NAME     PU11_P0_3 33
 '@S9S_MB_2U_LIB.S9S_MB_2U(SCH_1):PAGE254_I20@PURE_QUANTA.ISL99390FRZTR5935(CHIPS)':
 'BOOT': CDS_PINID='BOOT';
NET_NAME
'SW_PVCCIN_CPU0_BOOT3_R'
 '@S9S_MB_2U_LIB.S9S_MB_2U(SCH_1):SW_PVCCIN_CPU0_BOOT3_R':
 C_SIGNAL='@s9s_mb_2u_lib.s9s_mb_2u(sch_1):sw_pvccin_cpu0_boot3_r';
NODE_NAME     PR1769 2
 '@S9S_MB_2U_LIB.S9S_MB_2U(SCH_1):PAGE254_I49@PURE_QUANTA.Q_RES(CHIPS)':
 'B': CDS_PINID='B';
NODE_NAME     PC279 1
 '@S9S_MB_2U_LIB.S9S_MB_2U(SCH_1):PAGE254_I51@PURE_QUANTA.Q_CAP(CHIPS)':
 'A': CDS_PINID='A';
NET_NAME
'SW_PVCCIN_CPU0_BOOT4'
 '@S9S_MB_2U_LIB.S9S_MB_2U(SCH_1):SW_PVCCIN_CPU0_BOOT4':
 C_SIGNAL='@s9s_mb_2u_lib.s9s_mb_2u(sch_1):sw_pvccin_cpu0_boot4';
NODE_NAME     PU10_P0_4 33
 '@S9S_MB_2U_LIB.S9S_MB_2U(SCH_1):PAGE254_I13@PURE_QUANTA.ISL99390FRZTR5935(CHIPS)':
 'BOOT': CDS_PINID='BOOT';
NODE_NAME     PR1768 1
 '@S9S_MB_2U_LIB.S9S_MB_2U(SCH_1):PAGE254_I36@PURE_QUANTA.Q_RES(CHIPS)':
 'A': CDS_PINID='A';
NET_NAME
'SW_PVCCIN_CPU0_BOOT4_R'
 '@S9S_MB_2U_LIB.S9S_MB_2U(SCH_1):SW_PVCCIN_CPU0_BOOT4_R':
 C_SIGNAL='@s9s_mb_2u_lib.s9s_mb_2u(sch_1):sw_pvccin_cpu0_boot4_r';
NODE_NAME     PR1768 2
 '@S9S_MB_2U_LIB.S9S_MB_2U(SCH_1):PAGE254_I36@PURE_QUANTA.Q_RES(CHIPS)':
 'B': CDS_PINID='B';
NODE_NAME     PC278 1
 '@S9S_MB_2U_LIB.S9S_MB_2U(SCH_1):PAGE254_I34@PURE_QUANTA.Q_CAP(CHIPS)':
 'A': CDS_PINID='A';
NET_NAME
'SW_PVCCIN_CPU0_BOOT5'
 '@S9S_MB_2U_LIB.S9S_MB_2U(SCH_1):SW_PVCCIN_CPU0_BOOT5':
 C_SIGNAL='@s9s_mb_2u_lib.s9s_mb_2u(sch_1):sw_pvccin_cpu0_boot5';
NODE_NAME     PR1771 1
 '@S9S_MB_2U_LIB.S9S_MB_2U(SCH_1):PAGE255_I49@PURE_QUANTA.Q_RES(CHIPS)':
 'A': CDS_PINID='A';
NODE_NAME     PU9_P0_5 33
 '@S9S_MB_2U_LIB.S9S_MB_2U(SCH_1):PAGE255_I66@PURE_QUANTA.ISL99390FRZTR5935(CHIPS)':
 'BOOT': CDS_PINID='BOOT';
NET_NAME
'SW_PVCCIN_CPU0_BOOT5_R'
 '@S9S_MB_2U_LIB.S9S_MB_2U(SCH_1):SW_PVCCIN_CPU0_BOOT5_R':
 C_SIGNAL='@s9s_mb_2u_lib.s9s_mb_2u(sch_1):sw_pvccin_cpu0_boot5_r';
NODE_NAME     PR1771 2
 '@S9S_MB_2U_LIB.S9S_MB_2U(SCH_1):PAGE255_I49@PURE_QUANTA.Q_RES(CHIPS)':
 'B': CDS_PINID='B';
NODE_NAME     PC257 1
 '@S9S_MB_2U_LIB.S9S_MB_2U(SCH_1):PAGE255_I51@PURE_QUANTA.Q_CAP(CHIPS)':
 'A': CDS_PINID='A';
NET_NAME
'SW_PVCCIN_CPU0_BOOT6'
 '@S9S_MB_2U_LIB.S9S_MB_2U(SCH_1):SW_PVCCIN_CPU0_BOOT6':
 C_SIGNAL='@s9s_mb_2u_lib.s9s_mb_2u(sch_1):sw_pvccin_cpu0_boot6';
NODE_NAME     PU8_P0_6 33
 '@S9S_MB_2U_LIB.S9S_MB_2U(SCH_1):PAGE255_I12@PURE_QUANTA.ISL99390FRZTR5935(CHIPS)':
 'BOOT': CDS_PINID='BOOT';
NODE_NAME     PR1770 1
 '@S9S_MB_2U_LIB.S9S_MB_2U(SCH_1):PAGE255_I35@PURE_QUANTA.Q_RES(CHIPS)':
 'A': CDS_PINID='A';
NET_NAME
'SW_PVCCIN_CPU0_BOOT6_R'
 '@S9S_MB_2U_LIB.S9S_MB_2U(SCH_1):SW_PVCCIN_CPU0_BOOT6_R':
 C_SIGNAL='@s9s_mb_2u_lib.s9s_mb_2u(sch_1):sw_pvccin_cpu0_boot6_r';
NODE_NAME     PC256 1
 '@S9S_MB_2U_LIB.S9S_MB_2U(SCH_1):PAGE255_I33@PURE_QUANTA.Q_CAP(CHIPS)':
 'A': CDS_PINID='A';
NODE_NAME     PR1770 2
 '@S9S_MB_2U_LIB.S9S_MB_2U(SCH_1):PAGE255_I35@PURE_QUANTA.Q_RES(CHIPS)':
 'B': CDS_PINID='B';
NET_NAME
'SW_PVCCIN_CPU0_BOOT7'
 '@S9S_MB_2U_LIB.S9S_MB_2U(SCH_1):SW_PVCCIN_CPU0_BOOT7':
 C_SIGNAL='@s9s_mb_2u_lib.s9s_mb_2u(sch_1):sw_pvccin_cpu0_boot7';
NODE_NAME     PR1773 1
 '@S9S_MB_2U_LIB.S9S_MB_2U(SCH_1):PAGE256_I40@PURE_QUANTA.Q_RES(CHIPS)':
 'A': CDS_PINID='A';
NODE_NAME     PU7_P0_7 33
 '@S9S_MB_2U_LIB.S9S_MB_2U(SCH_1):PAGE256_I32@PURE_QUANTA.ISL99390FRZTR5935(CHIPS)':
 'BOOT': CDS_PINID='BOOT';
NET_NAME
'SW_PVCCIN_CPU0_BOOT7_R'
 '@S9S_MB_2U_LIB.S9S_MB_2U(SCH_1):SW_PVCCIN_CPU0_BOOT7_R':
 C_SIGNAL='@s9s_mb_2u_lib.s9s_mb_2u(sch_1):sw_pvccin_cpu0_boot7_r';
NODE_NAME     PR1773 2
 '@S9S_MB_2U_LIB.S9S_MB_2U(SCH_1):PAGE256_I40@PURE_QUANTA.Q_RES(CHIPS)':
 'B': CDS_PINID='B';
NODE_NAME     PC235 1
 '@S9S_MB_2U_LIB.S9S_MB_2U(SCH_1):PAGE256_I59@PURE_QUANTA.Q_CAP(CHIPS)':
 'A': CDS_PINID='A';
NET_NAME
'SW_PVCCIN_CPU0_BOOT8'
 '@S9S_MB_2U_LIB.S9S_MB_2U(SCH_1):SW_PVCCIN_CPU0_BOOT8':
 C_SIGNAL='@s9s_mb_2u_lib.s9s_mb_2u(sch_1):sw_pvccin_cpu0_boot8';
NODE_NAME     PU6_P0_8 33
 '@S9S_MB_2U_LIB.S9S_MB_2U(SCH_1):PAGE256_I2@PURE_QUANTA.ISL99390FRZTR5935(CHIPS)':
 'BOOT': CDS_PINID='BOOT';
NODE_NAME     PR1772 1
 '@S9S_MB_2U_LIB.S9S_MB_2U(SCH_1):PAGE256_I19@PURE_QUANTA.Q_RES(CHIPS)':
 'A': CDS_PINID='A';
NET_NAME
'SW_PVCCIN_CPU0_BOOT8_R'
 '@S9S_MB_2U_LIB.S9S_MB_2U(SCH_1):SW_PVCCIN_CPU0_BOOT8_R':
 C_SIGNAL='@s9s_mb_2u_lib.s9s_mb_2u(sch_1):sw_pvccin_cpu0_boot8_r';
NODE_NAME     PR1772 2
 '@S9S_MB_2U_LIB.S9S_MB_2U(SCH_1):PAGE256_I19@PURE_QUANTA.Q_RES(CHIPS)':
 'B': CDS_PINID='B';
NODE_NAME     PC234 1
 '@S9S_MB_2U_LIB.S9S_MB_2U(SCH_1):PAGE256_I45@PURE_QUANTA.Q_CAP(CHIPS)':
 'A': CDS_PINID='A';
NET_NAME
'SW_PVCCIN_CPU0_BOOTR1'
 '@S9S_MB_2U_LIB.S9S_MB_2U(SCH_1):SW_PVCCIN_CPU0_BOOTR1':
 C_SIGNAL='@s9s_mb_2u_lib.s9s_mb_2u(sch_1):sw_pvccin_cpu0_bootr1';
NODE_NAME     PU13_P0_1 32
 '@S9S_MB_2U_LIB.S9S_MB_2U(SCH_1):PAGE253_I40@PURE_QUANTA.ISL99390FRZTR5935(CHIPS)':
 'PHASE': CDS_PINID='PHASE';
NODE_NAME     PC301 2
 '@S9S_MB_2U_LIB.S9S_MB_2U(SCH_1):PAGE253_I48@PURE_QUANTA.Q_CAP(CHIPS)':
 'B': CDS_PINID='B';
NET_NAME
'SW_PVCCIN_CPU0_BOOTR2'
 '@S9S_MB_2U_LIB.S9S_MB_2U(SCH_1):SW_PVCCIN_CPU0_BOOTR2':
 C_SIGNAL='@s9s_mb_2u_lib.s9s_mb_2u(sch_1):sw_pvccin_cpu0_bootr2';
NODE_NAME     PU12_P0_2 32
 '@S9S_MB_2U_LIB.S9S_MB_2U(SCH_1):PAGE253_I6@PURE_QUANTA.ISL99390FRZTR5935(CHIPS)':
 'PHASE': CDS_PINID='PHASE';
NODE_NAME     PC300 2
 '@S9S_MB_2U_LIB.S9S_MB_2U(SCH_1):PAGE253_I20@PURE_QUANTA.Q_CAP(CHIPS)':
 'B': CDS_PINID='B';
NET_NAME
'SW_PVCCIN_CPU0_BOOTR3'
 '@S9S_MB_2U_LIB.S9S_MB_2U(SCH_1):SW_PVCCIN_CPU0_BOOTR3':
 C_SIGNAL='@s9s_mb_2u_lib.s9s_mb_2u(sch_1):sw_pvccin_cpu0_bootr3';
NODE_NAME     PC279 2
 '@S9S_MB_2U_LIB.S9S_MB_2U(SCH_1):PAGE254_I51@PURE_QUANTA.Q_CAP(CHIPS)':
 'B': CDS_PINID='B';
NODE_NAME     PU11_P0_3 32
 '@S9S_MB_2U_LIB.S9S_MB_2U(SCH_1):PAGE254_I20@PURE_QUANTA.ISL99390FRZTR5935(CHIPS)':
 'PHASE': CDS_PINID='PHASE';
NET_NAME
'SW_PVCCIN_CPU0_BOOTR4'
 '@S9S_MB_2U_LIB.S9S_MB_2U(SCH_1):SW_PVCCIN_CPU0_BOOTR4':
 C_SIGNAL='@s9s_mb_2u_lib.s9s_mb_2u(sch_1):sw_pvccin_cpu0_bootr4';
NODE_NAME     PU10_P0_4 32
 '@S9S_MB_2U_LIB.S9S_MB_2U(SCH_1):PAGE254_I13@PURE_QUANTA.ISL99390FRZTR5935(CHIPS)':
 'PHASE': CDS_PINID='PHASE';
NODE_NAME     PC278 2
 '@S9S_MB_2U_LIB.S9S_MB_2U(SCH_1):PAGE254_I34@PURE_QUANTA.Q_CAP(CHIPS)':
 'B': CDS_PINID='B';
NET_NAME
'SW_PVCCIN_CPU0_BOOTR5'
 '@S9S_MB_2U_LIB.S9S_MB_2U(SCH_1):SW_PVCCIN_CPU0_BOOTR5':
 C_SIGNAL='@s9s_mb_2u_lib.s9s_mb_2u(sch_1):sw_pvccin_cpu0_bootr5';
NODE_NAME     PC257 2
 '@S9S_MB_2U_LIB.S9S_MB_2U(SCH_1):PAGE255_I51@PURE_QUANTA.Q_CAP(CHIPS)':
 'B': CDS_PINID='B';
NODE_NAME     PU9_P0_5 32
 '@S9S_MB_2U_LIB.S9S_MB_2U(SCH_1):PAGE255_I66@PURE_QUANTA.ISL99390FRZTR5935(CHIPS)':
 'PHASE': CDS_PINID='PHASE';
NET_NAME
'SW_PVCCIN_CPU0_BOOTR6'
 '@S9S_MB_2U_LIB.S9S_MB_2U(SCH_1):SW_PVCCIN_CPU0_BOOTR6':
 C_SIGNAL='@s9s_mb_2u_lib.s9s_mb_2u(sch_1):sw_pvccin_cpu0_bootr6';
NODE_NAME     PU8_P0_6 32
 '@S9S_MB_2U_LIB.S9S_MB_2U(SCH_1):PAGE255_I12@PURE_QUANTA.ISL99390FRZTR5935(CHIPS)':
 'PHASE': CDS_PINID='PHASE';
NODE_NAME     PC256 2
 '@S9S_MB_2U_LIB.S9S_MB_2U(SCH_1):PAGE255_I33@PURE_QUANTA.Q_CAP(CHIPS)':
 'B': CDS_PINID='B';
NET_NAME
'SW_PVCCIN_CPU0_BOOTR7'
 '@S9S_MB_2U_LIB.S9S_MB_2U(SCH_1):SW_PVCCIN_CPU0_BOOTR7':
 C_SIGNAL='@s9s_mb_2u_lib.s9s_mb_2u(sch_1):sw_pvccin_cpu0_bootr7';
NODE_NAME     PU7_P0_7 32
 '@S9S_MB_2U_LIB.S9S_MB_2U(SCH_1):PAGE256_I32@PURE_QUANTA.ISL99390FRZTR5935(CHIPS)':
 'PHASE': CDS_PINID='PHASE';
NODE_NAME     PC235 2
 '@S9S_MB_2U_LIB.S9S_MB_2U(SCH_1):PAGE256_I59@PURE_QUANTA.Q_CAP(CHIPS)':
 'B': CDS_PINID='B';
NET_NAME
'SW_PVCCIN_CPU0_BOOTR8'
 '@S9S_MB_2U_LIB.S9S_MB_2U(SCH_1):SW_PVCCIN_CPU0_BOOTR8':
 C_SIGNAL='@s9s_mb_2u_lib.s9s_mb_2u(sch_1):sw_pvccin_cpu0_bootr8';
NODE_NAME     PU6_P0_8 32
 '@S9S_MB_2U_LIB.S9S_MB_2U(SCH_1):PAGE256_I2@PURE_QUANTA.ISL99390FRZTR5935(CHIPS)':
 'PHASE': CDS_PINID='PHASE';
NODE_NAME     PC234 2
 '@S9S_MB_2U_LIB.S9S_MB_2U(SCH_1):PAGE256_I45@PURE_QUANTA.Q_CAP(CHIPS)':
 'B': CDS_PINID='B';
NET_NAME
'SW_PVCCIN_CPU0_SW1'
 '@S9S_MB_2U_LIB.S9S_MB_2U(SCH_1):SW_PVCCIN_CPU0_SW1':
 C_SIGNAL='@s9s_mb_2u_lib.s9s_mb_2u(sch_1):sw_pvccin_cpu0_sw1';
NODE_NAME     PU13_P0_1 10_19
 '@S9S_MB_2U_LIB.S9S_MB_2U(SCH_1):PAGE253_I40@PURE_QUANTA.ISL99390FRZTR5935(CHIPS)':
 'SW': CDS_PINID='SW';
NODE_NAME     PL114 1
 '@S9S_MB_2U_LIB.S9S_MB_2U(SCH_1):PAGE253_I46@PURE_QUANTA.Q_INDUCTOR4P_14(CHIPS)':
 '1': CDS_PINID='\1\';
NET_NAME
'SW_PVCCIN_CPU0_SW2'
 '@S9S_MB_2U_LIB.S9S_MB_2U(SCH_1):SW_PVCCIN_CPU0_SW2':
 C_SIGNAL='@s9s_mb_2u_lib.s9s_mb_2u(sch_1):sw_pvccin_cpu0_sw2';
NODE_NAME     PL13 1
 '@S9S_MB_2U_LIB.S9S_MB_2U(SCH_1):PAGE253_I21@PURE_QUANTA.Q_INDUCTOR4P_14(CHIPS)':
 '1': CDS_PINID='\1\';
NODE_NAME     PU12_P0_2 10_19
 '@S9S_MB_2U_LIB.S9S_MB_2U(SCH_1):PAGE253_I6@PURE_QUANTA.ISL99390FRZTR5935(CHIPS)':
 'SW': CDS_PINID='SW';
NET_NAME
'SW_PVCCIN_CPU0_SW3'
 '@S9S_MB_2U_LIB.S9S_MB_2U(SCH_1):SW_PVCCIN_CPU0_SW3':
 C_SIGNAL='@s9s_mb_2u_lib.s9s_mb_2u(sch_1):sw_pvccin_cpu0_sw3';
NODE_NAME     PL112 1
 '@S9S_MB_2U_LIB.S9S_MB_2U(SCH_1):PAGE254_I50@PURE_QUANTA.Q_INDUCTOR4P_14(CHIPS)':
 '1': CDS_PINID='\1\';
NODE_NAME     PU11_P0_3 10_19
 '@S9S_MB_2U_LIB.S9S_MB_2U(SCH_1):PAGE254_I20@PURE_QUANTA.ISL99390FRZTR5935(CHIPS)':
 'SW': CDS_PINID='SW';
NET_NAME
'SW_PVCCIN_CPU0_SW4'
 '@S9S_MB_2U_LIB.S9S_MB_2U(SCH_1):SW_PVCCIN_CPU0_SW4':
 C_SIGNAL='@s9s_mb_2u_lib.s9s_mb_2u(sch_1):sw_pvccin_cpu0_sw4';
NODE_NAME     PU10_P0_4 10_19
 '@S9S_MB_2U_LIB.S9S_MB_2U(SCH_1):PAGE254_I13@PURE_QUANTA.ISL99390FRZTR5935(CHIPS)':
 'SW': CDS_PINID='SW';
NODE_NAME     PL11 1
 '@S9S_MB_2U_LIB.S9S_MB_2U(SCH_1):PAGE254_I33@PURE_QUANTA.Q_INDUCTOR4P_14(CHIPS)':
 '1': CDS_PINID='\1\';
NET_NAME
'SW_PVCCIN_CPU0_SW5'
 '@S9S_MB_2U_LIB.S9S_MB_2U(SCH_1):SW_PVCCIN_CPU0_SW5':
 C_SIGNAL='@s9s_mb_2u_lib.s9s_mb_2u(sch_1):sw_pvccin_cpu0_sw5';
NODE_NAME     PL10 1
 '@S9S_MB_2U_LIB.S9S_MB_2U(SCH_1):PAGE255_I50@PURE_QUANTA.Q_INDUCTOR4P_14(CHIPS)':
 '1': CDS_PINID='\1\';
NODE_NAME     PU9_P0_5 10_19
 '@S9S_MB_2U_LIB.S9S_MB_2U(SCH_1):PAGE255_I66@PURE_QUANTA.ISL99390FRZTR5935(CHIPS)':
 'SW': CDS_PINID='SW';
NET_NAME
'SW_PVCCIN_CPU0_SW6'
 '@S9S_MB_2U_LIB.S9S_MB_2U(SCH_1):SW_PVCCIN_CPU0_SW6':
 C_SIGNAL='@s9s_mb_2u_lib.s9s_mb_2u(sch_1):sw_pvccin_cpu0_sw6';
NODE_NAME     PU8_P0_6 10_19
 '@S9S_MB_2U_LIB.S9S_MB_2U(SCH_1):PAGE255_I12@PURE_QUANTA.ISL99390FRZTR5935(CHIPS)':
 'SW': CDS_PINID='SW';
NODE_NAME     PL9 1
 '@S9S_MB_2U_LIB.S9S_MB_2U(SCH_1):PAGE255_I32@PURE_QUANTA.Q_INDUCTOR4P_14(CHIPS)':
 '1': CDS_PINID='\1\';
NET_NAME
'SW_PVCCIN_CPU0_SW7'
 '@S9S_MB_2U_LIB.S9S_MB_2U(SCH_1):SW_PVCCIN_CPU0_SW7':
 C_SIGNAL='@s9s_mb_2u_lib.s9s_mb_2u(sch_1):sw_pvccin_cpu0_sw7';
NODE_NAME     PL8 1
 '@S9S_MB_2U_LIB.S9S_MB_2U(SCH_1):PAGE256_I58@PURE_QUANTA.Q_INDUCTOR4P_14(CHIPS)':
 '1': CDS_PINID='\1\';
NODE_NAME     PU7_P0_7 10_19
 '@S9S_MB_2U_LIB.S9S_MB_2U(SCH_1):PAGE256_I32@PURE_QUANTA.ISL99390FRZTR5935(CHIPS)':
 'SW': CDS_PINID='SW';
NET_NAME
'SW_PVCCIN_CPU0_SW8'
 '@S9S_MB_2U_LIB.S9S_MB_2U(SCH_1):SW_PVCCIN_CPU0_SW8':
 C_SIGNAL='@s9s_mb_2u_lib.s9s_mb_2u(sch_1):sw_pvccin_cpu0_sw8';
NODE_NAME     PU6_P0_8 10_19
 '@S9S_MB_2U_LIB.S9S_MB_2U(SCH_1):PAGE256_I2@PURE_QUANTA.ISL99390FRZTR5935(CHIPS)':
 'SW': CDS_PINID='SW';
NODE_NAME     PL7 1
 '@S9S_MB_2U_LIB.S9S_MB_2U(SCH_1):PAGE256_I44@PURE_QUANTA.Q_INDUCTOR4P_14(CHIPS)':
 '1': CDS_PINID='\1\';
NET_NAME
'SW_PVCCIN_CPU1_BOOT1'
 '@S9S_MB_2U_LIB.S9S_MB_2U(SCH_1):SW_PVCCIN_CPU1_BOOT1':
 C_SIGNAL='@s9s_mb_2u_lib.s9s_mb_2u(sch_1):sw_pvccin_cpu1_boot1';
NODE_NAME     PR1767 1
 '@S9S_MB_2U_LIB.S9S_MB_2U(SCH_1):PAGE271_I46@PURE_QUANTA.Q_RES(CHIPS)':
 'A': CDS_PINID='A';
NODE_NAME     PU31_P1_1 33
 '@S9S_MB_2U_LIB.S9S_MB_2U(SCH_1):PAGE271_I40@PURE_QUANTA.ISL99390FRZTR5935(CHIPS)':
 'BOOT': CDS_PINID='BOOT';
NET_NAME
'SW_PVCCIN_CPU1_BOOT1_R'
 '@S9S_MB_2U_LIB.S9S_MB_2U(SCH_1):SW_PVCCIN_CPU1_BOOT1_R':
 C_SIGNAL='@s9s_mb_2u_lib.s9s_mb_2u(sch_1):sw_pvccin_cpu1_boot1_r';
NODE_NAME     PR1767 2
 '@S9S_MB_2U_LIB.S9S_MB_2U(SCH_1):PAGE271_I46@PURE_QUANTA.Q_RES(CHIPS)':
 'B': CDS_PINID='B';
NODE_NAME     PC565 1
 '@S9S_MB_2U_LIB.S9S_MB_2U(SCH_1):PAGE271_I49@PURE_QUANTA.Q_CAP(CHIPS)':
 'A': CDS_PINID='A';
NET_NAME
'SW_PVCCIN_CPU1_BOOT2'
 '@S9S_MB_2U_LIB.S9S_MB_2U(SCH_1):SW_PVCCIN_CPU1_BOOT2':
 C_SIGNAL='@s9s_mb_2u_lib.s9s_mb_2u(sch_1):sw_pvccin_cpu1_boot2';
NODE_NAME     PR1766 1
 '@S9S_MB_2U_LIB.S9S_MB_2U(SCH_1):PAGE271_I20@PURE_QUANTA.Q_RES(CHIPS)':
 'A': CDS_PINID='A';
NODE_NAME     PU30_P1_2 33
 '@S9S_MB_2U_LIB.S9S_MB_2U(SCH_1):PAGE271_I7@PURE_QUANTA.ISL99390FRZTR5935(CHIPS)':
 'BOOT': CDS_PINID='BOOT';
NET_NAME
'SW_PVCCIN_CPU1_BOOT2_R'
 '@S9S_MB_2U_LIB.S9S_MB_2U(SCH_1):SW_PVCCIN_CPU1_BOOT2_R':
 C_SIGNAL='@s9s_mb_2u_lib.s9s_mb_2u(sch_1):sw_pvccin_cpu1_boot2_r';
NODE_NAME     PC564 1
 '@S9S_MB_2U_LIB.S9S_MB_2U(SCH_1):PAGE271_I23@PURE_QUANTA.Q_CAP(CHIPS)':
 'A': CDS_PINID='A';
NODE_NAME     PR1766 2
 '@S9S_MB_2U_LIB.S9S_MB_2U(SCH_1):PAGE271_I20@PURE_QUANTA.Q_RES(CHIPS)':
 'B': CDS_PINID='B';
NET_NAME
'SW_PVCCIN_CPU1_BOOT3'
 '@S9S_MB_2U_LIB.S9S_MB_2U(SCH_1):SW_PVCCIN_CPU1_BOOT3':
 C_SIGNAL='@s9s_mb_2u_lib.s9s_mb_2u(sch_1):sw_pvccin_cpu1_boot3';
NODE_NAME     PR1789 1
 '@S9S_MB_2U_LIB.S9S_MB_2U(SCH_1):PAGE272_I46@PURE_QUANTA.Q_RES(CHIPS)':
 'A': CDS_PINID='A';
NODE_NAME     PU28_P1_3 33
 '@S9S_MB_2U_LIB.S9S_MB_2U(SCH_1):PAGE272_I66@PURE_QUANTA.ISL99390FRZTR5935(CHIPS)':
 'BOOT': CDS_PINID='BOOT';
NET_NAME
'SW_PVCCIN_CPU1_BOOT3_R'
 '@S9S_MB_2U_LIB.S9S_MB_2U(SCH_1):SW_PVCCIN_CPU1_BOOT3_R':
 C_SIGNAL='@s9s_mb_2u_lib.s9s_mb_2u(sch_1):sw_pvccin_cpu1_boot3_r';
NODE_NAME     PR1789 2
 '@S9S_MB_2U_LIB.S9S_MB_2U(SCH_1):PAGE272_I46@PURE_QUANTA.Q_RES(CHIPS)':
 'B': CDS_PINID='B';
NODE_NAME     PC532 1
 '@S9S_MB_2U_LIB.S9S_MB_2U(SCH_1):PAGE272_I52@PURE_QUANTA.Q_CAP(CHIPS)':
 'A': CDS_PINID='A';
NET_NAME
'SW_PVCCIN_CPU1_BOOT4'
 '@S9S_MB_2U_LIB.S9S_MB_2U(SCH_1):SW_PVCCIN_CPU1_BOOT4':
 C_SIGNAL='@s9s_mb_2u_lib.s9s_mb_2u(sch_1):sw_pvccin_cpu1_boot4';
NODE_NAME     PR1788 1
 '@S9S_MB_2U_LIB.S9S_MB_2U(SCH_1):PAGE272_I34@PURE_QUANTA.Q_RES(CHIPS)':
 'A': CDS_PINID='A';
NODE_NAME     PU27_P1_4 33
 '@S9S_MB_2U_LIB.S9S_MB_2U(SCH_1):PAGE272_I10@PURE_QUANTA.ISL99390FRZTR5935(CHIPS)':
 'BOOT': CDS_PINID='BOOT';
NET_NAME
'SW_PVCCIN_CPU1_BOOT4_R'
 '@S9S_MB_2U_LIB.S9S_MB_2U(SCH_1):SW_PVCCIN_CPU1_BOOT4_R':
 C_SIGNAL='@s9s_mb_2u_lib.s9s_mb_2u(sch_1):sw_pvccin_cpu1_boot4_r';
NODE_NAME     PR1788 2
 '@S9S_MB_2U_LIB.S9S_MB_2U(SCH_1):PAGE272_I34@PURE_QUANTA.Q_RES(CHIPS)':
 'B': CDS_PINID='B';
NODE_NAME     PC531 1
 '@S9S_MB_2U_LIB.S9S_MB_2U(SCH_1):PAGE272_I39@PURE_QUANTA.Q_CAP(CHIPS)':
 'A': CDS_PINID='A';
NET_NAME
'SW_PVCCIN_CPU1_BOOT5'
 '@S9S_MB_2U_LIB.S9S_MB_2U(SCH_1):SW_PVCCIN_CPU1_BOOT5':
 C_SIGNAL='@s9s_mb_2u_lib.s9s_mb_2u(sch_1):sw_pvccin_cpu1_boot5';
NODE_NAME     PU26_P1_5 33
 '@S9S_MB_2U_LIB.S9S_MB_2U(SCH_1):PAGE273_I23@PURE_QUANTA.ISL99390FRZTR5935(CHIPS)':
 'BOOT': CDS_PINID='BOOT';
NODE_NAME     PR1791 1
 '@S9S_MB_2U_LIB.S9S_MB_2U(SCH_1):PAGE273_I44@PURE_QUANTA.Q_RES(CHIPS)':
 'A': CDS_PINID='A';
NET_NAME
'SW_PVCCIN_CPU1_BOOT5_R'
 '@S9S_MB_2U_LIB.S9S_MB_2U(SCH_1):SW_PVCCIN_CPU1_BOOT5_R':
 C_SIGNAL='@s9s_mb_2u_lib.s9s_mb_2u(sch_1):sw_pvccin_cpu1_boot5_r';
NODE_NAME     PR1791 2
 '@S9S_MB_2U_LIB.S9S_MB_2U(SCH_1):PAGE273_I44@PURE_QUANTA.Q_RES(CHIPS)':
 'B': CDS_PINID='B';
NODE_NAME     PC510 1
 '@S9S_MB_2U_LIB.S9S_MB_2U(SCH_1):PAGE273_I47@PURE_QUANTA.Q_CAP(CHIPS)':
 'A': CDS_PINID='A';
NET_NAME
'SW_PVCCIN_CPU1_BOOT6'
 '@S9S_MB_2U_LIB.S9S_MB_2U(SCH_1):SW_PVCCIN_CPU1_BOOT6':
 C_SIGNAL='@s9s_mb_2u_lib.s9s_mb_2u(sch_1):sw_pvccin_cpu1_boot6';
NODE_NAME     PU25_P1_6 33
 '@S9S_MB_2U_LIB.S9S_MB_2U(SCH_1):PAGE273_I16@PURE_QUANTA.ISL99390FRZTR5935(CHIPS)':
 'BOOT': CDS_PINID='BOOT';
NODE_NAME     PR1790 1
 '@S9S_MB_2U_LIB.S9S_MB_2U(SCH_1):PAGE273_I30@PURE_QUANTA.Q_RES(CHIPS)':
 'A': CDS_PINID='A';
NET_NAME
'SW_PVCCIN_CPU1_BOOT6_R'
 '@S9S_MB_2U_LIB.S9S_MB_2U(SCH_1):SW_PVCCIN_CPU1_BOOT6_R':
 C_SIGNAL='@s9s_mb_2u_lib.s9s_mb_2u(sch_1):sw_pvccin_cpu1_boot6_r';
NODE_NAME     PC509 1
 '@S9S_MB_2U_LIB.S9S_MB_2U(SCH_1):PAGE273_I26@PURE_QUANTA.Q_CAP(CHIPS)':
 'A': CDS_PINID='A';
NODE_NAME     PR1790 2
 '@S9S_MB_2U_LIB.S9S_MB_2U(SCH_1):PAGE273_I30@PURE_QUANTA.Q_RES(CHIPS)':
 'B': CDS_PINID='B';
NET_NAME
'SW_PVCCIN_CPU1_BOOT7'
 '@S9S_MB_2U_LIB.S9S_MB_2U(SCH_1):SW_PVCCIN_CPU1_BOOT7':
 C_SIGNAL='@s9s_mb_2u_lib.s9s_mb_2u(sch_1):sw_pvccin_cpu1_boot7';
NODE_NAME     PR1793 1
 '@S9S_MB_2U_LIB.S9S_MB_2U(SCH_1):PAGE274_I39@PURE_QUANTA.Q_RES(CHIPS)':
 'A': CDS_PINID='A';
NODE_NAME     PU24_P1_7 33
 '@S9S_MB_2U_LIB.S9S_MB_2U(SCH_1):PAGE274_I20@PURE_QUANTA.ISL99390FRZTR5935(CHIPS)':
 'BOOT': CDS_PINID='BOOT';
NET_NAME
'SW_PVCCIN_CPU1_BOOT7_R'
 '@S9S_MB_2U_LIB.S9S_MB_2U(SCH_1):SW_PVCCIN_CPU1_BOOT7_R':
 C_SIGNAL='@s9s_mb_2u_lib.s9s_mb_2u(sch_1):sw_pvccin_cpu1_boot7_r';
NODE_NAME     PR1793 2
 '@S9S_MB_2U_LIB.S9S_MB_2U(SCH_1):PAGE274_I39@PURE_QUANTA.Q_RES(CHIPS)':
 'B': CDS_PINID='B';
NODE_NAME     PC488 1
 '@S9S_MB_2U_LIB.S9S_MB_2U(SCH_1):PAGE274_I59@PURE_QUANTA.Q_CAP(CHIPS)':
 'A': CDS_PINID='A';
NET_NAME
'SW_PVCCIN_CPU1_BOOT8'
 '@S9S_MB_2U_LIB.S9S_MB_2U(SCH_1):SW_PVCCIN_CPU1_BOOT8':
 C_SIGNAL='@s9s_mb_2u_lib.s9s_mb_2u(sch_1):sw_pvccin_cpu1_boot8';
NODE_NAME     PR1792 1
 '@S9S_MB_2U_LIB.S9S_MB_2U(SCH_1):PAGE274_I26@PURE_QUANTA.Q_RES(CHIPS)':
 'A': CDS_PINID='A';
NODE_NAME     PU23_P1_8 33
 '@S9S_MB_2U_LIB.S9S_MB_2U(SCH_1):PAGE274_I11@PURE_QUANTA.ISL99390FRZTR5935(CHIPS)':
 'BOOT': CDS_PINID='BOOT';
NET_NAME
'SW_PVCCIN_CPU1_BOOT8_R'
 '@S9S_MB_2U_LIB.S9S_MB_2U(SCH_1):SW_PVCCIN_CPU1_BOOT8_R':
 C_SIGNAL='@s9s_mb_2u_lib.s9s_mb_2u(sch_1):sw_pvccin_cpu1_boot8_r';
NODE_NAME     PR1792 2
 '@S9S_MB_2U_LIB.S9S_MB_2U(SCH_1):PAGE274_I26@PURE_QUANTA.Q_RES(CHIPS)':
 'B': CDS_PINID='B';
NODE_NAME     PC487 1
 '@S9S_MB_2U_LIB.S9S_MB_2U(SCH_1):PAGE274_I42@PURE_QUANTA.Q_CAP(CHIPS)':
 'A': CDS_PINID='A';
NET_NAME
'SW_PVCCIN_CPU1_BOOTR1'
 '@S9S_MB_2U_LIB.S9S_MB_2U(SCH_1):SW_PVCCIN_CPU1_BOOTR1':
 C_SIGNAL='@s9s_mb_2u_lib.s9s_mb_2u(sch_1):sw_pvccin_cpu1_bootr1';
NODE_NAME     PC565 2
 '@S9S_MB_2U_LIB.S9S_MB_2U(SCH_1):PAGE271_I49@PURE_QUANTA.Q_CAP(CHIPS)':
 'B': CDS_PINID='B';
NODE_NAME     PU31_P1_1 32
 '@S9S_MB_2U_LIB.S9S_MB_2U(SCH_1):PAGE271_I40@PURE_QUANTA.ISL99390FRZTR5935(CHIPS)':
 'PHASE': CDS_PINID='PHASE';
NET_NAME
'SW_PVCCIN_CPU1_BOOTR2'
 '@S9S_MB_2U_LIB.S9S_MB_2U(SCH_1):SW_PVCCIN_CPU1_BOOTR2':
 C_SIGNAL='@s9s_mb_2u_lib.s9s_mb_2u(sch_1):sw_pvccin_cpu1_bootr2';
NODE_NAME     PC564 2
 '@S9S_MB_2U_LIB.S9S_MB_2U(SCH_1):PAGE271_I23@PURE_QUANTA.Q_CAP(CHIPS)':
 'B': CDS_PINID='B';
NODE_NAME     PU30_P1_2 32
 '@S9S_MB_2U_LIB.S9S_MB_2U(SCH_1):PAGE271_I7@PURE_QUANTA.ISL99390FRZTR5935(CHIPS)':
 'PHASE': CDS_PINID='PHASE';
NET_NAME
'SW_PVCCIN_CPU1_BOOTR3'
 '@S9S_MB_2U_LIB.S9S_MB_2U(SCH_1):SW_PVCCIN_CPU1_BOOTR3':
 C_SIGNAL='@s9s_mb_2u_lib.s9s_mb_2u(sch_1):sw_pvccin_cpu1_bootr3';
NODE_NAME     PC532 2
 '@S9S_MB_2U_LIB.S9S_MB_2U(SCH_1):PAGE272_I52@PURE_QUANTA.Q_CAP(CHIPS)':
 'B': CDS_PINID='B';
NODE_NAME     PU28_P1_3 32
 '@S9S_MB_2U_LIB.S9S_MB_2U(SCH_1):PAGE272_I66@PURE_QUANTA.ISL99390FRZTR5935(CHIPS)':
 'PHASE': CDS_PINID='PHASE';
NET_NAME
'SW_PVCCIN_CPU1_BOOTR4'
 '@S9S_MB_2U_LIB.S9S_MB_2U(SCH_1):SW_PVCCIN_CPU1_BOOTR4':
 C_SIGNAL='@s9s_mb_2u_lib.s9s_mb_2u(sch_1):sw_pvccin_cpu1_bootr4';
NODE_NAME     PU27_P1_4 32
 '@S9S_MB_2U_LIB.S9S_MB_2U(SCH_1):PAGE272_I10@PURE_QUANTA.ISL99390FRZTR5935(CHIPS)':
 'PHASE': CDS_PINID='PHASE';
NODE_NAME     PC531 2
 '@S9S_MB_2U_LIB.S9S_MB_2U(SCH_1):PAGE272_I39@PURE_QUANTA.Q_CAP(CHIPS)':
 'B': CDS_PINID='B';
NET_NAME
'SW_PVCCIN_CPU1_BOOTR5'
 '@S9S_MB_2U_LIB.S9S_MB_2U(SCH_1):SW_PVCCIN_CPU1_BOOTR5':
 C_SIGNAL='@s9s_mb_2u_lib.s9s_mb_2u(sch_1):sw_pvccin_cpu1_bootr5';
NODE_NAME     PU26_P1_5 32
 '@S9S_MB_2U_LIB.S9S_MB_2U(SCH_1):PAGE273_I23@PURE_QUANTA.ISL99390FRZTR5935(CHIPS)':
 'PHASE': CDS_PINID='PHASE';
NODE_NAME     PC510 2
 '@S9S_MB_2U_LIB.S9S_MB_2U(SCH_1):PAGE273_I47@PURE_QUANTA.Q_CAP(CHIPS)':
 'B': CDS_PINID='B';
NET_NAME
'SW_PVCCIN_CPU1_BOOTR6'
 '@S9S_MB_2U_LIB.S9S_MB_2U(SCH_1):SW_PVCCIN_CPU1_BOOTR6':
 C_SIGNAL='@s9s_mb_2u_lib.s9s_mb_2u(sch_1):sw_pvccin_cpu1_bootr6';
NODE_NAME     PU25_P1_6 32
 '@S9S_MB_2U_LIB.S9S_MB_2U(SCH_1):PAGE273_I16@PURE_QUANTA.ISL99390FRZTR5935(CHIPS)':
 'PHASE': CDS_PINID='PHASE';
NODE_NAME     PC509 2
 '@S9S_MB_2U_LIB.S9S_MB_2U(SCH_1):PAGE273_I26@PURE_QUANTA.Q_CAP(CHIPS)':
 'B': CDS_PINID='B';
NET_NAME
'SW_PVCCIN_CPU1_BOOTR7'
 '@S9S_MB_2U_LIB.S9S_MB_2U(SCH_1):SW_PVCCIN_CPU1_BOOTR7':
 C_SIGNAL='@s9s_mb_2u_lib.s9s_mb_2u(sch_1):sw_pvccin_cpu1_bootr7';
NODE_NAME     PU24_P1_7 32
 '@S9S_MB_2U_LIB.S9S_MB_2U(SCH_1):PAGE274_I20@PURE_QUANTA.ISL99390FRZTR5935(CHIPS)':
 'PHASE': CDS_PINID='PHASE';
NODE_NAME     PC488 2
 '@S9S_MB_2U_LIB.S9S_MB_2U(SCH_1):PAGE274_I59@PURE_QUANTA.Q_CAP(CHIPS)':
 'B': CDS_PINID='B';
NET_NAME
'SW_PVCCIN_CPU1_BOOTR8'
 '@S9S_MB_2U_LIB.S9S_MB_2U(SCH_1):SW_PVCCIN_CPU1_BOOTR8':
 C_SIGNAL='@s9s_mb_2u_lib.s9s_mb_2u(sch_1):sw_pvccin_cpu1_bootr8';
NODE_NAME     PC487 2
 '@S9S_MB_2U_LIB.S9S_MB_2U(SCH_1):PAGE274_I42@PURE_QUANTA.Q_CAP(CHIPS)':
 'B': CDS_PINID='B';
NODE_NAME     PU23_P1_8 32
 '@S9S_MB_2U_LIB.S9S_MB_2U(SCH_1):PAGE274_I11@PURE_QUANTA.ISL99390FRZTR5935(CHIPS)':
 'PHASE': CDS_PINID='PHASE';
NET_NAME
'SW_PVCCIN_CPU1_SW1'
 '@S9S_MB_2U_LIB.S9S_MB_2U(SCH_1):SW_PVCCIN_CPU1_SW1':
 C_SIGNAL='@s9s_mb_2u_lib.s9s_mb_2u(sch_1):sw_pvccin_cpu1_sw1';
NODE_NAME     PL31 1
 '@S9S_MB_2U_LIB.S9S_MB_2U(SCH_1):PAGE271_I74@PURE_QUANTA.Q_INDUCTOR4P_14(CHIPS)':
 '1': CDS_PINID='\1\';
NODE_NAME     PU31_P1_1 10_19
 '@S9S_MB_2U_LIB.S9S_MB_2U(SCH_1):PAGE271_I40@PURE_QUANTA.ISL99390FRZTR5935(CHIPS)':
 'SW': CDS_PINID='SW';
NET_NAME
'SW_PVCCIN_CPU1_SW2'
 '@S9S_MB_2U_LIB.S9S_MB_2U(SCH_1):SW_PVCCIN_CPU1_SW2':
 C_SIGNAL='@s9s_mb_2u_lib.s9s_mb_2u(sch_1):sw_pvccin_cpu1_sw2';
NODE_NAME     PU30_P1_2 10_19
 '@S9S_MB_2U_LIB.S9S_MB_2U(SCH_1):PAGE271_I7@PURE_QUANTA.ISL99390FRZTR5935(CHIPS)':
 'SW': CDS_PINID='SW';
NODE_NAME     PL30 1
 '@S9S_MB_2U_LIB.S9S_MB_2U(SCH_1):PAGE271_I18@PURE_QUANTA.Q_INDUCTOR4P_14(CHIPS)':
 '1': CDS_PINID='\1\';
NET_NAME
'SW_PVCCIN_CPU1_SW3'
 '@S9S_MB_2U_LIB.S9S_MB_2U(SCH_1):SW_PVCCIN_CPU1_SW3':
 C_SIGNAL='@s9s_mb_2u_lib.s9s_mb_2u(sch_1):sw_pvccin_cpu1_sw3';
NODE_NAME     PL29 1
 '@S9S_MB_2U_LIB.S9S_MB_2U(SCH_1):PAGE272_I51@PURE_QUANTA.Q_INDUCTOR4P_14(CHIPS)':
 '1': CDS_PINID='\1\';
NODE_NAME     PU28_P1_3 10_19
 '@S9S_MB_2U_LIB.S9S_MB_2U(SCH_1):PAGE272_I66@PURE_QUANTA.ISL99390FRZTR5935(CHIPS)':
 'SW': CDS_PINID='SW';
NET_NAME
'SW_PVCCIN_CPU1_SW4'
 '@S9S_MB_2U_LIB.S9S_MB_2U(SCH_1):SW_PVCCIN_CPU1_SW4':
 C_SIGNAL='@s9s_mb_2u_lib.s9s_mb_2u(sch_1):sw_pvccin_cpu1_sw4';
NODE_NAME     PU27_P1_4 10_19
 '@S9S_MB_2U_LIB.S9S_MB_2U(SCH_1):PAGE272_I10@PURE_QUANTA.ISL99390FRZTR5935(CHIPS)':
 'SW': CDS_PINID='SW';
NODE_NAME     PL28 1
 '@S9S_MB_2U_LIB.S9S_MB_2U(SCH_1):PAGE272_I37@PURE_QUANTA.Q_INDUCTOR4P_14(CHIPS)':
 '1': CDS_PINID='\1\';
NET_NAME
'SW_PVCCIN_CPU1_SW5'
 '@S9S_MB_2U_LIB.S9S_MB_2U(SCH_1):SW_PVCCIN_CPU1_SW5':
 C_SIGNAL='@s9s_mb_2u_lib.s9s_mb_2u(sch_1):sw_pvccin_cpu1_sw5';
NODE_NAME     PU26_P1_5 10_19
 '@S9S_MB_2U_LIB.S9S_MB_2U(SCH_1):PAGE273_I23@PURE_QUANTA.ISL99390FRZTR5935(CHIPS)':
 'SW': CDS_PINID='SW';
NODE_NAME     PL27 1
 '@S9S_MB_2U_LIB.S9S_MB_2U(SCH_1):PAGE273_I48@PURE_QUANTA.Q_INDUCTOR4P_14(CHIPS)':
 '1': CDS_PINID='\1\';
NET_NAME
'SW_PVCCIN_CPU1_SW6'
 '@S9S_MB_2U_LIB.S9S_MB_2U(SCH_1):SW_PVCCIN_CPU1_SW6':
 C_SIGNAL='@s9s_mb_2u_lib.s9s_mb_2u(sch_1):sw_pvccin_cpu1_sw6';
NODE_NAME     PL26 1
 '@S9S_MB_2U_LIB.S9S_MB_2U(SCH_1):PAGE273_I28@PURE_QUANTA.Q_INDUCTOR4P_14(CHIPS)':
 '1': CDS_PINID='\1\';
NODE_NAME     PU25_P1_6 10_19
 '@S9S_MB_2U_LIB.S9S_MB_2U(SCH_1):PAGE273_I16@PURE_QUANTA.ISL99390FRZTR5935(CHIPS)':
 'SW': CDS_PINID='SW';
NET_NAME
'SW_PVCCIN_CPU1_SW7'
 '@S9S_MB_2U_LIB.S9S_MB_2U(SCH_1):SW_PVCCIN_CPU1_SW7':
 C_SIGNAL='@s9s_mb_2u_lib.s9s_mb_2u(sch_1):sw_pvccin_cpu1_sw7';
NODE_NAME     PU24_P1_7 10_19
 '@S9S_MB_2U_LIB.S9S_MB_2U(SCH_1):PAGE274_I20@PURE_QUANTA.ISL99390FRZTR5935(CHIPS)':
 'SW': CDS_PINID='SW';
NODE_NAME     PL25 1
 '@S9S_MB_2U_LIB.S9S_MB_2U(SCH_1):PAGE274_I58@PURE_QUANTA.Q_INDUCTOR4P_14(CHIPS)':
 '1': CDS_PINID='\1\';
NET_NAME
'SW_PVCCIN_CPU1_SW8'
 '@S9S_MB_2U_LIB.S9S_MB_2U(SCH_1):SW_PVCCIN_CPU1_SW8':
 C_SIGNAL='@s9s_mb_2u_lib.s9s_mb_2u(sch_1):sw_pvccin_cpu1_sw8';
NODE_NAME     PL24 1
 '@S9S_MB_2U_LIB.S9S_MB_2U(SCH_1):PAGE274_I43@PURE_QUANTA.Q_INDUCTOR4P_14(CHIPS)':
 '1': CDS_PINID='\1\';
NODE_NAME     PU23_P1_8 10_19
 '@S9S_MB_2U_LIB.S9S_MB_2U(SCH_1):PAGE274_I11@PURE_QUANTA.ISL99390FRZTR5935(CHIPS)':
 'SW': CDS_PINID='SW';
NET_NAME
'SW_PVNN_MAIN_CPU0_BST'
 '@S9S_MB_2U_LIB.S9S_MB_2U(SCH_1):SW_PVNN_MAIN_CPU0_BST':
 C_SIGNAL='@s9s_mb_2u_lib.s9s_mb_2u(sch_1):sw_pvnn_main_cpu0_bst';
NODE_NAME     PR4271 1
 '@S9S_MB_2U_LIB.S9S_MB_2U(SCH_1):PAGE268_I27@PURE_QUANTA.Q_RES(CHIPS)':
 'A': CDS_PINID='A';
NODE_NAME     PU81 10
 '@S9S_MB_2U_LIB.S9S_MB_2U(SCH_1):PAGE268_I22@PURE_QUANTA.RS53317LR(CHIPS)':
 'BST': CDS_PINID='BST';
NET_NAME
'SW_PVNN_MAIN_CPU0_BST_R'
 '@S9S_MB_2U_LIB.S9S_MB_2U(SCH_1):SW_PVNN_MAIN_CPU0_BST_R':
 C_SIGNAL='@s9s_mb_2u_lib.s9s_mb_2u(sch_1):sw_pvnn_main_cpu0_bst_r';
NODE_NAME     PC1275 1
 '@S9S_MB_2U_LIB.S9S_MB_2U(SCH_1):PAGE268_I26@PURE_QUANTA.Q_CAP(CHIPS)':
 'A': CDS_PINID='A';
NODE_NAME     PR4271 2
 '@S9S_MB_2U_LIB.S9S_MB_2U(SCH_1):PAGE268_I27@PURE_QUANTA.Q_RES(CHIPS)':
 'B': CDS_PINID='B';
NET_NAME
'SW_PVNN_MAIN_CPU0_SW'
 '@S9S_MB_2U_LIB.S9S_MB_2U(SCH_1):SW_PVNN_MAIN_CPU0_SW':
 C_SIGNAL='@s9s_mb_2u_lib.s9s_mb_2u(sch_1):sw_pvnn_main_cpu0_sw';
NODE_NAME     PC1275 2
 '@S9S_MB_2U_LIB.S9S_MB_2U(SCH_1):PAGE268_I26@PURE_QUANTA.Q_CAP(CHIPS)':
 'B': CDS_PINID='B';
NODE_NAME     PU81 2
 '@S9S_MB_2U_LIB.S9S_MB_2U(SCH_1):PAGE268_I22@PURE_QUANTA.RS53317LR(CHIPS)':
 'SW1': CDS_PINID='SW1';
NODE_NAME     PU81 11
 '@S9S_MB_2U_LIB.S9S_MB_2U(SCH_1):PAGE268_I22@PURE_QUANTA.RS53317LR(CHIPS)':
 'SW2': CDS_PINID='SW2';
NODE_NAME     PL120 1
 '@S9S_MB_2U_LIB.S9S_MB_2U(SCH_1):PAGE268_I29@PURE_QUANTA.Q_INDUCTOR(CHIPS)':
 '1': CDS_PINID='\1\';
NET_NAME
'SW_PVNN_MAIN_CPU1_BST'
 '@S9S_MB_2U_LIB.S9S_MB_2U(SCH_1):SW_PVNN_MAIN_CPU1_BST':
 C_SIGNAL='@s9s_mb_2u_lib.s9s_mb_2u(sch_1):sw_pvnn_main_cpu1_bst';
NODE_NAME     PU82 10
 '@S9S_MB_2U_LIB.S9S_MB_2U(SCH_1):PAGE286_I20@PURE_QUANTA.RS53317LR(CHIPS)':
 'BST': CDS_PINID='BST';
NODE_NAME     PR4272 1
 '@S9S_MB_2U_LIB.S9S_MB_2U(SCH_1):PAGE286_I25@PURE_QUANTA.Q_RES(CHIPS)':
 'A': CDS_PINID='A';
NET_NAME
'SW_PVNN_MAIN_CPU1_BST_R'
 '@S9S_MB_2U_LIB.S9S_MB_2U(SCH_1):SW_PVNN_MAIN_CPU1_BST_R':
 C_SIGNAL='@s9s_mb_2u_lib.s9s_mb_2u(sch_1):sw_pvnn_main_cpu1_bst_r';
NODE_NAME     PR4272 2
 '@S9S_MB_2U_LIB.S9S_MB_2U(SCH_1):PAGE286_I25@PURE_QUANTA.Q_RES(CHIPS)':
 'B': CDS_PINID='B';
NODE_NAME     PC1283 1
 '@S9S_MB_2U_LIB.S9S_MB_2U(SCH_1):PAGE286_I24@PURE_QUANTA.Q_CAP(CHIPS)':
 'A': CDS_PINID='A';
NET_NAME
'SW_PVNN_MAIN_CPU1_SW'
 '@S9S_MB_2U_LIB.S9S_MB_2U(SCH_1):SW_PVNN_MAIN_CPU1_SW':
 C_SIGNAL='@s9s_mb_2u_lib.s9s_mb_2u(sch_1):sw_pvnn_main_cpu1_sw';
NODE_NAME     PL121 1
 '@S9S_MB_2U_LIB.S9S_MB_2U(SCH_1):PAGE286_I27@PURE_QUANTA.Q_INDUCTOR(CHIPS)':
 '1': CDS_PINID='\1\';
NODE_NAME     PU82 2
 '@S9S_MB_2U_LIB.S9S_MB_2U(SCH_1):PAGE286_I20@PURE_QUANTA.RS53317LR(CHIPS)':
 'SW1': CDS_PINID='SW1';
NODE_NAME     PU82 11
 '@S9S_MB_2U_LIB.S9S_MB_2U(SCH_1):PAGE286_I20@PURE_QUANTA.RS53317LR(CHIPS)':
 'SW2': CDS_PINID='SW2';
NODE_NAME     PC1283 2
 '@S9S_MB_2U_LIB.S9S_MB_2U(SCH_1):PAGE286_I24@PURE_QUANTA.Q_CAP(CHIPS)':
 'B': CDS_PINID='B';
NET_NAME
'SW_PVPP_HBM_CPU0_BST'
 '@S9S_MB_2U_LIB.S9S_MB_2U(SCH_1):SW_PVPP_HBM_CPU0_BST':
 C_SIGNAL='@s9s_mb_2u_lib.s9s_mb_2u(sch_1):sw_pvpp_hbm_cpu0_bst';
NODE_NAME     PC1252 1
 '@S9S_MB_2U_LIB.S9S_MB_2U(SCH_1):PAGE267_I27@PURE_QUANTA.Q_CAP(CHIPS)':
 'A': CDS_PINID='A';
NODE_NAME     PU79 1
 '@S9S_MB_2U_LIB.S9S_MB_2U(SCH_1):PAGE267_I19@PURE_QUANTA.RS53318LR(CHIPS)':
 'BST': CDS_PINID='BST';
NET_NAME
'SW_PVPP_HBM_CPU0_SW'
 '@S9S_MB_2U_LIB.S9S_MB_2U(SCH_1):SW_PVPP_HBM_CPU0_SW':
 C_SIGNAL='@s9s_mb_2u_lib.s9s_mb_2u(sch_1):sw_pvpp_hbm_cpu0_sw';
NODE_NAME     PC1252 2
 '@S9S_MB_2U_LIB.S9S_MB_2U(SCH_1):PAGE267_I27@PURE_QUANTA.Q_CAP(CHIPS)':
 'B': CDS_PINID='B';
NODE_NAME     PL118 1
 '@S9S_MB_2U_LIB.S9S_MB_2U(SCH_1):PAGE267_I28@PURE_QUANTA.Q_INDUCTOR(CHIPS)':
 '1': CDS_PINID='\1\';
NODE_NAME     PU79 20
 '@S9S_MB_2U_LIB.S9S_MB_2U(SCH_1):PAGE267_I19@PURE_QUANTA.RS53318LR(CHIPS)':
 'SW': CDS_PINID='SW';
NET_NAME
'SW_PVPP_HBM_CPU1_BST'
 '@S9S_MB_2U_LIB.S9S_MB_2U(SCH_1):SW_PVPP_HBM_CPU1_BST':
 C_SIGNAL='@s9s_mb_2u_lib.s9s_mb_2u(sch_1):sw_pvpp_hbm_cpu1_bst';
NODE_NAME     PU80 1
 '@S9S_MB_2U_LIB.S9S_MB_2U(SCH_1):PAGE285_I25@PURE_QUANTA.RS53318LR(CHIPS)':
 'BST': CDS_PINID='BST';
NODE_NAME     PC1265 1
 '@S9S_MB_2U_LIB.S9S_MB_2U(SCH_1):PAGE285_I26@PURE_QUANTA.Q_CAP(CHIPS)':
 'A': CDS_PINID='A';
NET_NAME
'SW_PVPP_HBM_CPU1_SW'
 '@S9S_MB_2U_LIB.S9S_MB_2U(SCH_1):SW_PVPP_HBM_CPU1_SW':
 C_SIGNAL='@s9s_mb_2u_lib.s9s_mb_2u(sch_1):sw_pvpp_hbm_cpu1_sw';
NODE_NAME     PL119 1
 '@S9S_MB_2U_LIB.S9S_MB_2U(SCH_1):PAGE285_I33@PURE_QUANTA.Q_INDUCTOR(CHIPS)':
 '1': CDS_PINID='\1\';
NODE_NAME     PU80 20
 '@S9S_MB_2U_LIB.S9S_MB_2U(SCH_1):PAGE285_I25@PURE_QUANTA.RS53318LR(CHIPS)':
 'SW': CDS_PINID='SW';
NODE_NAME     PC1265 2
 '@S9S_MB_2U_LIB.S9S_MB_2U(SCH_1):PAGE285_I26@PURE_QUANTA.Q_CAP(CHIPS)':
 'B': CDS_PINID='B';
NET_NAME
'T1_GND'
 '@S9S_MB_2U_LIB.S9S_MB_2U(SCH_1):T1_GND':
 C_SIGNAL='@s9s_mb_2u_lib.s9s_mb_2u(sch_1):t1_gnd',
 CDS_GLOBAL_NET='TRUE';
NODE_NAME     X19 2
 '@S9S_MB_2U_LIB.S9S_MB_2U(SCH_1):PAGE288_I3@PURE_QUANTA.TP_TDR_4P_FTS(CHIPS)':
 'P1': CDS_PINID='P1';
NODE_NAME     X19 3
 '@S9S_MB_2U_LIB.S9S_MB_2U(SCH_1):PAGE288_I3@PURE_QUANTA.TP_TDR_4P_FTS(CHIPS)':
 'P2': CDS_PINID='P2';
NODE_NAME     X20 2
 '@S9S_MB_2U_LIB.S9S_MB_2U(SCH_1):PAGE288_I4@PURE_QUANTA.TP_TDR_4P_FTS(CHIPS)':
 'P1': CDS_PINID='P1';
NODE_NAME     X20 3
 '@S9S_MB_2U_LIB.S9S_MB_2U(SCH_1):PAGE288_I4@PURE_QUANTA.TP_TDR_4P_FTS(CHIPS)':
 'P2': CDS_PINID='P2';
NODE_NAME     X22 2
 '@S9S_MB_2U_LIB.S9S_MB_2U(SCH_1):PAGE288_I8@PURE_QUANTA.TP_TDR_4P_FTS(CHIPS)':
 'P1': CDS_PINID='P1';
NODE_NAME     X22 3
 '@S9S_MB_2U_LIB.S9S_MB_2U(SCH_1):PAGE288_I8@PURE_QUANTA.TP_TDR_4P_FTS(CHIPS)':
 'P2': CDS_PINID='P2';
NODE_NAME     X21 2
 '@S9S_MB_2U_LIB.S9S_MB_2U(SCH_1):PAGE288_I9@PURE_QUANTA.TP_TDR_4P_FTS(CHIPS)':
 'P1': CDS_PINID='P1';
NODE_NAME     X21 3
 '@S9S_MB_2U_LIB.S9S_MB_2U(SCH_1):PAGE288_I9@PURE_QUANTA.TP_TDR_4P_FTS(CHIPS)':
 'P2': CDS_PINID='P2';
NODE_NAME     X23 2
 '@S9S_MB_2U_LIB.S9S_MB_2U(SCH_1):PAGE288_I10@PURE_QUANTA.TP_TDR_4P_FTS(CHIPS)':
 'P1': CDS_PINID='P1';
NODE_NAME     X23 3
 '@S9S_MB_2U_LIB.S9S_MB_2U(SCH_1):PAGE288_I10@PURE_QUANTA.TP_TDR_4P_FTS(CHIPS)':
 'P2': CDS_PINID='P2';
NODE_NAME     X13 2
 '@S9S_MB_2U_LIB.S9S_MB_2U(SCH_1):PAGE288_I11@PURE_QUANTA.TP_TDR_4P_FTS(CHIPS)':
 'P1': CDS_PINID='P1';
NODE_NAME     X13 3
 '@S9S_MB_2U_LIB.S9S_MB_2U(SCH_1):PAGE288_I11@PURE_QUANTA.TP_TDR_4P_FTS(CHIPS)':
 'P2': CDS_PINID='P2';
NODE_NAME     X14 2
 '@S9S_MB_2U_LIB.S9S_MB_2U(SCH_1):PAGE288_I12@PURE_QUANTA.TP_TDR_4P_FTS(CHIPS)':
 'P1': CDS_PINID='P1';
NODE_NAME     X14 3
 '@S9S_MB_2U_LIB.S9S_MB_2U(SCH_1):PAGE288_I12@PURE_QUANTA.TP_TDR_4P_FTS(CHIPS)':
 'P2': CDS_PINID='P2';
NODE_NAME     X15 2
 '@S9S_MB_2U_LIB.S9S_MB_2U(SCH_1):PAGE288_I17@PURE_QUANTA.TP_TDR_4P_FTS(CHIPS)':
 'P1': CDS_PINID='P1';
NODE_NAME     X15 3
 '@S9S_MB_2U_LIB.S9S_MB_2U(SCH_1):PAGE288_I17@PURE_QUANTA.TP_TDR_4P_FTS(CHIPS)':
 'P2': CDS_PINID='P2';
NODE_NAME     X16 2
 '@S9S_MB_2U_LIB.S9S_MB_2U(SCH_1):PAGE288_I18@PURE_QUANTA.TP_TDR_4P_FTS(CHIPS)':
 'P1': CDS_PINID='P1';
NODE_NAME     X16 3
 '@S9S_MB_2U_LIB.S9S_MB_2U(SCH_1):PAGE288_I18@PURE_QUANTA.TP_TDR_4P_FTS(CHIPS)':
 'P2': CDS_PINID='P2';
NODE_NAME     X17 2
 '@S9S_MB_2U_LIB.S9S_MB_2U(SCH_1):PAGE288_I19@PURE_QUANTA.TP_TDR_4P_FTS(CHIPS)':
 'P1': CDS_PINID='P1';
NODE_NAME     X17 3
 '@S9S_MB_2U_LIB.S9S_MB_2U(SCH_1):PAGE288_I19@PURE_QUANTA.TP_TDR_4P_FTS(CHIPS)':
 'P2': CDS_PINID='P2';
NODE_NAME     X7 2
 '@S9S_MB_2U_LIB.S9S_MB_2U(SCH_1):PAGE288_I26@PURE_QUANTA.TP_TDR_4P_FTS(CHIPS)':
 'P1': CDS_PINID='P1';
NODE_NAME     X7 3
 '@S9S_MB_2U_LIB.S9S_MB_2U(SCH_1):PAGE288_I26@PURE_QUANTA.TP_TDR_4P_FTS(CHIPS)':
 'P2': CDS_PINID='P2';
NODE_NAME     X8 2
 '@S9S_MB_2U_LIB.S9S_MB_2U(SCH_1):PAGE288_I27@PURE_QUANTA.TP_TDR_4P_FTS(CHIPS)':
 'P1': CDS_PINID='P1';
NODE_NAME     X8 3
 '@S9S_MB_2U_LIB.S9S_MB_2U(SCH_1):PAGE288_I27@PURE_QUANTA.TP_TDR_4P_FTS(CHIPS)':
 'P2': CDS_PINID='P2';
NODE_NAME     X1 2
 '@S9S_MB_2U_LIB.S9S_MB_2U(SCH_1):PAGE288_I28@PURE_QUANTA.TP_TDR_4P_FTS(CHIPS)':
 'P1': CDS_PINID='P1';
NODE_NAME     X1 3
 '@S9S_MB_2U_LIB.S9S_MB_2U(SCH_1):PAGE288_I28@PURE_QUANTA.TP_TDR_4P_FTS(CHIPS)':
 'P2': CDS_PINID='P2';
NODE_NAME     X2 2
 '@S9S_MB_2U_LIB.S9S_MB_2U(SCH_1):PAGE288_I30@PURE_QUANTA.TP_TDR_4P_FTS(CHIPS)':
 'P1': CDS_PINID='P1';
NODE_NAME     X2 3
 '@S9S_MB_2U_LIB.S9S_MB_2U(SCH_1):PAGE288_I30@PURE_QUANTA.TP_TDR_4P_FTS(CHIPS)':
 'P2': CDS_PINID='P2';
NODE_NAME     X9 2
 '@S9S_MB_2U_LIB.S9S_MB_2U(SCH_1):PAGE288_I32@PURE_QUANTA.TP_TDR_4P_FTS(CHIPS)':
 'P1': CDS_PINID='P1';
NODE_NAME     X9 3
 '@S9S_MB_2U_LIB.S9S_MB_2U(SCH_1):PAGE288_I32@PURE_QUANTA.TP_TDR_4P_FTS(CHIPS)':
 'P2': CDS_PINID='P2';
NODE_NAME     X10 2
 '@S9S_MB_2U_LIB.S9S_MB_2U(SCH_1):PAGE288_I33@PURE_QUANTA.TP_TDR_4P_FTS(CHIPS)':
 'P1': CDS_PINID='P1';
NODE_NAME     X10 3
 '@S9S_MB_2U_LIB.S9S_MB_2U(SCH_1):PAGE288_I33@PURE_QUANTA.TP_TDR_4P_FTS(CHIPS)':
 'P2': CDS_PINID='P2';
NODE_NAME     X11 2
 '@S9S_MB_2U_LIB.S9S_MB_2U(SCH_1):PAGE288_I34@PURE_QUANTA.TP_TDR_4P_FTS(CHIPS)':
 'P1': CDS_PINID='P1';
NODE_NAME     X11 3
 '@S9S_MB_2U_LIB.S9S_MB_2U(SCH_1):PAGE288_I34@PURE_QUANTA.TP_TDR_4P_FTS(CHIPS)':
 'P2': CDS_PINID='P2';
NODE_NAME     X3 2
 '@S9S_MB_2U_LIB.S9S_MB_2U(SCH_1):PAGE288_I35@PURE_QUANTA.TP_TDR_4P_FTS(CHIPS)':
 'P1': CDS_PINID='P1';
NODE_NAME     X3 3
 '@S9S_MB_2U_LIB.S9S_MB_2U(SCH_1):PAGE288_I35@PURE_QUANTA.TP_TDR_4P_FTS(CHIPS)':
 'P2': CDS_PINID='P2';
NODE_NAME     X4 2
 '@S9S_MB_2U_LIB.S9S_MB_2U(SCH_1):PAGE288_I37@PURE_QUANTA.TP_TDR_4P_FTS(CHIPS)':
 'P1': CDS_PINID='P1';
NODE_NAME     X4 3
 '@S9S_MB_2U_LIB.S9S_MB_2U(SCH_1):PAGE288_I37@PURE_QUANTA.TP_TDR_4P_FTS(CHIPS)':
 'P2': CDS_PINID='P2';
NODE_NAME     X5 2
 '@S9S_MB_2U_LIB.S9S_MB_2U(SCH_1):PAGE288_I39@PURE_QUANTA.TP_TDR_4P_FTS(CHIPS)':
 'P1': CDS_PINID='P1';
NODE_NAME     X5 3
 '@S9S_MB_2U_LIB.S9S_MB_2U(SCH_1):PAGE288_I39@PURE_QUANTA.TP_TDR_4P_FTS(CHIPS)':
 'P2': CDS_PINID='P2';
NODE_NAME     X24 2
 '@S9S_MB_2U_LIB.S9S_MB_2U(SCH_1):PAGE288_I42@PURE_QUANTA.TP_TDR_4P_FTS(CHIPS)':
 'P1': CDS_PINID='P1';
NODE_NAME     X24 3
 '@S9S_MB_2U_LIB.S9S_MB_2U(SCH_1):PAGE288_I42@PURE_QUANTA.TP_TDR_4P_FTS(CHIPS)':
 'P2': CDS_PINID='P2';
NODE_NAME     X18 2
 '@S9S_MB_2U_LIB.S9S_MB_2U(SCH_1):PAGE288_I43@PURE_QUANTA.TP_TDR_4P_FTS(CHIPS)':
 'P1': CDS_PINID='P1';
NODE_NAME     X18 3
 '@S9S_MB_2U_LIB.S9S_MB_2U(SCH_1):PAGE288_I43@PURE_QUANTA.TP_TDR_4P_FTS(CHIPS)':
 'P2': CDS_PINID='P2';
NODE_NAME     X12 2
 '@S9S_MB_2U_LIB.S9S_MB_2U(SCH_1):PAGE288_I46@PURE_QUANTA.TP_TDR_4P_FTS(CHIPS)':
 'P1': CDS_PINID='P1';
NODE_NAME     X12 3
 '@S9S_MB_2U_LIB.S9S_MB_2U(SCH_1):PAGE288_I46@PURE_QUANTA.TP_TDR_4P_FTS(CHIPS)':
 'P2': CDS_PINID='P2';
NODE_NAME     X6 2
 '@S9S_MB_2U_LIB.S9S_MB_2U(SCH_1):PAGE288_I47@PURE_QUANTA.TP_TDR_4P_FTS(CHIPS)':
 'P1': CDS_PINID='P1';
NODE_NAME     X6 3
 '@S9S_MB_2U_LIB.S9S_MB_2U(SCH_1):PAGE288_I47@PURE_QUANTA.TP_TDR_4P_FTS(CHIPS)':
 'P2': CDS_PINID='P2';
NODE_NAME     DB7 1
 '@S9S_MB_2U_LIB.S9S_MB_2U(SCH_1):PAGE288_I49@PURE_QUANTA.TDR_3P(CHIPS)':
 'GND': CDS_PINID='GND';
NODE_NAME     DB8 1
 '@S9S_MB_2U_LIB.S9S_MB_2U(SCH_1):PAGE288_I51@PURE_QUANTA.TDR_3P(CHIPS)':
 'GND': CDS_PINID='GND';
NODE_NAME     DB9 1
 '@S9S_MB_2U_LIB.S9S_MB_2U(SCH_1):PAGE288_I53@PURE_QUANTA.TDR_3P(CHIPS)':
 'GND': CDS_PINID='GND';
NODE_NAME     DB10 1
 '@S9S_MB_2U_LIB.S9S_MB_2U(SCH_1):PAGE288_I55@PURE_QUANTA.TDR_3P(CHIPS)':
 'GND': CDS_PINID='GND';
NODE_NAME     DB11 1
 '@S9S_MB_2U_LIB.S9S_MB_2U(SCH_1):PAGE288_I57@PURE_QUANTA.TDR_3P(CHIPS)':
 'GND': CDS_PINID='GND';
NODE_NAME     DB12 1
 '@S9S_MB_2U_LIB.S9S_MB_2U(SCH_1):PAGE288_I60@PURE_QUANTA.TDR_3P(CHIPS)':
 'GND': CDS_PINID='GND';
NODE_NAME     DB1 1
 '@S9S_MB_2U_LIB.S9S_MB_2U(SCH_1):PAGE288_I61@PURE_QUANTA.TDR_3P(CHIPS)':
 'GND': CDS_PINID='GND';
NODE_NAME     DB2 1
 '@S9S_MB_2U_LIB.S9S_MB_2U(SCH_1):PAGE288_I62@PURE_QUANTA.TDR_3P(CHIPS)':
 'GND': CDS_PINID='GND';
NODE_NAME     DB3 1
 '@S9S_MB_2U_LIB.S9S_MB_2U(SCH_1):PAGE288_I63@PURE_QUANTA.TDR_3P(CHIPS)':
 'GND': CDS_PINID='GND';
NODE_NAME     DB4 1
 '@S9S_MB_2U_LIB.S9S_MB_2U(SCH_1):PAGE288_I67@PURE_QUANTA.TDR_3P(CHIPS)':
 'GND': CDS_PINID='GND';
NODE_NAME     DB5 1
 '@S9S_MB_2U_LIB.S9S_MB_2U(SCH_1):PAGE288_I68@PURE_QUANTA.TDR_3P(CHIPS)':
 'GND': CDS_PINID='GND';
NODE_NAME     DB6 1
 '@S9S_MB_2U_LIB.S9S_MB_2U(SCH_1):PAGE288_I69@PURE_QUANTA.TDR_3P(CHIPS)':
 'GND': CDS_PINID='GND';
NODE_NAME     DB14 1
 '@S9S_MB_2U_LIB.S9S_MB_2U(SCH_1):PAGE288_I96@PURE_QUANTA.TDR_3P(CHIPS)':
 'GND': CDS_PINID='GND';
NODE_NAME     DB15 1
 '@S9S_MB_2U_LIB.S9S_MB_2U(SCH_1):PAGE288_I97@PURE_QUANTA.TDR_3P(CHIPS)':
 'GND': CDS_PINID='GND';
NODE_NAME     DB16 1
 '@S9S_MB_2U_LIB.S9S_MB_2U(SCH_1):PAGE288_I99@PURE_QUANTA.TDR_3P(CHIPS)':
 'GND': CDS_PINID='GND';
NODE_NAME     DB13 1
 '@S9S_MB_2U_LIB.S9S_MB_2U(SCH_1):PAGE288_I101@PURE_QUANTA.TDR_3P(CHIPS)':
 'GND': CDS_PINID='GND';
NODE_NAME     X27 2
 '@S9S_MB_2U_LIB.S9S_MB_2U(SCH_1):PAGE288_I106@PURE_QUANTA.TP_TDR_4P_FTS(CHIPS)':
 'P1': CDS_PINID='P1';
NODE_NAME     X27 3
 '@S9S_MB_2U_LIB.S9S_MB_2U(SCH_1):PAGE288_I106@PURE_QUANTA.TP_TDR_4P_FTS(CHIPS)':
 'P2': CDS_PINID='P2';
NODE_NAME     X28 2
 '@S9S_MB_2U_LIB.S9S_MB_2U(SCH_1):PAGE288_I107@PURE_QUANTA.TP_TDR_4P_FTS(CHIPS)':
 'P1': CDS_PINID='P1';
NODE_NAME     X28 3
 '@S9S_MB_2U_LIB.S9S_MB_2U(SCH_1):PAGE288_I107@PURE_QUANTA.TP_TDR_4P_FTS(CHIPS)':
 'P2': CDS_PINID='P2';
NODE_NAME     X25 2
 '@S9S_MB_2U_LIB.S9S_MB_2U(SCH_1):PAGE288_I108@PURE_QUANTA.TP_TDR_4P_FTS(CHIPS)':
 'P1': CDS_PINID='P1';
NODE_NAME     X25 3
 '@S9S_MB_2U_LIB.S9S_MB_2U(SCH_1):PAGE288_I108@PURE_QUANTA.TP_TDR_4P_FTS(CHIPS)':
 'P2': CDS_PINID='P2';
NODE_NAME     X26 2
 '@S9S_MB_2U_LIB.S9S_MB_2U(SCH_1):PAGE288_I110@PURE_QUANTA.TP_TDR_4P_FTS(CHIPS)':
 'P1': CDS_PINID='P1';
NODE_NAME     X26 3
 '@S9S_MB_2U_LIB.S9S_MB_2U(SCH_1):PAGE288_I110@PURE_QUANTA.TP_TDR_4P_FTS(CHIPS)':
 'P2': CDS_PINID='P2';
NODE_NAME     X31 2
 '@S9S_MB_2U_LIB.S9S_MB_2U(SCH_1):PAGE288_I112@PURE_QUANTA.TP_TDR_4P_FTS(CHIPS)':
 'P1': CDS_PINID='P1';
NODE_NAME     X31 3
 '@S9S_MB_2U_LIB.S9S_MB_2U(SCH_1):PAGE288_I112@PURE_QUANTA.TP_TDR_4P_FTS(CHIPS)':
 'P2': CDS_PINID='P2';
NODE_NAME     X32 2
 '@S9S_MB_2U_LIB.S9S_MB_2U(SCH_1):PAGE288_I115@PURE_QUANTA.TP_TDR_4P_FTS(CHIPS)':
 'P1': CDS_PINID='P1';
NODE_NAME     X32 3
 '@S9S_MB_2U_LIB.S9S_MB_2U(SCH_1):PAGE288_I115@PURE_QUANTA.TP_TDR_4P_FTS(CHIPS)':
 'P2': CDS_PINID='P2';
NODE_NAME     X29 2
 '@S9S_MB_2U_LIB.S9S_MB_2U(SCH_1):PAGE288_I116@PURE_QUANTA.TP_TDR_4P_FTS(CHIPS)':
 'P1': CDS_PINID='P1';
NODE_NAME     X29 3
 '@S9S_MB_2U_LIB.S9S_MB_2U(SCH_1):PAGE288_I116@PURE_QUANTA.TP_TDR_4P_FTS(CHIPS)':
 'P2': CDS_PINID='P2';
NODE_NAME     X30 2
 '@S9S_MB_2U_LIB.S9S_MB_2U(SCH_1):PAGE288_I117@PURE_QUANTA.TP_TDR_4P_FTS(CHIPS)':
 'P1': CDS_PINID='P1';
NODE_NAME     X30 3
 '@S9S_MB_2U_LIB.S9S_MB_2U(SCH_1):PAGE288_I117@PURE_QUANTA.TP_TDR_4P_FTS(CHIPS)':
 'P2': CDS_PINID='P2';
NODE_NAME     X38 2
 '@S9S_MB_2U_LIB.S9S_MB_2U(SCH_1):PAGE310_I5@PURE_QUANTA.TP_TDR_4P_FTS(CHIPS)':
 'P1': CDS_PINID='P1';
NODE_NAME     X38 3
 '@S9S_MB_2U_LIB.S9S_MB_2U(SCH_1):PAGE310_I5@PURE_QUANTA.TP_TDR_4P_FTS(CHIPS)':
 'P2': CDS_PINID='P2';
NODE_NAME     X44 2
 '@S9S_MB_2U_LIB.S9S_MB_2U(SCH_1):PAGE310_I6@PURE_QUANTA.TP_TDR_4P_FTS(CHIPS)':
 'P1': CDS_PINID='P1';
NODE_NAME     X44 3
 '@S9S_MB_2U_LIB.S9S_MB_2U(SCH_1):PAGE310_I6@PURE_QUANTA.TP_TDR_4P_FTS(CHIPS)':
 'P2': CDS_PINID='P2';
NODE_NAME     X37 2
 '@S9S_MB_2U_LIB.S9S_MB_2U(SCH_1):PAGE310_I7@PURE_QUANTA.TP_TDR_4P_FTS(CHIPS)':
 'P1': CDS_PINID='P1';
NODE_NAME     X37 3
 '@S9S_MB_2U_LIB.S9S_MB_2U(SCH_1):PAGE310_I7@PURE_QUANTA.TP_TDR_4P_FTS(CHIPS)':
 'P2': CDS_PINID='P2';
NODE_NAME     X36 2
 '@S9S_MB_2U_LIB.S9S_MB_2U(SCH_1):PAGE310_I8@PURE_QUANTA.TP_TDR_4P_FTS(CHIPS)':
 'P1': CDS_PINID='P1';
NODE_NAME     X36 3
 '@S9S_MB_2U_LIB.S9S_MB_2U(SCH_1):PAGE310_I8@PURE_QUANTA.TP_TDR_4P_FTS(CHIPS)':
 'P2': CDS_PINID='P2';
NODE_NAME     X43 2
 '@S9S_MB_2U_LIB.S9S_MB_2U(SCH_1):PAGE310_I9@PURE_QUANTA.TP_TDR_4P_FTS(CHIPS)':
 'P1': CDS_PINID='P1';
NODE_NAME     X43 3
 '@S9S_MB_2U_LIB.S9S_MB_2U(SCH_1):PAGE310_I9@PURE_QUANTA.TP_TDR_4P_FTS(CHIPS)':
 'P2': CDS_PINID='P2';
NODE_NAME     X42 2
 '@S9S_MB_2U_LIB.S9S_MB_2U(SCH_1):PAGE310_I10@PURE_QUANTA.TP_TDR_4P_FTS(CHIPS)':
 'P1': CDS_PINID='P1';
NODE_NAME     X42 3
 '@S9S_MB_2U_LIB.S9S_MB_2U(SCH_1):PAGE310_I10@PURE_QUANTA.TP_TDR_4P_FTS(CHIPS)':
 'P2': CDS_PINID='P2';
NODE_NAME     X41 2
 '@S9S_MB_2U_LIB.S9S_MB_2U(SCH_1):PAGE310_I15@PURE_QUANTA.TP_TDR_4P_FTS(CHIPS)':
 'P1': CDS_PINID='P1';
NODE_NAME     X41 3
 '@S9S_MB_2U_LIB.S9S_MB_2U(SCH_1):PAGE310_I15@PURE_QUANTA.TP_TDR_4P_FTS(CHIPS)':
 'P2': CDS_PINID='P2';
NODE_NAME     X35 2
 '@S9S_MB_2U_LIB.S9S_MB_2U(SCH_1):PAGE310_I16@PURE_QUANTA.TP_TDR_4P_FTS(CHIPS)':
 'P1': CDS_PINID='P1';
NODE_NAME     X35 3
 '@S9S_MB_2U_LIB.S9S_MB_2U(SCH_1):PAGE310_I16@PURE_QUANTA.TP_TDR_4P_FTS(CHIPS)':
 'P2': CDS_PINID='P2';
NODE_NAME     X34 2
 '@S9S_MB_2U_LIB.S9S_MB_2U(SCH_1):PAGE310_I19@PURE_QUANTA.TP_TDR_4P_FTS(CHIPS)':
 'P1': CDS_PINID='P1';
NODE_NAME     X34 3
 '@S9S_MB_2U_LIB.S9S_MB_2U(SCH_1):PAGE310_I19@PURE_QUANTA.TP_TDR_4P_FTS(CHIPS)':
 'P2': CDS_PINID='P2';
NODE_NAME     X33 2
 '@S9S_MB_2U_LIB.S9S_MB_2U(SCH_1):PAGE310_I20@PURE_QUANTA.TP_TDR_4P_FTS(CHIPS)':
 'P1': CDS_PINID='P1';
NODE_NAME     X33 3
 '@S9S_MB_2U_LIB.S9S_MB_2U(SCH_1):PAGE310_I20@PURE_QUANTA.TP_TDR_4P_FTS(CHIPS)':
 'P2': CDS_PINID='P2';
NODE_NAME     X40 2
 '@S9S_MB_2U_LIB.S9S_MB_2U(SCH_1):PAGE310_I21@PURE_QUANTA.TP_TDR_4P_FTS(CHIPS)':
 'P1': CDS_PINID='P1';
NODE_NAME     X40 3
 '@S9S_MB_2U_LIB.S9S_MB_2U(SCH_1):PAGE310_I21@PURE_QUANTA.TP_TDR_4P_FTS(CHIPS)':
 'P2': CDS_PINID='P2';
NODE_NAME     X39 2
 '@S9S_MB_2U_LIB.S9S_MB_2U(SCH_1):PAGE310_I22@PURE_QUANTA.TP_TDR_4P_FTS(CHIPS)':
 'P1': CDS_PINID='P1';
NODE_NAME     X39 3
 '@S9S_MB_2U_LIB.S9S_MB_2U(SCH_1):PAGE310_I22@PURE_QUANTA.TP_TDR_4P_FTS(CHIPS)':
 'P2': CDS_PINID='P2';
NET_NAME
'TCA9539_0_ADD0'
 '@S9S_MB_2U_LIB.S9S_MB_2U(SCH_1):TCA9539_0_ADD0':
 C_SIGNAL='@s9s_mb_2u_lib.s9s_mb_2u(sch_1):tca9539_0_add0';
NODE_NAME     U181 21
 '@S9S_MB_2U_LIB.S9S_MB_2U(SCH_1):PAGE214_I66@PURE_QUANTA.PCA9539RPW(CHIPS)':
 'A0': CDS_PINID='A0';
NODE_NAME     R2695 2
 '@S9S_MB_2U_LIB.S9S_MB_2U(SCH_1):PAGE214_I74@PURE_QUANTA.Q_RES(CHIPS)':
 'B': CDS_PINID='B';
NODE_NAME     R2696 1
 '@S9S_MB_2U_LIB.S9S_MB_2U(SCH_1):PAGE214_I75@PURE_QUANTA.Q_RES(CHIPS)':
 'A': CDS_PINID='A';
NET_NAME
'TCA9539_0_ADD1'
 '@S9S_MB_2U_LIB.S9S_MB_2U(SCH_1):TCA9539_0_ADD1':
 C_SIGNAL='@s9s_mb_2u_lib.s9s_mb_2u(sch_1):tca9539_0_add1';
NODE_NAME     U181 2
 '@S9S_MB_2U_LIB.S9S_MB_2U(SCH_1):PAGE214_I66@PURE_QUANTA.PCA9539RPW(CHIPS)':
 'A1': CDS_PINID='A1';
NODE_NAME     R2693 2
 '@S9S_MB_2U_LIB.S9S_MB_2U(SCH_1):PAGE214_I76@PURE_QUANTA.Q_RES(CHIPS)':
 'B': CDS_PINID='B';
NODE_NAME     R2694 1
 '@S9S_MB_2U_LIB.S9S_MB_2U(SCH_1):PAGE214_I77@PURE_QUANTA.Q_RES(CHIPS)':
 'A': CDS_PINID='A';
NET_NAME
'TDR_DIFF_100_BOT_DN'
 '@S9S_MB_2U_LIB.S9S_MB_2U(SCH_1):TDR_DIFF_100_BOT_DN':
 C_SIGNAL='@s9s_mb_2u_lib.s9s_mb_2u(sch_1):tdr_diff_100_bot_dn';
NODE_NAME     X24 1
 '@S9S_MB_2U_LIB.S9S_MB_2U(SCH_1):PAGE288_I42@PURE_QUANTA.TP_TDR_4P_FTS(CHIPS)':
 'S1': CDS_PINID='S1';
NODE_NAME     X18 4
 '@S9S_MB_2U_LIB.S9S_MB_2U(SCH_1):PAGE288_I43@PURE_QUANTA.TP_TDR_4P_FTS(CHIPS)':
 'S2': CDS_PINID='S2';
NET_NAME
'TDR_DIFF_100_BOT_DP'
 '@S9S_MB_2U_LIB.S9S_MB_2U(SCH_1):TDR_DIFF_100_BOT_DP':
 C_SIGNAL='@s9s_mb_2u_lib.s9s_mb_2u(sch_1):tdr_diff_100_bot_dp';
NODE_NAME     X24 4
 '@S9S_MB_2U_LIB.S9S_MB_2U(SCH_1):PAGE288_I42@PURE_QUANTA.TP_TDR_4P_FTS(CHIPS)':
 'S2': CDS_PINID='S2';
NODE_NAME     X18 1
 '@S9S_MB_2U_LIB.S9S_MB_2U(SCH_1):PAGE288_I43@PURE_QUANTA.TP_TDR_4P_FTS(CHIPS)':
 'S1': CDS_PINID='S1';
NET_NAME
'TDR_DIFF_100_IN1_DN'
 '@S9S_MB_2U_LIB.S9S_MB_2U(SCH_1):TDR_DIFF_100_IN1_DN':
 C_SIGNAL='@s9s_mb_2u_lib.s9s_mb_2u(sch_1):tdr_diff_100_in1_dn';
NODE_NAME     X20 1
 '@S9S_MB_2U_LIB.S9S_MB_2U(SCH_1):PAGE288_I4@PURE_QUANTA.TP_TDR_4P_FTS(CHIPS)':
 'S1': CDS_PINID='S1';
NODE_NAME     X14 4
 '@S9S_MB_2U_LIB.S9S_MB_2U(SCH_1):PAGE288_I12@PURE_QUANTA.TP_TDR_4P_FTS(CHIPS)':
 'S2': CDS_PINID='S2';
NET_NAME
'TDR_DIFF_100_IN1_DP'
 '@S9S_MB_2U_LIB.S9S_MB_2U(SCH_1):TDR_DIFF_100_IN1_DP':
 C_SIGNAL='@s9s_mb_2u_lib.s9s_mb_2u(sch_1):tdr_diff_100_in1_dp';
NODE_NAME     X20 4
 '@S9S_MB_2U_LIB.S9S_MB_2U(SCH_1):PAGE288_I4@PURE_QUANTA.TP_TDR_4P_FTS(CHIPS)':
 'S2': CDS_PINID='S2';
NODE_NAME     X14 1
 '@S9S_MB_2U_LIB.S9S_MB_2U(SCH_1):PAGE288_I12@PURE_QUANTA.TP_TDR_4P_FTS(CHIPS)':
 'S1': CDS_PINID='S1';
NET_NAME
'TDR_DIFF_100_IN2_DN'
 '@S9S_MB_2U_LIB.S9S_MB_2U(SCH_1):TDR_DIFF_100_IN2_DN':
 C_SIGNAL='@s9s_mb_2u_lib.s9s_mb_2u(sch_1):tdr_diff_100_in2_dn';
NODE_NAME     X21 1
 '@S9S_MB_2U_LIB.S9S_MB_2U(SCH_1):PAGE288_I9@PURE_QUANTA.TP_TDR_4P_FTS(CHIPS)':
 'S1': CDS_PINID='S1';
NODE_NAME     X15 4
 '@S9S_MB_2U_LIB.S9S_MB_2U(SCH_1):PAGE288_I17@PURE_QUANTA.TP_TDR_4P_FTS(CHIPS)':
 'S2': CDS_PINID='S2';
NET_NAME
'TDR_DIFF_100_IN2_DP'
 '@S9S_MB_2U_LIB.S9S_MB_2U(SCH_1):TDR_DIFF_100_IN2_DP':
 C_SIGNAL='@s9s_mb_2u_lib.s9s_mb_2u(sch_1):tdr_diff_100_in2_dp';
NODE_NAME     X21 4
 '@S9S_MB_2U_LIB.S9S_MB_2U(SCH_1):PAGE288_I9@PURE_QUANTA.TP_TDR_4P_FTS(CHIPS)':
 'S2': CDS_PINID='S2';
NODE_NAME     X15 1
 '@S9S_MB_2U_LIB.S9S_MB_2U(SCH_1):PAGE288_I17@PURE_QUANTA.TP_TDR_4P_FTS(CHIPS)':
 'S1': CDS_PINID='S1';
NET_NAME
'TDR_DIFF_100_IN3_DN'
 '@S9S_MB_2U_LIB.S9S_MB_2U(SCH_1):TDR_DIFF_100_IN3_DN':
 C_SIGNAL='@s9s_mb_2u_lib.s9s_mb_2u(sch_1):tdr_diff_100_in3_dn';
NODE_NAME     X22 1
 '@S9S_MB_2U_LIB.S9S_MB_2U(SCH_1):PAGE288_I8@PURE_QUANTA.TP_TDR_4P_FTS(CHIPS)':
 'S1': CDS_PINID='S1';
NODE_NAME     X16 4
 '@S9S_MB_2U_LIB.S9S_MB_2U(SCH_1):PAGE288_I18@PURE_QUANTA.TP_TDR_4P_FTS(CHIPS)':
 'S2': CDS_PINID='S2';
NET_NAME
'TDR_DIFF_100_IN3_DP'
 '@S9S_MB_2U_LIB.S9S_MB_2U(SCH_1):TDR_DIFF_100_IN3_DP':
 C_SIGNAL='@s9s_mb_2u_lib.s9s_mb_2u(sch_1):tdr_diff_100_in3_dp';
NODE_NAME     X22 4
 '@S9S_MB_2U_LIB.S9S_MB_2U(SCH_1):PAGE288_I8@PURE_QUANTA.TP_TDR_4P_FTS(CHIPS)':
 'S2': CDS_PINID='S2';
NODE_NAME     X16 1
 '@S9S_MB_2U_LIB.S9S_MB_2U(SCH_1):PAGE288_I18@PURE_QUANTA.TP_TDR_4P_FTS(CHIPS)':
 'S1': CDS_PINID='S1';
NET_NAME
'TDR_DIFF_100_IN4_DN'
 '@S9S_MB_2U_LIB.S9S_MB_2U(SCH_1):TDR_DIFF_100_IN4_DN':
 C_SIGNAL='@s9s_mb_2u_lib.s9s_mb_2u(sch_1):tdr_diff_100_in4_dn';
NODE_NAME     X23 1
 '@S9S_MB_2U_LIB.S9S_MB_2U(SCH_1):PAGE288_I10@PURE_QUANTA.TP_TDR_4P_FTS(CHIPS)':
 'S1': CDS_PINID='S1';
NODE_NAME     X17 4
 '@S9S_MB_2U_LIB.S9S_MB_2U(SCH_1):PAGE288_I19@PURE_QUANTA.TP_TDR_4P_FTS(CHIPS)':
 'S2': CDS_PINID='S2';
NET_NAME
'TDR_DIFF_100_IN4_DP'
 '@S9S_MB_2U_LIB.S9S_MB_2U(SCH_1):TDR_DIFF_100_IN4_DP':
 C_SIGNAL='@s9s_mb_2u_lib.s9s_mb_2u(sch_1):tdr_diff_100_in4_dp';
NODE_NAME     X23 4
 '@S9S_MB_2U_LIB.S9S_MB_2U(SCH_1):PAGE288_I10@PURE_QUANTA.TP_TDR_4P_FTS(CHIPS)':
 'S2': CDS_PINID='S2';
NODE_NAME     X17 1
 '@S9S_MB_2U_LIB.S9S_MB_2U(SCH_1):PAGE288_I19@PURE_QUANTA.TP_TDR_4P_FTS(CHIPS)':
 'S1': CDS_PINID='S1';
NET_NAME
'TDR_DIFF_100_IN5_DN'
 '@S9S_MB_2U_LIB.S9S_MB_2U(SCH_1):TDR_DIFF_100_IN5_DN':
 C_SIGNAL='@s9s_mb_2u_lib.s9s_mb_2u(sch_1):tdr_diff_100_in5_dn';
NODE_NAME     X31 1
 '@S9S_MB_2U_LIB.S9S_MB_2U(SCH_1):PAGE288_I112@PURE_QUANTA.TP_TDR_4P_FTS(CHIPS)':
 'S1': CDS_PINID='S1';
NODE_NAME     X29 4
 '@S9S_MB_2U_LIB.S9S_MB_2U(SCH_1):PAGE288_I116@PURE_QUANTA.TP_TDR_4P_FTS(CHIPS)':
 'S2': CDS_PINID='S2';
NET_NAME
'TDR_DIFF_100_IN5_DP'
 '@S9S_MB_2U_LIB.S9S_MB_2U(SCH_1):TDR_DIFF_100_IN5_DP':
 C_SIGNAL='@s9s_mb_2u_lib.s9s_mb_2u(sch_1):tdr_diff_100_in5_dp';
NODE_NAME     X31 4
 '@S9S_MB_2U_LIB.S9S_MB_2U(SCH_1):PAGE288_I112@PURE_QUANTA.TP_TDR_4P_FTS(CHIPS)':
 'S2': CDS_PINID='S2';
NODE_NAME     X29 1
 '@S9S_MB_2U_LIB.S9S_MB_2U(SCH_1):PAGE288_I116@PURE_QUANTA.TP_TDR_4P_FTS(CHIPS)':
 'S1': CDS_PINID='S1';
NET_NAME
'TDR_DIFF_100_IN6_DN'
 '@S9S_MB_2U_LIB.S9S_MB_2U(SCH_1):TDR_DIFF_100_IN6_DN':
 C_SIGNAL='@s9s_mb_2u_lib.s9s_mb_2u(sch_1):tdr_diff_100_in6_dn';
NODE_NAME     X32 1
 '@S9S_MB_2U_LIB.S9S_MB_2U(SCH_1):PAGE288_I115@PURE_QUANTA.TP_TDR_4P_FTS(CHIPS)':
 'S1': CDS_PINID='S1';
NODE_NAME     X30 4
 '@S9S_MB_2U_LIB.S9S_MB_2U(SCH_1):PAGE288_I117@PURE_QUANTA.TP_TDR_4P_FTS(CHIPS)':
 'S2': CDS_PINID='S2';
NET_NAME
'TDR_DIFF_100_IN6_DP'
 '@S9S_MB_2U_LIB.S9S_MB_2U(SCH_1):TDR_DIFF_100_IN6_DP':
 C_SIGNAL='@s9s_mb_2u_lib.s9s_mb_2u(sch_1):tdr_diff_100_in6_dp';
NODE_NAME     X32 4
 '@S9S_MB_2U_LIB.S9S_MB_2U(SCH_1):PAGE288_I115@PURE_QUANTA.TP_TDR_4P_FTS(CHIPS)':
 'S2': CDS_PINID='S2';
NODE_NAME     X30 1
 '@S9S_MB_2U_LIB.S9S_MB_2U(SCH_1):PAGE288_I117@PURE_QUANTA.TP_TDR_4P_FTS(CHIPS)':
 'S1': CDS_PINID='S1';
NET_NAME
'TDR_DIFF_100_TOP_DN'
 '@S9S_MB_2U_LIB.S9S_MB_2U(SCH_1):TDR_DIFF_100_TOP_DN':
 C_SIGNAL='@s9s_mb_2u_lib.s9s_mb_2u(sch_1):tdr_diff_100_top_dn';
NODE_NAME     X19 1
 '@S9S_MB_2U_LIB.S9S_MB_2U(SCH_1):PAGE288_I3@PURE_QUANTA.TP_TDR_4P_FTS(CHIPS)':
 'S1': CDS_PINID='S1';
NODE_NAME     X13 4
 '@S9S_MB_2U_LIB.S9S_MB_2U(SCH_1):PAGE288_I11@PURE_QUANTA.TP_TDR_4P_FTS(CHIPS)':
 'S2': CDS_PINID='S2';
NET_NAME
'TDR_DIFF_100_TOP_DP'
 '@S9S_MB_2U_LIB.S9S_MB_2U(SCH_1):TDR_DIFF_100_TOP_DP':
 C_SIGNAL='@s9s_mb_2u_lib.s9s_mb_2u(sch_1):tdr_diff_100_top_dp';
NODE_NAME     X19 4
 '@S9S_MB_2U_LIB.S9S_MB_2U(SCH_1):PAGE288_I3@PURE_QUANTA.TP_TDR_4P_FTS(CHIPS)':
 'S2': CDS_PINID='S2';
NODE_NAME     X13 1
 '@S9S_MB_2U_LIB.S9S_MB_2U(SCH_1):PAGE288_I11@PURE_QUANTA.TP_TDR_4P_FTS(CHIPS)':
 'S1': CDS_PINID='S1';
NET_NAME
'TDR_DIFF_85_BOT_DN'
 '@S9S_MB_2U_LIB.S9S_MB_2U(SCH_1):TDR_DIFF_85_BOT_DN':
 C_SIGNAL='@s9s_mb_2u_lib.s9s_mb_2u(sch_1):tdr_diff_85_bot_dn';
NODE_NAME     X12 1
 '@S9S_MB_2U_LIB.S9S_MB_2U(SCH_1):PAGE288_I46@PURE_QUANTA.TP_TDR_4P_FTS(CHIPS)':
 'S1': CDS_PINID='S1';
NODE_NAME     X6 4
 '@S9S_MB_2U_LIB.S9S_MB_2U(SCH_1):PAGE288_I47@PURE_QUANTA.TP_TDR_4P_FTS(CHIPS)':
 'S2': CDS_PINID='S2';
NET_NAME
'TDR_DIFF_85_BOT_DP'
 '@S9S_MB_2U_LIB.S9S_MB_2U(SCH_1):TDR_DIFF_85_BOT_DP':
 C_SIGNAL='@s9s_mb_2u_lib.s9s_mb_2u(sch_1):tdr_diff_85_bot_dp';
NODE_NAME     X12 4
 '@S9S_MB_2U_LIB.S9S_MB_2U(SCH_1):PAGE288_I46@PURE_QUANTA.TP_TDR_4P_FTS(CHIPS)':
 'S2': CDS_PINID='S2';
NODE_NAME     X6 1
 '@S9S_MB_2U_LIB.S9S_MB_2U(SCH_1):PAGE288_I47@PURE_QUANTA.TP_TDR_4P_FTS(CHIPS)':
 'S1': CDS_PINID='S1';
NET_NAME
'TDR_DIFF_85_IN1_DN'
 '@S9S_MB_2U_LIB.S9S_MB_2U(SCH_1):TDR_DIFF_85_IN1_DN':
 C_SIGNAL='@s9s_mb_2u_lib.s9s_mb_2u(sch_1):tdr_diff_85_in1_dn';
NODE_NAME     X8 1
 '@S9S_MB_2U_LIB.S9S_MB_2U(SCH_1):PAGE288_I27@PURE_QUANTA.TP_TDR_4P_FTS(CHIPS)':
 'S1': CDS_PINID='S1';
NODE_NAME     X2 4
 '@S9S_MB_2U_LIB.S9S_MB_2U(SCH_1):PAGE288_I30@PURE_QUANTA.TP_TDR_4P_FTS(CHIPS)':
 'S2': CDS_PINID='S2';
NET_NAME
'TDR_DIFF_85_IN1_DP'
 '@S9S_MB_2U_LIB.S9S_MB_2U(SCH_1):TDR_DIFF_85_IN1_DP':
 C_SIGNAL='@s9s_mb_2u_lib.s9s_mb_2u(sch_1):tdr_diff_85_in1_dp';
NODE_NAME     X8 4
 '@S9S_MB_2U_LIB.S9S_MB_2U(SCH_1):PAGE288_I27@PURE_QUANTA.TP_TDR_4P_FTS(CHIPS)':
 'S2': CDS_PINID='S2';
NODE_NAME     X2 1
 '@S9S_MB_2U_LIB.S9S_MB_2U(SCH_1):PAGE288_I30@PURE_QUANTA.TP_TDR_4P_FTS(CHIPS)':
 'S1': CDS_PINID='S1';
NET_NAME
'TDR_DIFF_85_IN2_DN'
 '@S9S_MB_2U_LIB.S9S_MB_2U(SCH_1):TDR_DIFF_85_IN2_DN':
 C_SIGNAL='@s9s_mb_2u_lib.s9s_mb_2u(sch_1):tdr_diff_85_in2_dn';
NODE_NAME     X9 1
 '@S9S_MB_2U_LIB.S9S_MB_2U(SCH_1):PAGE288_I32@PURE_QUANTA.TP_TDR_4P_FTS(CHIPS)':
 'S1': CDS_PINID='S1';
NODE_NAME     X3 4
 '@S9S_MB_2U_LIB.S9S_MB_2U(SCH_1):PAGE288_I35@PURE_QUANTA.TP_TDR_4P_FTS(CHIPS)':
 'S2': CDS_PINID='S2';
NET_NAME
'TDR_DIFF_85_IN2_DP'
 '@S9S_MB_2U_LIB.S9S_MB_2U(SCH_1):TDR_DIFF_85_IN2_DP':
 C_SIGNAL='@s9s_mb_2u_lib.s9s_mb_2u(sch_1):tdr_diff_85_in2_dp';
NODE_NAME     X9 4
 '@S9S_MB_2U_LIB.S9S_MB_2U(SCH_1):PAGE288_I32@PURE_QUANTA.TP_TDR_4P_FTS(CHIPS)':
 'S2': CDS_PINID='S2';
NODE_NAME     X3 1
 '@S9S_MB_2U_LIB.S9S_MB_2U(SCH_1):PAGE288_I35@PURE_QUANTA.TP_TDR_4P_FTS(CHIPS)':
 'S1': CDS_PINID='S1';
NET_NAME
'TDR_DIFF_85_IN3_DN'
 '@S9S_MB_2U_LIB.S9S_MB_2U(SCH_1):TDR_DIFF_85_IN3_DN':
 C_SIGNAL='@s9s_mb_2u_lib.s9s_mb_2u(sch_1):tdr_diff_85_in3_dn';
NODE_NAME     X10 1
 '@S9S_MB_2U_LIB.S9S_MB_2U(SCH_1):PAGE288_I33@PURE_QUANTA.TP_TDR_4P_FTS(CHIPS)':
 'S1': CDS_PINID='S1';
NODE_NAME     X4 4
 '@S9S_MB_2U_LIB.S9S_MB_2U(SCH_1):PAGE288_I37@PURE_QUANTA.TP_TDR_4P_FTS(CHIPS)':
 'S2': CDS_PINID='S2';
NET_NAME
'TDR_DIFF_85_IN3_DP'
 '@S9S_MB_2U_LIB.S9S_MB_2U(SCH_1):TDR_DIFF_85_IN3_DP':
 C_SIGNAL='@s9s_mb_2u_lib.s9s_mb_2u(sch_1):tdr_diff_85_in3_dp';
NODE_NAME     X10 4
 '@S9S_MB_2U_LIB.S9S_MB_2U(SCH_1):PAGE288_I33@PURE_QUANTA.TP_TDR_4P_FTS(CHIPS)':
 'S2': CDS_PINID='S2';
NODE_NAME     X4 1
 '@S9S_MB_2U_LIB.S9S_MB_2U(SCH_1):PAGE288_I37@PURE_QUANTA.TP_TDR_4P_FTS(CHIPS)':
 'S1': CDS_PINID='S1';
NET_NAME
'TDR_DIFF_85_IN4_DN'
 '@S9S_MB_2U_LIB.S9S_MB_2U(SCH_1):TDR_DIFF_85_IN4_DN':
 C_SIGNAL='@s9s_mb_2u_lib.s9s_mb_2u(sch_1):tdr_diff_85_in4_dn';
NODE_NAME     X11 1
 '@S9S_MB_2U_LIB.S9S_MB_2U(SCH_1):PAGE288_I34@PURE_QUANTA.TP_TDR_4P_FTS(CHIPS)':
 'S1': CDS_PINID='S1';
NODE_NAME     X5 4
 '@S9S_MB_2U_LIB.S9S_MB_2U(SCH_1):PAGE288_I39@PURE_QUANTA.TP_TDR_4P_FTS(CHIPS)':
 'S2': CDS_PINID='S2';
NET_NAME
'TDR_DIFF_85_IN4_DP'
 '@S9S_MB_2U_LIB.S9S_MB_2U(SCH_1):TDR_DIFF_85_IN4_DP':
 C_SIGNAL='@s9s_mb_2u_lib.s9s_mb_2u(sch_1):tdr_diff_85_in4_dp';
NODE_NAME     X11 4
 '@S9S_MB_2U_LIB.S9S_MB_2U(SCH_1):PAGE288_I34@PURE_QUANTA.TP_TDR_4P_FTS(CHIPS)':
 'S2': CDS_PINID='S2';
NODE_NAME     X5 1
 '@S9S_MB_2U_LIB.S9S_MB_2U(SCH_1):PAGE288_I39@PURE_QUANTA.TP_TDR_4P_FTS(CHIPS)':
 'S1': CDS_PINID='S1';
NET_NAME
'TDR_DIFF_85_IN5_DN'
 '@S9S_MB_2U_LIB.S9S_MB_2U(SCH_1):TDR_DIFF_85_IN5_DN':
 C_SIGNAL='@s9s_mb_2u_lib.s9s_mb_2u(sch_1):tdr_diff_85_in5_dn';
NODE_NAME     X27 1
 '@S9S_MB_2U_LIB.S9S_MB_2U(SCH_1):PAGE288_I106@PURE_QUANTA.TP_TDR_4P_FTS(CHIPS)':
 'S1': CDS_PINID='S1';
NODE_NAME     X25 4
 '@S9S_MB_2U_LIB.S9S_MB_2U(SCH_1):PAGE288_I108@PURE_QUANTA.TP_TDR_4P_FTS(CHIPS)':
 'S2': CDS_PINID='S2';
NET_NAME
'TDR_DIFF_85_IN5_DP'
 '@S9S_MB_2U_LIB.S9S_MB_2U(SCH_1):TDR_DIFF_85_IN5_DP':
 C_SIGNAL='@s9s_mb_2u_lib.s9s_mb_2u(sch_1):tdr_diff_85_in5_dp';
NODE_NAME     X27 4
 '@S9S_MB_2U_LIB.S9S_MB_2U(SCH_1):PAGE288_I106@PURE_QUANTA.TP_TDR_4P_FTS(CHIPS)':
 'S2': CDS_PINID='S2';
NODE_NAME     X25 1
 '@S9S_MB_2U_LIB.S9S_MB_2U(SCH_1):PAGE288_I108@PURE_QUANTA.TP_TDR_4P_FTS(CHIPS)':
 'S1': CDS_PINID='S1';
NET_NAME
'TDR_DIFF_85_IN6_DN'
 '@S9S_MB_2U_LIB.S9S_MB_2U(SCH_1):TDR_DIFF_85_IN6_DN':
 C_SIGNAL='@s9s_mb_2u_lib.s9s_mb_2u(sch_1):tdr_diff_85_in6_dn';
NODE_NAME     X28 1
 '@S9S_MB_2U_LIB.S9S_MB_2U(SCH_1):PAGE288_I107@PURE_QUANTA.TP_TDR_4P_FTS(CHIPS)':
 'S1': CDS_PINID='S1';
NODE_NAME     X26 4
 '@S9S_MB_2U_LIB.S9S_MB_2U(SCH_1):PAGE288_I110@PURE_QUANTA.TP_TDR_4P_FTS(CHIPS)':
 'S2': CDS_PINID='S2';
NET_NAME
'TDR_DIFF_85_IN6_DP'
 '@S9S_MB_2U_LIB.S9S_MB_2U(SCH_1):TDR_DIFF_85_IN6_DP':
 C_SIGNAL='@s9s_mb_2u_lib.s9s_mb_2u(sch_1):tdr_diff_85_in6_dp';
NODE_NAME     X28 4
 '@S9S_MB_2U_LIB.S9S_MB_2U(SCH_1):PAGE288_I107@PURE_QUANTA.TP_TDR_4P_FTS(CHIPS)':
 'S2': CDS_PINID='S2';
NODE_NAME     X26 1
 '@S9S_MB_2U_LIB.S9S_MB_2U(SCH_1):PAGE288_I110@PURE_QUANTA.TP_TDR_4P_FTS(CHIPS)':
 'S1': CDS_PINID='S1';
NET_NAME
'TDR_DIFF_85_TOP_DN'
 '@S9S_MB_2U_LIB.S9S_MB_2U(SCH_1):TDR_DIFF_85_TOP_DN':
 C_SIGNAL='@s9s_mb_2u_lib.s9s_mb_2u(sch_1):tdr_diff_85_top_dn';
NODE_NAME     X7 1
 '@S9S_MB_2U_LIB.S9S_MB_2U(SCH_1):PAGE288_I26@PURE_QUANTA.TP_TDR_4P_FTS(CHIPS)':
 'S1': CDS_PINID='S1';
NODE_NAME     X1 4
 '@S9S_MB_2U_LIB.S9S_MB_2U(SCH_1):PAGE288_I28@PURE_QUANTA.TP_TDR_4P_FTS(CHIPS)':
 'S2': CDS_PINID='S2';
NET_NAME
'TDR_DIFF_85_TOP_DP'
 '@S9S_MB_2U_LIB.S9S_MB_2U(SCH_1):TDR_DIFF_85_TOP_DP':
 C_SIGNAL='@s9s_mb_2u_lib.s9s_mb_2u(sch_1):tdr_diff_85_top_dp';
NODE_NAME     X7 4
 '@S9S_MB_2U_LIB.S9S_MB_2U(SCH_1):PAGE288_I26@PURE_QUANTA.TP_TDR_4P_FTS(CHIPS)':
 'S2': CDS_PINID='S2';
NODE_NAME     X1 1
 '@S9S_MB_2U_LIB.S9S_MB_2U(SCH_1):PAGE288_I28@PURE_QUANTA.TP_TDR_4P_FTS(CHIPS)':
 'S1': CDS_PINID='S1';
NET_NAME
'TDR_SE_40_OHM_BOT'
 '@S9S_MB_2U_LIB.S9S_MB_2U(SCH_1):TDR_SE_40_OHM_BOT':
 C_SIGNAL='@s9s_mb_2u_lib.s9s_mb_2u(sch_1):tdr_se_40_ohm_bot';
NODE_NAME     DB6 2
 '@S9S_MB_2U_LIB.S9S_MB_2U(SCH_1):PAGE288_I69@PURE_QUANTA.TDR_3P(CHIPS)':
 'IO1': CDS_PINID='IO1';
NODE_NAME     DB6 3
 '@S9S_MB_2U_LIB.S9S_MB_2U(SCH_1):PAGE288_I69@PURE_QUANTA.TDR_3P(CHIPS)':
 'IO2': CDS_PINID='IO2';
NET_NAME
'TDR_SE_40_OHM_IN1'
 '@S9S_MB_2U_LIB.S9S_MB_2U(SCH_1):TDR_SE_40_OHM_IN1':
 C_SIGNAL='@s9s_mb_2u_lib.s9s_mb_2u(sch_1):tdr_se_40_ohm_in1';
NODE_NAME     DB2 2
 '@S9S_MB_2U_LIB.S9S_MB_2U(SCH_1):PAGE288_I62@PURE_QUANTA.TDR_3P(CHIPS)':
 'IO1': CDS_PINID='IO1';
NODE_NAME     DB2 3
 '@S9S_MB_2U_LIB.S9S_MB_2U(SCH_1):PAGE288_I62@PURE_QUANTA.TDR_3P(CHIPS)':
 'IO2': CDS_PINID='IO2';
NET_NAME
'TDR_SE_40_OHM_IN2'
 '@S9S_MB_2U_LIB.S9S_MB_2U(SCH_1):TDR_SE_40_OHM_IN2':
 C_SIGNAL='@s9s_mb_2u_lib.s9s_mb_2u(sch_1):tdr_se_40_ohm_in2';
NODE_NAME     DB3 2
 '@S9S_MB_2U_LIB.S9S_MB_2U(SCH_1):PAGE288_I63@PURE_QUANTA.TDR_3P(CHIPS)':
 'IO1': CDS_PINID='IO1';
NODE_NAME     DB3 3
 '@S9S_MB_2U_LIB.S9S_MB_2U(SCH_1):PAGE288_I63@PURE_QUANTA.TDR_3P(CHIPS)':
 'IO2': CDS_PINID='IO2';
NET_NAME
'TDR_SE_40_OHM_IN3'
 '@S9S_MB_2U_LIB.S9S_MB_2U(SCH_1):TDR_SE_40_OHM_IN3':
 C_SIGNAL='@s9s_mb_2u_lib.s9s_mb_2u(sch_1):tdr_se_40_ohm_in3';
NODE_NAME     DB4 2
 '@S9S_MB_2U_LIB.S9S_MB_2U(SCH_1):PAGE288_I67@PURE_QUANTA.TDR_3P(CHIPS)':
 'IO1': CDS_PINID='IO1';
NODE_NAME     DB4 3
 '@S9S_MB_2U_LIB.S9S_MB_2U(SCH_1):PAGE288_I67@PURE_QUANTA.TDR_3P(CHIPS)':
 'IO2': CDS_PINID='IO2';
NET_NAME
'TDR_SE_40_OHM_IN4'
 '@S9S_MB_2U_LIB.S9S_MB_2U(SCH_1):TDR_SE_40_OHM_IN4':
 C_SIGNAL='@s9s_mb_2u_lib.s9s_mb_2u(sch_1):tdr_se_40_ohm_in4';
NODE_NAME     DB5 2
 '@S9S_MB_2U_LIB.S9S_MB_2U(SCH_1):PAGE288_I68@PURE_QUANTA.TDR_3P(CHIPS)':
 'IO1': CDS_PINID='IO1';
NODE_NAME     DB5 3
 '@S9S_MB_2U_LIB.S9S_MB_2U(SCH_1):PAGE288_I68@PURE_QUANTA.TDR_3P(CHIPS)':
 'IO2': CDS_PINID='IO2';
NET_NAME
'TDR_SE_40_OHM_IN5'
 '@S9S_MB_2U_LIB.S9S_MB_2U(SCH_1):TDR_SE_40_OHM_IN5':
 C_SIGNAL='@s9s_mb_2u_lib.s9s_mb_2u(sch_1):tdr_se_40_ohm_in5';
NODE_NAME     DB13 2
 '@S9S_MB_2U_LIB.S9S_MB_2U(SCH_1):PAGE288_I101@PURE_QUANTA.TDR_3P(CHIPS)':
 'IO1': CDS_PINID='IO1';
NODE_NAME     DB13 3
 '@S9S_MB_2U_LIB.S9S_MB_2U(SCH_1):PAGE288_I101@PURE_QUANTA.TDR_3P(CHIPS)':
 'IO2': CDS_PINID='IO2';
NET_NAME
'TDR_SE_40_OHM_IN6'
 '@S9S_MB_2U_LIB.S9S_MB_2U(SCH_1):TDR_SE_40_OHM_IN6':
 C_SIGNAL='@s9s_mb_2u_lib.s9s_mb_2u(sch_1):tdr_se_40_ohm_in6';
NODE_NAME     DB14 2
 '@S9S_MB_2U_LIB.S9S_MB_2U(SCH_1):PAGE288_I96@PURE_QUANTA.TDR_3P(CHIPS)':
 'IO1': CDS_PINID='IO1';
NODE_NAME     DB14 3
 '@S9S_MB_2U_LIB.S9S_MB_2U(SCH_1):PAGE288_I96@PURE_QUANTA.TDR_3P(CHIPS)':
 'IO2': CDS_PINID='IO2';
NET_NAME
'TDR_SE_40_OHM_TOP'
 '@S9S_MB_2U_LIB.S9S_MB_2U(SCH_1):TDR_SE_40_OHM_TOP':
 C_SIGNAL='@s9s_mb_2u_lib.s9s_mb_2u(sch_1):tdr_se_40_ohm_top';
NODE_NAME     DB1 2
 '@S9S_MB_2U_LIB.S9S_MB_2U(SCH_1):PAGE288_I61@PURE_QUANTA.TDR_3P(CHIPS)':
 'IO1': CDS_PINID='IO1';
NODE_NAME     DB1 3
 '@S9S_MB_2U_LIB.S9S_MB_2U(SCH_1):PAGE288_I61@PURE_QUANTA.TDR_3P(CHIPS)':
 'IO2': CDS_PINID='IO2';
NET_NAME
'TDR_SE_50_OHM_BOT'
 '@S9S_MB_2U_LIB.S9S_MB_2U(SCH_1):TDR_SE_50_OHM_BOT':
 C_SIGNAL='@s9s_mb_2u_lib.s9s_mb_2u(sch_1):tdr_se_50_ohm_bot';
NODE_NAME     DB12 2
 '@S9S_MB_2U_LIB.S9S_MB_2U(SCH_1):PAGE288_I60@PURE_QUANTA.TDR_3P(CHIPS)':
 'IO1': CDS_PINID='IO1';
NODE_NAME     DB12 3
 '@S9S_MB_2U_LIB.S9S_MB_2U(SCH_1):PAGE288_I60@PURE_QUANTA.TDR_3P(CHIPS)':
 'IO2': CDS_PINID='IO2';
NET_NAME
'TDR_SE_50_OHM_IN1'
 '@S9S_MB_2U_LIB.S9S_MB_2U(SCH_1):TDR_SE_50_OHM_IN1':
 C_SIGNAL='@s9s_mb_2u_lib.s9s_mb_2u(sch_1):tdr_se_50_ohm_in1';
NODE_NAME     DB8 2
 '@S9S_MB_2U_LIB.S9S_MB_2U(SCH_1):PAGE288_I51@PURE_QUANTA.TDR_3P(CHIPS)':
 'IO1': CDS_PINID='IO1';
NODE_NAME     DB8 3
 '@S9S_MB_2U_LIB.S9S_MB_2U(SCH_1):PAGE288_I51@PURE_QUANTA.TDR_3P(CHIPS)':
 'IO2': CDS_PINID='IO2';
NET_NAME
'TDR_SE_50_OHM_IN2'
 '@S9S_MB_2U_LIB.S9S_MB_2U(SCH_1):TDR_SE_50_OHM_IN2':
 C_SIGNAL='@s9s_mb_2u_lib.s9s_mb_2u(sch_1):tdr_se_50_ohm_in2';
NODE_NAME     DB9 2
 '@S9S_MB_2U_LIB.S9S_MB_2U(SCH_1):PAGE288_I53@PURE_QUANTA.TDR_3P(CHIPS)':
 'IO1': CDS_PINID='IO1';
NODE_NAME     DB9 3
 '@S9S_MB_2U_LIB.S9S_MB_2U(SCH_1):PAGE288_I53@PURE_QUANTA.TDR_3P(CHIPS)':
 'IO2': CDS_PINID='IO2';
NET_NAME
'TDR_SE_50_OHM_IN3'
 '@S9S_MB_2U_LIB.S9S_MB_2U(SCH_1):TDR_SE_50_OHM_IN3':
 C_SIGNAL='@s9s_mb_2u_lib.s9s_mb_2u(sch_1):tdr_se_50_ohm_in3';
NODE_NAME     DB10 2
 '@S9S_MB_2U_LIB.S9S_MB_2U(SCH_1):PAGE288_I55@PURE_QUANTA.TDR_3P(CHIPS)':
 'IO1': CDS_PINID='IO1';
NODE_NAME     DB10 3
 '@S9S_MB_2U_LIB.S9S_MB_2U(SCH_1):PAGE288_I55@PURE_QUANTA.TDR_3P(CHIPS)':
 'IO2': CDS_PINID='IO2';
NET_NAME
'TDR_SE_50_OHM_IN4'
 '@S9S_MB_2U_LIB.S9S_MB_2U(SCH_1):TDR_SE_50_OHM_IN4':
 C_SIGNAL='@s9s_mb_2u_lib.s9s_mb_2u(sch_1):tdr_se_50_ohm_in4';
NODE_NAME     DB11 2
 '@S9S_MB_2U_LIB.S9S_MB_2U(SCH_1):PAGE288_I57@PURE_QUANTA.TDR_3P(CHIPS)':
 'IO1': CDS_PINID='IO1';
NODE_NAME     DB11 3
 '@S9S_MB_2U_LIB.S9S_MB_2U(SCH_1):PAGE288_I57@PURE_QUANTA.TDR_3P(CHIPS)':
 'IO2': CDS_PINID='IO2';
NET_NAME
'TDR_SE_50_OHM_IN5'
 '@S9S_MB_2U_LIB.S9S_MB_2U(SCH_1):TDR_SE_50_OHM_IN5':
 C_SIGNAL='@s9s_mb_2u_lib.s9s_mb_2u(sch_1):tdr_se_50_ohm_in5';
NODE_NAME     DB15 2
 '@S9S_MB_2U_LIB.S9S_MB_2U(SCH_1):PAGE288_I97@PURE_QUANTA.TDR_3P(CHIPS)':
 'IO1': CDS_PINID='IO1';
NODE_NAME     DB15 3
 '@S9S_MB_2U_LIB.S9S_MB_2U(SCH_1):PAGE288_I97@PURE_QUANTA.TDR_3P(CHIPS)':
 'IO2': CDS_PINID='IO2';
NET_NAME
'TDR_SE_50_OHM_IN6'
 '@S9S_MB_2U_LIB.S9S_MB_2U(SCH_1):TDR_SE_50_OHM_IN6':
 C_SIGNAL='@s9s_mb_2u_lib.s9s_mb_2u(sch_1):tdr_se_50_ohm_in6';
NODE_NAME     DB16 2
 '@S9S_MB_2U_LIB.S9S_MB_2U(SCH_1):PAGE288_I99@PURE_QUANTA.TDR_3P(CHIPS)':
 'IO1': CDS_PINID='IO1';
NODE_NAME     DB16 3
 '@S9S_MB_2U_LIB.S9S_MB_2U(SCH_1):PAGE288_I99@PURE_QUANTA.TDR_3P(CHIPS)':
 'IO2': CDS_PINID='IO2';
NET_NAME
'TDR_SE_50_OHM_TOP'
 '@S9S_MB_2U_LIB.S9S_MB_2U(SCH_1):TDR_SE_50_OHM_TOP':
 C_SIGNAL='@s9s_mb_2u_lib.s9s_mb_2u(sch_1):tdr_se_50_ohm_top';
NODE_NAME     DB7 2
 '@S9S_MB_2U_LIB.S9S_MB_2U(SCH_1):PAGE288_I49@PURE_QUANTA.TDR_3P(CHIPS)':
 'IO1': CDS_PINID='IO1';
NODE_NAME     DB7 3
 '@S9S_MB_2U_LIB.S9S_MB_2U(SCH_1):PAGE288_I49@PURE_QUANTA.TDR_3P(CHIPS)':
 'IO2': CDS_PINID='IO2';
NET_NAME
'TP_74CB_B8'
 '@S9S_MB_2U_LIB.S9S_MB_2U(SCH_1):TP_74CB_B8':
 C_SIGNAL='@s9s_mb_2u_lib.s9s_mb_2u(sch_1):tp_74cb_b8';
NODE_NAME     U17 8
 '@S9S_MB_2U_LIB.S9S_MB_2U(SCH_1):PAGE134_I80@PURE_QUANTA.74CBTLV3126PW(CHIPS)':
 '3B': CDS_PINID='\3b\';
NET_NAME
'TP_ADC128_INT'
 '@S9S_MB_2U_LIB.S9S_MB_2U(SCH_1):TP_ADC128_INT':
 C_SIGNAL='@s9s_mb_2u_lib.s9s_mb_2u(sch_1):tp_adc128_int';
NODE_NAME     U269 6
 '@S9S_MB_2U_LIB.S9S_MB_2U(SCH_1):PAGE239_I103@PURE_QUANTA.ADC128D818CIMTXNOPB(CHIPS)':
 'INT#': CDS_PINID='\int#\';
NET_NAME
'TP_CHA_CPU0_DIMM1_FRU_0'
 '@S9S_MB_2U_LIB.S9S_MB_2U(SCH_1):TP_CHA_CPU0_DIMM1_FRU_0':
 C_SIGNAL='@s9s_mb_2u_lib.s9s_mb_2u(sch_1):tp_cha_cpu0_dimm1_fru_0';
NODE_NAME     J1 2
 '@S9S_MB_2U_LIB.S9S_MB_2U(SCH_1):PAGE82_I198@PURE_QUANTA.SCONN288_ADR50017P130CC(CHIPS)':
 'RFU0': CDS_PINID='RFU0';
NET_NAME
'TP_CHA_CPU0_DIMM1_FRU_1'
 '@S9S_MB_2U_LIB.S9S_MB_2U(SCH_1):TP_CHA_CPU0_DIMM1_FRU_1':
 C_SIGNAL='@s9s_mb_2u_lib.s9s_mb_2u(sch_1):tp_cha_cpu0_dimm1_fru_1';
NODE_NAME     J1 144
 '@S9S_MB_2U_LIB.S9S_MB_2U(SCH_1):PAGE82_I198@PURE_QUANTA.SCONN288_ADR50017P130CC(CHIPS)':
 'RFU1': CDS_PINID='RFU1';
NET_NAME
'TP_CHA_CPU0_DIMM1_FRU_2'
 '@S9S_MB_2U_LIB.S9S_MB_2U(SCH_1):TP_CHA_CPU0_DIMM1_FRU_2':
 C_SIGNAL='@s9s_mb_2u_lib.s9s_mb_2u(sch_1):tp_cha_cpu0_dimm1_fru_2';
NODE_NAME     J1 149
 '@S9S_MB_2U_LIB.S9S_MB_2U(SCH_1):PAGE82_I198@PURE_QUANTA.SCONN288_ADR50017P130CC(CHIPS)':
 'RFU2': CDS_PINID='RFU2';
NET_NAME
'TP_CHA_CPU0_DIMM1_FRU_3'
 '@S9S_MB_2U_LIB.S9S_MB_2U(SCH_1):TP_CHA_CPU0_DIMM1_FRU_3':
 C_SIGNAL='@s9s_mb_2u_lib.s9s_mb_2u(sch_1):tp_cha_cpu0_dimm1_fru_3';
NODE_NAME     J1 150
 '@S9S_MB_2U_LIB.S9S_MB_2U(SCH_1):PAGE82_I198@PURE_QUANTA.SCONN288_ADR50017P130CC(CHIPS)':
 'RFU3': CDS_PINID='RFU3';
NET_NAME
'TP_CHA_CPU0_DIMM1_FRU_4'
 '@S9S_MB_2U_LIB.S9S_MB_2U(SCH_1):TP_CHA_CPU0_DIMM1_FRU_4':
 C_SIGNAL='@s9s_mb_2u_lib.s9s_mb_2u(sch_1):tp_cha_cpu0_dimm1_fru_4';
NODE_NAME     J1 220
 '@S9S_MB_2U_LIB.S9S_MB_2U(SCH_1):PAGE82_I198@PURE_QUANTA.SCONN288_ADR50017P130CC(CHIPS)':
 'RFU4': CDS_PINID='RFU4';
NET_NAME
'TP_CHA_CPU0_DIMM1_FRU_5'
 '@S9S_MB_2U_LIB.S9S_MB_2U(SCH_1):TP_CHA_CPU0_DIMM1_FRU_5':
 C_SIGNAL='@s9s_mb_2u_lib.s9s_mb_2u(sch_1):tp_cha_cpu0_dimm1_fru_5';
NODE_NAME     J1 231
 '@S9S_MB_2U_LIB.S9S_MB_2U(SCH_1):PAGE82_I198@PURE_QUANTA.SCONN288_ADR50017P130CC(CHIPS)':
 'RFU5': CDS_PINID='RFU5';
NET_NAME
'TP_CHA_CPU0_DIMM1_FRU_6'
 '@S9S_MB_2U_LIB.S9S_MB_2U(SCH_1):TP_CHA_CPU0_DIMM1_FRU_6':
 C_SIGNAL='@s9s_mb_2u_lib.s9s_mb_2u(sch_1):tp_cha_cpu0_dimm1_fru_6';
NODE_NAME     J1 232
 '@S9S_MB_2U_LIB.S9S_MB_2U(SCH_1):PAGE82_I198@PURE_QUANTA.SCONN288_ADR50017P130CC(CHIPS)':
 'RFU6': CDS_PINID='RFU6';
NET_NAME
'TP_CHA_CPU0_DIMM2_FRU_0'
 '@S9S_MB_2U_LIB.S9S_MB_2U(SCH_1):TP_CHA_CPU0_DIMM2_FRU_0':
 C_SIGNAL='@s9s_mb_2u_lib.s9s_mb_2u(sch_1):tp_cha_cpu0_dimm2_fru_0';
NODE_NAME     J2 2
 '@S9S_MB_2U_LIB.S9S_MB_2U(SCH_1):PAGE83_I177@PURE_QUANTA.SCONN288_ADR50017P087CC(CHIPS)':
 'RFU0': CDS_PINID='RFU0';
NET_NAME
'TP_CHA_CPU0_DIMM2_FRU_1'
 '@S9S_MB_2U_LIB.S9S_MB_2U(SCH_1):TP_CHA_CPU0_DIMM2_FRU_1':
 C_SIGNAL='@s9s_mb_2u_lib.s9s_mb_2u(sch_1):tp_cha_cpu0_dimm2_fru_1';
NODE_NAME     J2 144
 '@S9S_MB_2U_LIB.S9S_MB_2U(SCH_1):PAGE83_I177@PURE_QUANTA.SCONN288_ADR50017P087CC(CHIPS)':
 'RFU1': CDS_PINID='RFU1';
NET_NAME
'TP_CHA_CPU0_DIMM2_FRU_2'
 '@S9S_MB_2U_LIB.S9S_MB_2U(SCH_1):TP_CHA_CPU0_DIMM2_FRU_2':
 C_SIGNAL='@s9s_mb_2u_lib.s9s_mb_2u(sch_1):tp_cha_cpu0_dimm2_fru_2';
NODE_NAME     J2 149
 '@S9S_MB_2U_LIB.S9S_MB_2U(SCH_1):PAGE83_I177@PURE_QUANTA.SCONN288_ADR50017P087CC(CHIPS)':
 'RFU2': CDS_PINID='RFU2';
NET_NAME
'TP_CHA_CPU0_DIMM2_FRU_3'
 '@S9S_MB_2U_LIB.S9S_MB_2U(SCH_1):TP_CHA_CPU0_DIMM2_FRU_3':
 C_SIGNAL='@s9s_mb_2u_lib.s9s_mb_2u(sch_1):tp_cha_cpu0_dimm2_fru_3';
NODE_NAME     J2 150
 '@S9S_MB_2U_LIB.S9S_MB_2U(SCH_1):PAGE83_I177@PURE_QUANTA.SCONN288_ADR50017P087CC(CHIPS)':
 'RFU3': CDS_PINID='RFU3';
NET_NAME
'TP_CHA_CPU0_DIMM2_FRU_4'
 '@S9S_MB_2U_LIB.S9S_MB_2U(SCH_1):TP_CHA_CPU0_DIMM2_FRU_4':
 C_SIGNAL='@s9s_mb_2u_lib.s9s_mb_2u(sch_1):tp_cha_cpu0_dimm2_fru_4';
NODE_NAME     J2 220
 '@S9S_MB_2U_LIB.S9S_MB_2U(SCH_1):PAGE83_I177@PURE_QUANTA.SCONN288_ADR50017P087CC(CHIPS)':
 'RFU4': CDS_PINID='RFU4';
NET_NAME
'TP_CHA_CPU0_DIMM2_FRU_5'
 '@S9S_MB_2U_LIB.S9S_MB_2U(SCH_1):TP_CHA_CPU0_DIMM2_FRU_5':
 C_SIGNAL='@s9s_mb_2u_lib.s9s_mb_2u(sch_1):tp_cha_cpu0_dimm2_fru_5';
NODE_NAME     J2 231
 '@S9S_MB_2U_LIB.S9S_MB_2U(SCH_1):PAGE83_I177@PURE_QUANTA.SCONN288_ADR50017P087CC(CHIPS)':
 'RFU5': CDS_PINID='RFU5';
NET_NAME
'TP_CHA_CPU0_DIMM2_FRU_6'
 '@S9S_MB_2U_LIB.S9S_MB_2U(SCH_1):TP_CHA_CPU0_DIMM2_FRU_6':
 C_SIGNAL='@s9s_mb_2u_lib.s9s_mb_2u(sch_1):tp_cha_cpu0_dimm2_fru_6';
NODE_NAME     J2 232
 '@S9S_MB_2U_LIB.S9S_MB_2U(SCH_1):PAGE83_I177@PURE_QUANTA.SCONN288_ADR50017P087CC(CHIPS)':
 'RFU6': CDS_PINID='RFU6';
NET_NAME
'TP_CHA_CPU1_DIMM1_FRU_0'
 '@S9S_MB_2U_LIB.S9S_MB_2U(SCH_1):TP_CHA_CPU1_DIMM1_FRU_0':
 C_SIGNAL='@s9s_mb_2u_lib.s9s_mb_2u(sch_1):tp_cha_cpu1_dimm1_fru_0';
NODE_NAME     J17 2
 '@S9S_MB_2U_LIB.S9S_MB_2U(SCH_1):PAGE98_I12@PURE_QUANTA.SCONN288_ADR50017P130CC(CHIPS)':
 'RFU0': CDS_PINID='RFU0';
NET_NAME
'TP_CHA_CPU1_DIMM1_FRU_1'
 '@S9S_MB_2U_LIB.S9S_MB_2U(SCH_1):TP_CHA_CPU1_DIMM1_FRU_1':
 C_SIGNAL='@s9s_mb_2u_lib.s9s_mb_2u(sch_1):tp_cha_cpu1_dimm1_fru_1';
NODE_NAME     J17 144
 '@S9S_MB_2U_LIB.S9S_MB_2U(SCH_1):PAGE98_I12@PURE_QUANTA.SCONN288_ADR50017P130CC(CHIPS)':
 'RFU1': CDS_PINID='RFU1';
NET_NAME
'TP_CHA_CPU1_DIMM1_FRU_2'
 '@S9S_MB_2U_LIB.S9S_MB_2U(SCH_1):TP_CHA_CPU1_DIMM1_FRU_2':
 C_SIGNAL='@s9s_mb_2u_lib.s9s_mb_2u(sch_1):tp_cha_cpu1_dimm1_fru_2';
NODE_NAME     J17 149
 '@S9S_MB_2U_LIB.S9S_MB_2U(SCH_1):PAGE98_I12@PURE_QUANTA.SCONN288_ADR50017P130CC(CHIPS)':
 'RFU2': CDS_PINID='RFU2';
NET_NAME
'TP_CHA_CPU1_DIMM1_FRU_3'
 '@S9S_MB_2U_LIB.S9S_MB_2U(SCH_1):TP_CHA_CPU1_DIMM1_FRU_3':
 C_SIGNAL='@s9s_mb_2u_lib.s9s_mb_2u(sch_1):tp_cha_cpu1_dimm1_fru_3';
NODE_NAME     J17 150
 '@S9S_MB_2U_LIB.S9S_MB_2U(SCH_1):PAGE98_I12@PURE_QUANTA.SCONN288_ADR50017P130CC(CHIPS)':
 'RFU3': CDS_PINID='RFU3';
NET_NAME
'TP_CHA_CPU1_DIMM1_FRU_4'
 '@S9S_MB_2U_LIB.S9S_MB_2U(SCH_1):TP_CHA_CPU1_DIMM1_FRU_4':
 C_SIGNAL='@s9s_mb_2u_lib.s9s_mb_2u(sch_1):tp_cha_cpu1_dimm1_fru_4';
NODE_NAME     J17 220
 '@S9S_MB_2U_LIB.S9S_MB_2U(SCH_1):PAGE98_I12@PURE_QUANTA.SCONN288_ADR50017P130CC(CHIPS)':
 'RFU4': CDS_PINID='RFU4';
NET_NAME
'TP_CHA_CPU1_DIMM1_FRU_5'
 '@S9S_MB_2U_LIB.S9S_MB_2U(SCH_1):TP_CHA_CPU1_DIMM1_FRU_5':
 C_SIGNAL='@s9s_mb_2u_lib.s9s_mb_2u(sch_1):tp_cha_cpu1_dimm1_fru_5';
NODE_NAME     J17 231
 '@S9S_MB_2U_LIB.S9S_MB_2U(SCH_1):PAGE98_I12@PURE_QUANTA.SCONN288_ADR50017P130CC(CHIPS)':
 'RFU5': CDS_PINID='RFU5';
NET_NAME
'TP_CHA_CPU1_DIMM1_FRU_6'
 '@S9S_MB_2U_LIB.S9S_MB_2U(SCH_1):TP_CHA_CPU1_DIMM1_FRU_6':
 C_SIGNAL='@s9s_mb_2u_lib.s9s_mb_2u(sch_1):tp_cha_cpu1_dimm1_fru_6';
NODE_NAME     J17 232
 '@S9S_MB_2U_LIB.S9S_MB_2U(SCH_1):PAGE98_I12@PURE_QUANTA.SCONN288_ADR50017P130CC(CHIPS)':
 'RFU6': CDS_PINID='RFU6';
NET_NAME
'TP_CHA_CPU1_DIMM2_FRU_0'
 '@S9S_MB_2U_LIB.S9S_MB_2U(SCH_1):TP_CHA_CPU1_DIMM2_FRU_0':
 C_SIGNAL='@s9s_mb_2u_lib.s9s_mb_2u(sch_1):tp_cha_cpu1_dimm2_fru_0';
NODE_NAME     J18 2
 '@S9S_MB_2U_LIB.S9S_MB_2U(SCH_1):PAGE99_I24@PURE_QUANTA.SCONN288_ADR50017P087CC(CHIPS)':
 'RFU0': CDS_PINID='RFU0';
NET_NAME
'TP_CHA_CPU1_DIMM2_FRU_1'
 '@S9S_MB_2U_LIB.S9S_MB_2U(SCH_1):TP_CHA_CPU1_DIMM2_FRU_1':
 C_SIGNAL='@s9s_mb_2u_lib.s9s_mb_2u(sch_1):tp_cha_cpu1_dimm2_fru_1';
NODE_NAME     J18 144
 '@S9S_MB_2U_LIB.S9S_MB_2U(SCH_1):PAGE99_I24@PURE_QUANTA.SCONN288_ADR50017P087CC(CHIPS)':
 'RFU1': CDS_PINID='RFU1';
NET_NAME
'TP_CHA_CPU1_DIMM2_FRU_2'
 '@S9S_MB_2U_LIB.S9S_MB_2U(SCH_1):TP_CHA_CPU1_DIMM2_FRU_2':
 C_SIGNAL='@s9s_mb_2u_lib.s9s_mb_2u(sch_1):tp_cha_cpu1_dimm2_fru_2';
NODE_NAME     J18 149
 '@S9S_MB_2U_LIB.S9S_MB_2U(SCH_1):PAGE99_I24@PURE_QUANTA.SCONN288_ADR50017P087CC(CHIPS)':
 'RFU2': CDS_PINID='RFU2';
NET_NAME
'TP_CHA_CPU1_DIMM2_FRU_3'
 '@S9S_MB_2U_LIB.S9S_MB_2U(SCH_1):TP_CHA_CPU1_DIMM2_FRU_3':
 C_SIGNAL='@s9s_mb_2u_lib.s9s_mb_2u(sch_1):tp_cha_cpu1_dimm2_fru_3';
NODE_NAME     J18 150
 '@S9S_MB_2U_LIB.S9S_MB_2U(SCH_1):PAGE99_I24@PURE_QUANTA.SCONN288_ADR50017P087CC(CHIPS)':
 'RFU3': CDS_PINID='RFU3';
NET_NAME
'TP_CHA_CPU1_DIMM2_FRU_4'
 '@S9S_MB_2U_LIB.S9S_MB_2U(SCH_1):TP_CHA_CPU1_DIMM2_FRU_4':
 C_SIGNAL='@s9s_mb_2u_lib.s9s_mb_2u(sch_1):tp_cha_cpu1_dimm2_fru_4';
NODE_NAME     J18 220
 '@S9S_MB_2U_LIB.S9S_MB_2U(SCH_1):PAGE99_I24@PURE_QUANTA.SCONN288_ADR50017P087CC(CHIPS)':
 'RFU4': CDS_PINID='RFU4';
NET_NAME
'TP_CHA_CPU1_DIMM2_FRU_5'
 '@S9S_MB_2U_LIB.S9S_MB_2U(SCH_1):TP_CHA_CPU1_DIMM2_FRU_5':
 C_SIGNAL='@s9s_mb_2u_lib.s9s_mb_2u(sch_1):tp_cha_cpu1_dimm2_fru_5';
NODE_NAME     J18 231
 '@S9S_MB_2U_LIB.S9S_MB_2U(SCH_1):PAGE99_I24@PURE_QUANTA.SCONN288_ADR50017P087CC(CHIPS)':
 'RFU5': CDS_PINID='RFU5';
NET_NAME
'TP_CHA_CPU1_DIMM2_FRU_6'
 '@S9S_MB_2U_LIB.S9S_MB_2U(SCH_1):TP_CHA_CPU1_DIMM2_FRU_6':
 C_SIGNAL='@s9s_mb_2u_lib.s9s_mb_2u(sch_1):tp_cha_cpu1_dimm2_fru_6';
NODE_NAME     J18 232
 '@S9S_MB_2U_LIB.S9S_MB_2U(SCH_1):PAGE99_I24@PURE_QUANTA.SCONN288_ADR50017P087CC(CHIPS)':
 'RFU6': CDS_PINID='RFU6';
NET_NAME
'TP_CHB_CPU0_DIMM1_FRU_0'
 '@S9S_MB_2U_LIB.S9S_MB_2U(SCH_1):TP_CHB_CPU0_DIMM1_FRU_0':
 C_SIGNAL='@s9s_mb_2u_lib.s9s_mb_2u(sch_1):tp_chb_cpu0_dimm1_fru_0';
NODE_NAME     J3 2
 '@S9S_MB_2U_LIB.S9S_MB_2U(SCH_1):PAGE84_I180@PURE_QUANTA.SCONN288_ADR50017P130CC(CHIPS)':
 'RFU0': CDS_PINID='RFU0';
NET_NAME
'TP_CHB_CPU0_DIMM1_FRU_1'
 '@S9S_MB_2U_LIB.S9S_MB_2U(SCH_1):TP_CHB_CPU0_DIMM1_FRU_1':
 C_SIGNAL='@s9s_mb_2u_lib.s9s_mb_2u(sch_1):tp_chb_cpu0_dimm1_fru_1';
NODE_NAME     J3 144
 '@S9S_MB_2U_LIB.S9S_MB_2U(SCH_1):PAGE84_I180@PURE_QUANTA.SCONN288_ADR50017P130CC(CHIPS)':
 'RFU1': CDS_PINID='RFU1';
NET_NAME
'TP_CHB_CPU0_DIMM1_FRU_2'
 '@S9S_MB_2U_LIB.S9S_MB_2U(SCH_1):TP_CHB_CPU0_DIMM1_FRU_2':
 C_SIGNAL='@s9s_mb_2u_lib.s9s_mb_2u(sch_1):tp_chb_cpu0_dimm1_fru_2';
NODE_NAME     J3 149
 '@S9S_MB_2U_LIB.S9S_MB_2U(SCH_1):PAGE84_I180@PURE_QUANTA.SCONN288_ADR50017P130CC(CHIPS)':
 'RFU2': CDS_PINID='RFU2';
NET_NAME
'TP_CHB_CPU0_DIMM1_FRU_3'
 '@S9S_MB_2U_LIB.S9S_MB_2U(SCH_1):TP_CHB_CPU0_DIMM1_FRU_3':
 C_SIGNAL='@s9s_mb_2u_lib.s9s_mb_2u(sch_1):tp_chb_cpu0_dimm1_fru_3';
NODE_NAME     J3 150
 '@S9S_MB_2U_LIB.S9S_MB_2U(SCH_1):PAGE84_I180@PURE_QUANTA.SCONN288_ADR50017P130CC(CHIPS)':
 'RFU3': CDS_PINID='RFU3';
NET_NAME
'TP_CHB_CPU0_DIMM1_FRU_4'
 '@S9S_MB_2U_LIB.S9S_MB_2U(SCH_1):TP_CHB_CPU0_DIMM1_FRU_4':
 C_SIGNAL='@s9s_mb_2u_lib.s9s_mb_2u(sch_1):tp_chb_cpu0_dimm1_fru_4';
NODE_NAME     J3 220
 '@S9S_MB_2U_LIB.S9S_MB_2U(SCH_1):PAGE84_I180@PURE_QUANTA.SCONN288_ADR50017P130CC(CHIPS)':
 'RFU4': CDS_PINID='RFU4';
NET_NAME
'TP_CHB_CPU0_DIMM1_FRU_5'
 '@S9S_MB_2U_LIB.S9S_MB_2U(SCH_1):TP_CHB_CPU0_DIMM1_FRU_5':
 C_SIGNAL='@s9s_mb_2u_lib.s9s_mb_2u(sch_1):tp_chb_cpu0_dimm1_fru_5';
NODE_NAME     J3 231
 '@S9S_MB_2U_LIB.S9S_MB_2U(SCH_1):PAGE84_I180@PURE_QUANTA.SCONN288_ADR50017P130CC(CHIPS)':
 'RFU5': CDS_PINID='RFU5';
NET_NAME
'TP_CHB_CPU0_DIMM1_FRU_6'
 '@S9S_MB_2U_LIB.S9S_MB_2U(SCH_1):TP_CHB_CPU0_DIMM1_FRU_6':
 C_SIGNAL='@s9s_mb_2u_lib.s9s_mb_2u(sch_1):tp_chb_cpu0_dimm1_fru_6';
NODE_NAME     J3 232
 '@S9S_MB_2U_LIB.S9S_MB_2U(SCH_1):PAGE84_I180@PURE_QUANTA.SCONN288_ADR50017P130CC(CHIPS)':
 'RFU6': CDS_PINID='RFU6';
NET_NAME
'TP_CHB_CPU0_DIMM2_FRU_0'
 '@S9S_MB_2U_LIB.S9S_MB_2U(SCH_1):TP_CHB_CPU0_DIMM2_FRU_0':
 C_SIGNAL='@s9s_mb_2u_lib.s9s_mb_2u(sch_1):tp_chb_cpu0_dimm2_fru_0';
NODE_NAME     J4 2
 '@S9S_MB_2U_LIB.S9S_MB_2U(SCH_1):PAGE85_I23@PURE_QUANTA.SCONN288_ADR50017P087CC(CHIPS)':
 'RFU0': CDS_PINID='RFU0';
NET_NAME
'TP_CHB_CPU0_DIMM2_FRU_1'
 '@S9S_MB_2U_LIB.S9S_MB_2U(SCH_1):TP_CHB_CPU0_DIMM2_FRU_1':
 C_SIGNAL='@s9s_mb_2u_lib.s9s_mb_2u(sch_1):tp_chb_cpu0_dimm2_fru_1';
NODE_NAME     J4 144
 '@S9S_MB_2U_LIB.S9S_MB_2U(SCH_1):PAGE85_I23@PURE_QUANTA.SCONN288_ADR50017P087CC(CHIPS)':
 'RFU1': CDS_PINID='RFU1';
NET_NAME
'TP_CHB_CPU0_DIMM2_FRU_2'
 '@S9S_MB_2U_LIB.S9S_MB_2U(SCH_1):TP_CHB_CPU0_DIMM2_FRU_2':
 C_SIGNAL='@s9s_mb_2u_lib.s9s_mb_2u(sch_1):tp_chb_cpu0_dimm2_fru_2';
NODE_NAME     J4 149
 '@S9S_MB_2U_LIB.S9S_MB_2U(SCH_1):PAGE85_I23@PURE_QUANTA.SCONN288_ADR50017P087CC(CHIPS)':
 'RFU2': CDS_PINID='RFU2';
NET_NAME
'TP_CHB_CPU0_DIMM2_FRU_3'
 '@S9S_MB_2U_LIB.S9S_MB_2U(SCH_1):TP_CHB_CPU0_DIMM2_FRU_3':
 C_SIGNAL='@s9s_mb_2u_lib.s9s_mb_2u(sch_1):tp_chb_cpu0_dimm2_fru_3';
NODE_NAME     J4 150
 '@S9S_MB_2U_LIB.S9S_MB_2U(SCH_1):PAGE85_I23@PURE_QUANTA.SCONN288_ADR50017P087CC(CHIPS)':
 'RFU3': CDS_PINID='RFU3';
NET_NAME
'TP_CHB_CPU0_DIMM2_FRU_4'
 '@S9S_MB_2U_LIB.S9S_MB_2U(SCH_1):TP_CHB_CPU0_DIMM2_FRU_4':
 C_SIGNAL='@s9s_mb_2u_lib.s9s_mb_2u(sch_1):tp_chb_cpu0_dimm2_fru_4';
NODE_NAME     J4 220
 '@S9S_MB_2U_LIB.S9S_MB_2U(SCH_1):PAGE85_I23@PURE_QUANTA.SCONN288_ADR50017P087CC(CHIPS)':
 'RFU4': CDS_PINID='RFU4';
NET_NAME
'TP_CHB_CPU0_DIMM2_FRU_5'
 '@S9S_MB_2U_LIB.S9S_MB_2U(SCH_1):TP_CHB_CPU0_DIMM2_FRU_5':
 C_SIGNAL='@s9s_mb_2u_lib.s9s_mb_2u(sch_1):tp_chb_cpu0_dimm2_fru_5';
NODE_NAME     J4 231
 '@S9S_MB_2U_LIB.S9S_MB_2U(SCH_1):PAGE85_I23@PURE_QUANTA.SCONN288_ADR50017P087CC(CHIPS)':
 'RFU5': CDS_PINID='RFU5';
NET_NAME
'TP_CHB_CPU0_DIMM2_FRU_6'
 '@S9S_MB_2U_LIB.S9S_MB_2U(SCH_1):TP_CHB_CPU0_DIMM2_FRU_6':
 C_SIGNAL='@s9s_mb_2u_lib.s9s_mb_2u(sch_1):tp_chb_cpu0_dimm2_fru_6';
NODE_NAME     J4 232
 '@S9S_MB_2U_LIB.S9S_MB_2U(SCH_1):PAGE85_I23@PURE_QUANTA.SCONN288_ADR50017P087CC(CHIPS)':
 'RFU6': CDS_PINID='RFU6';
NET_NAME
'TP_CHB_CPU1_DIMM1_FRU_0'
 '@S9S_MB_2U_LIB.S9S_MB_2U(SCH_1):TP_CHB_CPU1_DIMM1_FRU_0':
 C_SIGNAL='@s9s_mb_2u_lib.s9s_mb_2u(sch_1):tp_chb_cpu1_dimm1_fru_0';
NODE_NAME     J19 2
 '@S9S_MB_2U_LIB.S9S_MB_2U(SCH_1):PAGE100_I25@PURE_QUANTA.SCONN288_ADR50017P130CC(CHIPS)':
 'RFU0': CDS_PINID='RFU0';
NET_NAME
'TP_CHB_CPU1_DIMM1_FRU_1'
 '@S9S_MB_2U_LIB.S9S_MB_2U(SCH_1):TP_CHB_CPU1_DIMM1_FRU_1':
 C_SIGNAL='@s9s_mb_2u_lib.s9s_mb_2u(sch_1):tp_chb_cpu1_dimm1_fru_1';
NODE_NAME     J19 144
 '@S9S_MB_2U_LIB.S9S_MB_2U(SCH_1):PAGE100_I25@PURE_QUANTA.SCONN288_ADR50017P130CC(CHIPS)':
 'RFU1': CDS_PINID='RFU1';
NET_NAME
'TP_CHB_CPU1_DIMM1_FRU_2'
 '@S9S_MB_2U_LIB.S9S_MB_2U(SCH_1):TP_CHB_CPU1_DIMM1_FRU_2':
 C_SIGNAL='@s9s_mb_2u_lib.s9s_mb_2u(sch_1):tp_chb_cpu1_dimm1_fru_2';
NODE_NAME     J19 149
 '@S9S_MB_2U_LIB.S9S_MB_2U(SCH_1):PAGE100_I25@PURE_QUANTA.SCONN288_ADR50017P130CC(CHIPS)':
 'RFU2': CDS_PINID='RFU2';
NET_NAME
'TP_CHB_CPU1_DIMM1_FRU_3'
 '@S9S_MB_2U_LIB.S9S_MB_2U(SCH_1):TP_CHB_CPU1_DIMM1_FRU_3':
 C_SIGNAL='@s9s_mb_2u_lib.s9s_mb_2u(sch_1):tp_chb_cpu1_dimm1_fru_3';
NODE_NAME     J19 150
 '@S9S_MB_2U_LIB.S9S_MB_2U(SCH_1):PAGE100_I25@PURE_QUANTA.SCONN288_ADR50017P130CC(CHIPS)':
 'RFU3': CDS_PINID='RFU3';
NET_NAME
'TP_CHB_CPU1_DIMM1_FRU_4'
 '@S9S_MB_2U_LIB.S9S_MB_2U(SCH_1):TP_CHB_CPU1_DIMM1_FRU_4':
 C_SIGNAL='@s9s_mb_2u_lib.s9s_mb_2u(sch_1):tp_chb_cpu1_dimm1_fru_4';
NODE_NAME     J19 220
 '@S9S_MB_2U_LIB.S9S_MB_2U(SCH_1):PAGE100_I25@PURE_QUANTA.SCONN288_ADR50017P130CC(CHIPS)':
 'RFU4': CDS_PINID='RFU4';
NET_NAME
'TP_CHB_CPU1_DIMM1_FRU_5'
 '@S9S_MB_2U_LIB.S9S_MB_2U(SCH_1):TP_CHB_CPU1_DIMM1_FRU_5':
 C_SIGNAL='@s9s_mb_2u_lib.s9s_mb_2u(sch_1):tp_chb_cpu1_dimm1_fru_5';
NODE_NAME     J19 231
 '@S9S_MB_2U_LIB.S9S_MB_2U(SCH_1):PAGE100_I25@PURE_QUANTA.SCONN288_ADR50017P130CC(CHIPS)':
 'RFU5': CDS_PINID='RFU5';
NET_NAME
'TP_CHB_CPU1_DIMM1_FRU_6'
 '@S9S_MB_2U_LIB.S9S_MB_2U(SCH_1):TP_CHB_CPU1_DIMM1_FRU_6':
 C_SIGNAL='@s9s_mb_2u_lib.s9s_mb_2u(sch_1):tp_chb_cpu1_dimm1_fru_6';
NODE_NAME     J19 232
 '@S9S_MB_2U_LIB.S9S_MB_2U(SCH_1):PAGE100_I25@PURE_QUANTA.SCONN288_ADR50017P130CC(CHIPS)':
 'RFU6': CDS_PINID='RFU6';
NET_NAME
'TP_CHB_CPU1_DIMM2_FRU_0'
 '@S9S_MB_2U_LIB.S9S_MB_2U(SCH_1):TP_CHB_CPU1_DIMM2_FRU_0':
 C_SIGNAL='@s9s_mb_2u_lib.s9s_mb_2u(sch_1):tp_chb_cpu1_dimm2_fru_0';
NODE_NAME     J20 2
 '@S9S_MB_2U_LIB.S9S_MB_2U(SCH_1):PAGE101_I47@PURE_QUANTA.SCONN288_ADR50017P087CC(CHIPS)':
 'RFU0': CDS_PINID='RFU0';
NET_NAME
'TP_CHB_CPU1_DIMM2_FRU_1'
 '@S9S_MB_2U_LIB.S9S_MB_2U(SCH_1):TP_CHB_CPU1_DIMM2_FRU_1':
 C_SIGNAL='@s9s_mb_2u_lib.s9s_mb_2u(sch_1):tp_chb_cpu1_dimm2_fru_1';
NODE_NAME     J20 144
 '@S9S_MB_2U_LIB.S9S_MB_2U(SCH_1):PAGE101_I47@PURE_QUANTA.SCONN288_ADR50017P087CC(CHIPS)':
 'RFU1': CDS_PINID='RFU1';
NET_NAME
'TP_CHB_CPU1_DIMM2_FRU_2'
 '@S9S_MB_2U_LIB.S9S_MB_2U(SCH_1):TP_CHB_CPU1_DIMM2_FRU_2':
 C_SIGNAL='@s9s_mb_2u_lib.s9s_mb_2u(sch_1):tp_chb_cpu1_dimm2_fru_2';
NODE_NAME     J20 149
 '@S9S_MB_2U_LIB.S9S_MB_2U(SCH_1):PAGE101_I47@PURE_QUANTA.SCONN288_ADR50017P087CC(CHIPS)':
 'RFU2': CDS_PINID='RFU2';
NET_NAME
'TP_CHB_CPU1_DIMM2_FRU_3'
 '@S9S_MB_2U_LIB.S9S_MB_2U(SCH_1):TP_CHB_CPU1_DIMM2_FRU_3':
 C_SIGNAL='@s9s_mb_2u_lib.s9s_mb_2u(sch_1):tp_chb_cpu1_dimm2_fru_3';
NODE_NAME     J20 150
 '@S9S_MB_2U_LIB.S9S_MB_2U(SCH_1):PAGE101_I47@PURE_QUANTA.SCONN288_ADR50017P087CC(CHIPS)':
 'RFU3': CDS_PINID='RFU3';
NET_NAME
'TP_CHB_CPU1_DIMM2_FRU_4'
 '@S9S_MB_2U_LIB.S9S_MB_2U(SCH_1):TP_CHB_CPU1_DIMM2_FRU_4':
 C_SIGNAL='@s9s_mb_2u_lib.s9s_mb_2u(sch_1):tp_chb_cpu1_dimm2_fru_4';
NODE_NAME     J20 220
 '@S9S_MB_2U_LIB.S9S_MB_2U(SCH_1):PAGE101_I47@PURE_QUANTA.SCONN288_ADR50017P087CC(CHIPS)':
 'RFU4': CDS_PINID='RFU4';
NET_NAME
'TP_CHB_CPU1_DIMM2_FRU_5'
 '@S9S_MB_2U_LIB.S9S_MB_2U(SCH_1):TP_CHB_CPU1_DIMM2_FRU_5':
 C_SIGNAL='@s9s_mb_2u_lib.s9s_mb_2u(sch_1):tp_chb_cpu1_dimm2_fru_5';
NODE_NAME     J20 231
 '@S9S_MB_2U_LIB.S9S_MB_2U(SCH_1):PAGE101_I47@PURE_QUANTA.SCONN288_ADR50017P087CC(CHIPS)':
 'RFU5': CDS_PINID='RFU5';
NET_NAME
'TP_CHB_CPU1_DIMM2_FRU_6'
 '@S9S_MB_2U_LIB.S9S_MB_2U(SCH_1):TP_CHB_CPU1_DIMM2_FRU_6':
 C_SIGNAL='@s9s_mb_2u_lib.s9s_mb_2u(sch_1):tp_chb_cpu1_dimm2_fru_6';
NODE_NAME     J20 232
 '@S9S_MB_2U_LIB.S9S_MB_2U(SCH_1):PAGE101_I47@PURE_QUANTA.SCONN288_ADR50017P087CC(CHIPS)':
 'RFU6': CDS_PINID='RFU6';
NET_NAME
'TP_CHC_CPU0_DIMM1_FRU_0'
 '@S9S_MB_2U_LIB.S9S_MB_2U(SCH_1):TP_CHC_CPU0_DIMM1_FRU_0':
 C_SIGNAL='@s9s_mb_2u_lib.s9s_mb_2u(sch_1):tp_chc_cpu0_dimm1_fru_0';
NODE_NAME     J5 2
 '@S9S_MB_2U_LIB.S9S_MB_2U(SCH_1):PAGE86_I24@PURE_QUANTA.SCONN288_ADR50017P130CC(CHIPS)':
 'RFU0': CDS_PINID='RFU0';
NET_NAME
'TP_CHC_CPU0_DIMM1_FRU_1'
 '@S9S_MB_2U_LIB.S9S_MB_2U(SCH_1):TP_CHC_CPU0_DIMM1_FRU_1':
 C_SIGNAL='@s9s_mb_2u_lib.s9s_mb_2u(sch_1):tp_chc_cpu0_dimm1_fru_1';
NODE_NAME     J5 144
 '@S9S_MB_2U_LIB.S9S_MB_2U(SCH_1):PAGE86_I24@PURE_QUANTA.SCONN288_ADR50017P130CC(CHIPS)':
 'RFU1': CDS_PINID='RFU1';
NET_NAME
'TP_CHC_CPU0_DIMM1_FRU_2'
 '@S9S_MB_2U_LIB.S9S_MB_2U(SCH_1):TP_CHC_CPU0_DIMM1_FRU_2':
 C_SIGNAL='@s9s_mb_2u_lib.s9s_mb_2u(sch_1):tp_chc_cpu0_dimm1_fru_2';
NODE_NAME     J5 149
 '@S9S_MB_2U_LIB.S9S_MB_2U(SCH_1):PAGE86_I24@PURE_QUANTA.SCONN288_ADR50017P130CC(CHIPS)':
 'RFU2': CDS_PINID='RFU2';
NET_NAME
'TP_CHC_CPU0_DIMM1_FRU_3'
 '@S9S_MB_2U_LIB.S9S_MB_2U(SCH_1):TP_CHC_CPU0_DIMM1_FRU_3':
 C_SIGNAL='@s9s_mb_2u_lib.s9s_mb_2u(sch_1):tp_chc_cpu0_dimm1_fru_3';
NODE_NAME     J5 150
 '@S9S_MB_2U_LIB.S9S_MB_2U(SCH_1):PAGE86_I24@PURE_QUANTA.SCONN288_ADR50017P130CC(CHIPS)':
 'RFU3': CDS_PINID='RFU3';
NET_NAME
'TP_CHC_CPU0_DIMM1_FRU_4'
 '@S9S_MB_2U_LIB.S9S_MB_2U(SCH_1):TP_CHC_CPU0_DIMM1_FRU_4':
 C_SIGNAL='@s9s_mb_2u_lib.s9s_mb_2u(sch_1):tp_chc_cpu0_dimm1_fru_4';
NODE_NAME     J5 220
 '@S9S_MB_2U_LIB.S9S_MB_2U(SCH_1):PAGE86_I24@PURE_QUANTA.SCONN288_ADR50017P130CC(CHIPS)':
 'RFU4': CDS_PINID='RFU4';
NET_NAME
'TP_CHC_CPU0_DIMM1_FRU_5'
 '@S9S_MB_2U_LIB.S9S_MB_2U(SCH_1):TP_CHC_CPU0_DIMM1_FRU_5':
 C_SIGNAL='@s9s_mb_2u_lib.s9s_mb_2u(sch_1):tp_chc_cpu0_dimm1_fru_5';
NODE_NAME     J5 231
 '@S9S_MB_2U_LIB.S9S_MB_2U(SCH_1):PAGE86_I24@PURE_QUANTA.SCONN288_ADR50017P130CC(CHIPS)':
 'RFU5': CDS_PINID='RFU5';
NET_NAME
'TP_CHC_CPU0_DIMM1_FRU_6'
 '@S9S_MB_2U_LIB.S9S_MB_2U(SCH_1):TP_CHC_CPU0_DIMM1_FRU_6':
 C_SIGNAL='@s9s_mb_2u_lib.s9s_mb_2u(sch_1):tp_chc_cpu0_dimm1_fru_6';
NODE_NAME     J5 232
 '@S9S_MB_2U_LIB.S9S_MB_2U(SCH_1):PAGE86_I24@PURE_QUANTA.SCONN288_ADR50017P130CC(CHIPS)':
 'RFU6': CDS_PINID='RFU6';
NET_NAME
'TP_CHC_CPU0_DIMM2_FRU_0'
 '@S9S_MB_2U_LIB.S9S_MB_2U(SCH_1):TP_CHC_CPU0_DIMM2_FRU_0':
 C_SIGNAL='@s9s_mb_2u_lib.s9s_mb_2u(sch_1):tp_chc_cpu0_dimm2_fru_0';
NODE_NAME     J6 2
 '@S9S_MB_2U_LIB.S9S_MB_2U(SCH_1):PAGE87_I46@PURE_QUANTA.SCONN288_ADR50017P087CC(CHIPS)':
 'RFU0': CDS_PINID='RFU0';
NET_NAME
'TP_CHC_CPU0_DIMM2_FRU_1'
 '@S9S_MB_2U_LIB.S9S_MB_2U(SCH_1):TP_CHC_CPU0_DIMM2_FRU_1':
 C_SIGNAL='@s9s_mb_2u_lib.s9s_mb_2u(sch_1):tp_chc_cpu0_dimm2_fru_1';
NODE_NAME     J6 144
 '@S9S_MB_2U_LIB.S9S_MB_2U(SCH_1):PAGE87_I46@PURE_QUANTA.SCONN288_ADR50017P087CC(CHIPS)':
 'RFU1': CDS_PINID='RFU1';
NET_NAME
'TP_CHC_CPU0_DIMM2_FRU_2'
 '@S9S_MB_2U_LIB.S9S_MB_2U(SCH_1):TP_CHC_CPU0_DIMM2_FRU_2':
 C_SIGNAL='@s9s_mb_2u_lib.s9s_mb_2u(sch_1):tp_chc_cpu0_dimm2_fru_2';
NODE_NAME     J6 149
 '@S9S_MB_2U_LIB.S9S_MB_2U(SCH_1):PAGE87_I46@PURE_QUANTA.SCONN288_ADR50017P087CC(CHIPS)':
 'RFU2': CDS_PINID='RFU2';
NET_NAME
'TP_CHC_CPU0_DIMM2_FRU_3'
 '@S9S_MB_2U_LIB.S9S_MB_2U(SCH_1):TP_CHC_CPU0_DIMM2_FRU_3':
 C_SIGNAL='@s9s_mb_2u_lib.s9s_mb_2u(sch_1):tp_chc_cpu0_dimm2_fru_3';
NODE_NAME     J6 150
 '@S9S_MB_2U_LIB.S9S_MB_2U(SCH_1):PAGE87_I46@PURE_QUANTA.SCONN288_ADR50017P087CC(CHIPS)':
 'RFU3': CDS_PINID='RFU3';
NET_NAME
'TP_CHC_CPU0_DIMM2_FRU_4'
 '@S9S_MB_2U_LIB.S9S_MB_2U(SCH_1):TP_CHC_CPU0_DIMM2_FRU_4':
 C_SIGNAL='@s9s_mb_2u_lib.s9s_mb_2u(sch_1):tp_chc_cpu0_dimm2_fru_4';
NODE_NAME     J6 220
 '@S9S_MB_2U_LIB.S9S_MB_2U(SCH_1):PAGE87_I46@PURE_QUANTA.SCONN288_ADR50017P087CC(CHIPS)':
 'RFU4': CDS_PINID='RFU4';
NET_NAME
'TP_CHC_CPU0_DIMM2_FRU_5'
 '@S9S_MB_2U_LIB.S9S_MB_2U(SCH_1):TP_CHC_CPU0_DIMM2_FRU_5':
 C_SIGNAL='@s9s_mb_2u_lib.s9s_mb_2u(sch_1):tp_chc_cpu0_dimm2_fru_5';
NODE_NAME     J6 231
 '@S9S_MB_2U_LIB.S9S_MB_2U(SCH_1):PAGE87_I46@PURE_QUANTA.SCONN288_ADR50017P087CC(CHIPS)':
 'RFU5': CDS_PINID='RFU5';
NET_NAME
'TP_CHC_CPU0_DIMM2_FRU_6'
 '@S9S_MB_2U_LIB.S9S_MB_2U(SCH_1):TP_CHC_CPU0_DIMM2_FRU_6':
 C_SIGNAL='@s9s_mb_2u_lib.s9s_mb_2u(sch_1):tp_chc_cpu0_dimm2_fru_6';
NODE_NAME     J6 232
 '@S9S_MB_2U_LIB.S9S_MB_2U(SCH_1):PAGE87_I46@PURE_QUANTA.SCONN288_ADR50017P087CC(CHIPS)':
 'RFU6': CDS_PINID='RFU6';
NET_NAME
'TP_CHC_CPU1_DIMM1_FRU_0'
 '@S9S_MB_2U_LIB.S9S_MB_2U(SCH_1):TP_CHC_CPU1_DIMM1_FRU_0':
 C_SIGNAL='@s9s_mb_2u_lib.s9s_mb_2u(sch_1):tp_chc_cpu1_dimm1_fru_0';
NODE_NAME     J21 2
 '@S9S_MB_2U_LIB.S9S_MB_2U(SCH_1):PAGE102_I13@PURE_QUANTA.SCONN288_ADR50017P130CC(CHIPS)':
 'RFU0': CDS_PINID='RFU0';
NET_NAME
'TP_CHC_CPU1_DIMM1_FRU_1'
 '@S9S_MB_2U_LIB.S9S_MB_2U(SCH_1):TP_CHC_CPU1_DIMM1_FRU_1':
 C_SIGNAL='@s9s_mb_2u_lib.s9s_mb_2u(sch_1):tp_chc_cpu1_dimm1_fru_1';
NODE_NAME     J21 144
 '@S9S_MB_2U_LIB.S9S_MB_2U(SCH_1):PAGE102_I13@PURE_QUANTA.SCONN288_ADR50017P130CC(CHIPS)':
 'RFU1': CDS_PINID='RFU1';
NET_NAME
'TP_CHC_CPU1_DIMM1_FRU_2'
 '@S9S_MB_2U_LIB.S9S_MB_2U(SCH_1):TP_CHC_CPU1_DIMM1_FRU_2':
 C_SIGNAL='@s9s_mb_2u_lib.s9s_mb_2u(sch_1):tp_chc_cpu1_dimm1_fru_2';
NODE_NAME     J21 149
 '@S9S_MB_2U_LIB.S9S_MB_2U(SCH_1):PAGE102_I13@PURE_QUANTA.SCONN288_ADR50017P130CC(CHIPS)':
 'RFU2': CDS_PINID='RFU2';
NET_NAME
'TP_CHC_CPU1_DIMM1_FRU_3'
 '@S9S_MB_2U_LIB.S9S_MB_2U(SCH_1):TP_CHC_CPU1_DIMM1_FRU_3':
 C_SIGNAL='@s9s_mb_2u_lib.s9s_mb_2u(sch_1):tp_chc_cpu1_dimm1_fru_3';
NODE_NAME     J21 150
 '@S9S_MB_2U_LIB.S9S_MB_2U(SCH_1):PAGE102_I13@PURE_QUANTA.SCONN288_ADR50017P130CC(CHIPS)':
 'RFU3': CDS_PINID='RFU3';
NET_NAME
'TP_CHC_CPU1_DIMM1_FRU_4'
 '@S9S_MB_2U_LIB.S9S_MB_2U(SCH_1):TP_CHC_CPU1_DIMM1_FRU_4':
 C_SIGNAL='@s9s_mb_2u_lib.s9s_mb_2u(sch_1):tp_chc_cpu1_dimm1_fru_4';
NODE_NAME     J21 220
 '@S9S_MB_2U_LIB.S9S_MB_2U(SCH_1):PAGE102_I13@PURE_QUANTA.SCONN288_ADR50017P130CC(CHIPS)':
 'RFU4': CDS_PINID='RFU4';
NET_NAME
'TP_CHC_CPU1_DIMM1_FRU_5'
 '@S9S_MB_2U_LIB.S9S_MB_2U(SCH_1):TP_CHC_CPU1_DIMM1_FRU_5':
 C_SIGNAL='@s9s_mb_2u_lib.s9s_mb_2u(sch_1):tp_chc_cpu1_dimm1_fru_5';
NODE_NAME     J21 231
 '@S9S_MB_2U_LIB.S9S_MB_2U(SCH_1):PAGE102_I13@PURE_QUANTA.SCONN288_ADR50017P130CC(CHIPS)':
 'RFU5': CDS_PINID='RFU5';
NET_NAME
'TP_CHC_CPU1_DIMM1_FRU_6'
 '@S9S_MB_2U_LIB.S9S_MB_2U(SCH_1):TP_CHC_CPU1_DIMM1_FRU_6':
 C_SIGNAL='@s9s_mb_2u_lib.s9s_mb_2u(sch_1):tp_chc_cpu1_dimm1_fru_6';
NODE_NAME     J21 232
 '@S9S_MB_2U_LIB.S9S_MB_2U(SCH_1):PAGE102_I13@PURE_QUANTA.SCONN288_ADR50017P130CC(CHIPS)':
 'RFU6': CDS_PINID='RFU6';
NET_NAME
'TP_CHC_CPU1_DIMM2_FRU_0'
 '@S9S_MB_2U_LIB.S9S_MB_2U(SCH_1):TP_CHC_CPU1_DIMM2_FRU_0':
 C_SIGNAL='@s9s_mb_2u_lib.s9s_mb_2u(sch_1):tp_chc_cpu1_dimm2_fru_0';
NODE_NAME     J22 2
 '@S9S_MB_2U_LIB.S9S_MB_2U(SCH_1):PAGE103_I51@PURE_QUANTA.SCONN288_ADR50017P087CC(CHIPS)':
 'RFU0': CDS_PINID='RFU0';
NET_NAME
'TP_CHC_CPU1_DIMM2_FRU_1'
 '@S9S_MB_2U_LIB.S9S_MB_2U(SCH_1):TP_CHC_CPU1_DIMM2_FRU_1':
 C_SIGNAL='@s9s_mb_2u_lib.s9s_mb_2u(sch_1):tp_chc_cpu1_dimm2_fru_1';
NODE_NAME     J22 144
 '@S9S_MB_2U_LIB.S9S_MB_2U(SCH_1):PAGE103_I51@PURE_QUANTA.SCONN288_ADR50017P087CC(CHIPS)':
 'RFU1': CDS_PINID='RFU1';
NET_NAME
'TP_CHC_CPU1_DIMM2_FRU_2'
 '@S9S_MB_2U_LIB.S9S_MB_2U(SCH_1):TP_CHC_CPU1_DIMM2_FRU_2':
 C_SIGNAL='@s9s_mb_2u_lib.s9s_mb_2u(sch_1):tp_chc_cpu1_dimm2_fru_2';
NODE_NAME     J22 149
 '@S9S_MB_2U_LIB.S9S_MB_2U(SCH_1):PAGE103_I51@PURE_QUANTA.SCONN288_ADR50017P087CC(CHIPS)':
 'RFU2': CDS_PINID='RFU2';
NET_NAME
'TP_CHC_CPU1_DIMM2_FRU_3'
 '@S9S_MB_2U_LIB.S9S_MB_2U(SCH_1):TP_CHC_CPU1_DIMM2_FRU_3':
 C_SIGNAL='@s9s_mb_2u_lib.s9s_mb_2u(sch_1):tp_chc_cpu1_dimm2_fru_3';
NODE_NAME     J22 150
 '@S9S_MB_2U_LIB.S9S_MB_2U(SCH_1):PAGE103_I51@PURE_QUANTA.SCONN288_ADR50017P087CC(CHIPS)':
 'RFU3': CDS_PINID='RFU3';
NET_NAME
'TP_CHC_CPU1_DIMM2_FRU_4'
 '@S9S_MB_2U_LIB.S9S_MB_2U(SCH_1):TP_CHC_CPU1_DIMM2_FRU_4':
 C_SIGNAL='@s9s_mb_2u_lib.s9s_mb_2u(sch_1):tp_chc_cpu1_dimm2_fru_4';
NODE_NAME     J22 220
 '@S9S_MB_2U_LIB.S9S_MB_2U(SCH_1):PAGE103_I51@PURE_QUANTA.SCONN288_ADR50017P087CC(CHIPS)':
 'RFU4': CDS_PINID='RFU4';
NET_NAME
'TP_CHC_CPU1_DIMM2_FRU_5'
 '@S9S_MB_2U_LIB.S9S_MB_2U(SCH_1):TP_CHC_CPU1_DIMM2_FRU_5':
 C_SIGNAL='@s9s_mb_2u_lib.s9s_mb_2u(sch_1):tp_chc_cpu1_dimm2_fru_5';
NODE_NAME     J22 231
 '@S9S_MB_2U_LIB.S9S_MB_2U(SCH_1):PAGE103_I51@PURE_QUANTA.SCONN288_ADR50017P087CC(CHIPS)':
 'RFU5': CDS_PINID='RFU5';
NET_NAME
'TP_CHC_CPU1_DIMM2_FRU_6'
 '@S9S_MB_2U_LIB.S9S_MB_2U(SCH_1):TP_CHC_CPU1_DIMM2_FRU_6':
 C_SIGNAL='@s9s_mb_2u_lib.s9s_mb_2u(sch_1):tp_chc_cpu1_dimm2_fru_6';
NODE_NAME     J22 232
 '@S9S_MB_2U_LIB.S9S_MB_2U(SCH_1):PAGE103_I51@PURE_QUANTA.SCONN288_ADR50017P087CC(CHIPS)':
 'RFU6': CDS_PINID='RFU6';
NET_NAME
'TP_CHD_CPU0_DIMM1_FRU_0'
 '@S9S_MB_2U_LIB.S9S_MB_2U(SCH_1):TP_CHD_CPU0_DIMM1_FRU_0':
 C_SIGNAL='@s9s_mb_2u_lib.s9s_mb_2u(sch_1):tp_chd_cpu0_dimm1_fru_0';
NODE_NAME     J7 2
 '@S9S_MB_2U_LIB.S9S_MB_2U(SCH_1):PAGE88_I12@PURE_QUANTA.SCONN288_ADR50017P130CC(CHIPS)':
 'RFU0': CDS_PINID='RFU0';
NET_NAME
'TP_CHD_CPU0_DIMM1_FRU_1'
 '@S9S_MB_2U_LIB.S9S_MB_2U(SCH_1):TP_CHD_CPU0_DIMM1_FRU_1':
 C_SIGNAL='@s9s_mb_2u_lib.s9s_mb_2u(sch_1):tp_chd_cpu0_dimm1_fru_1';
NODE_NAME     J7 144
 '@S9S_MB_2U_LIB.S9S_MB_2U(SCH_1):PAGE88_I12@PURE_QUANTA.SCONN288_ADR50017P130CC(CHIPS)':
 'RFU1': CDS_PINID='RFU1';
NET_NAME
'TP_CHD_CPU0_DIMM1_FRU_2'
 '@S9S_MB_2U_LIB.S9S_MB_2U(SCH_1):TP_CHD_CPU0_DIMM1_FRU_2':
 C_SIGNAL='@s9s_mb_2u_lib.s9s_mb_2u(sch_1):tp_chd_cpu0_dimm1_fru_2';
NODE_NAME     J7 149
 '@S9S_MB_2U_LIB.S9S_MB_2U(SCH_1):PAGE88_I12@PURE_QUANTA.SCONN288_ADR50017P130CC(CHIPS)':
 'RFU2': CDS_PINID='RFU2';
NET_NAME
'TP_CHD_CPU0_DIMM1_FRU_3'
 '@S9S_MB_2U_LIB.S9S_MB_2U(SCH_1):TP_CHD_CPU0_DIMM1_FRU_3':
 C_SIGNAL='@s9s_mb_2u_lib.s9s_mb_2u(sch_1):tp_chd_cpu0_dimm1_fru_3';
NODE_NAME     J7 150
 '@S9S_MB_2U_LIB.S9S_MB_2U(SCH_1):PAGE88_I12@PURE_QUANTA.SCONN288_ADR50017P130CC(CHIPS)':
 'RFU3': CDS_PINID='RFU3';
NET_NAME
'TP_CHD_CPU0_DIMM1_FRU_4'
 '@S9S_MB_2U_LIB.S9S_MB_2U(SCH_1):TP_CHD_CPU0_DIMM1_FRU_4':
 C_SIGNAL='@s9s_mb_2u_lib.s9s_mb_2u(sch_1):tp_chd_cpu0_dimm1_fru_4';
NODE_NAME     J7 220
 '@S9S_MB_2U_LIB.S9S_MB_2U(SCH_1):PAGE88_I12@PURE_QUANTA.SCONN288_ADR50017P130CC(CHIPS)':
 'RFU4': CDS_PINID='RFU4';
NET_NAME
'TP_CHD_CPU0_DIMM1_FRU_5'
 '@S9S_MB_2U_LIB.S9S_MB_2U(SCH_1):TP_CHD_CPU0_DIMM1_FRU_5':
 C_SIGNAL='@s9s_mb_2u_lib.s9s_mb_2u(sch_1):tp_chd_cpu0_dimm1_fru_5';
NODE_NAME     J7 231
 '@S9S_MB_2U_LIB.S9S_MB_2U(SCH_1):PAGE88_I12@PURE_QUANTA.SCONN288_ADR50017P130CC(CHIPS)':
 'RFU5': CDS_PINID='RFU5';
NET_NAME
'TP_CHD_CPU0_DIMM1_FRU_6'
 '@S9S_MB_2U_LIB.S9S_MB_2U(SCH_1):TP_CHD_CPU0_DIMM1_FRU_6':
 C_SIGNAL='@s9s_mb_2u_lib.s9s_mb_2u(sch_1):tp_chd_cpu0_dimm1_fru_6';
NODE_NAME     J7 232
 '@S9S_MB_2U_LIB.S9S_MB_2U(SCH_1):PAGE88_I12@PURE_QUANTA.SCONN288_ADR50017P130CC(CHIPS)':
 'RFU6': CDS_PINID='RFU6';
NET_NAME
'TP_CHD_CPU0_DIMM2_FRU_0'
 '@S9S_MB_2U_LIB.S9S_MB_2U(SCH_1):TP_CHD_CPU0_DIMM2_FRU_0':
 C_SIGNAL='@s9s_mb_2u_lib.s9s_mb_2u(sch_1):tp_chd_cpu0_dimm2_fru_0';
NODE_NAME     J8 2
 '@S9S_MB_2U_LIB.S9S_MB_2U(SCH_1):PAGE89_I50@PURE_QUANTA.SCONN288_ADR50017P087CC(CHIPS)':
 'RFU0': CDS_PINID='RFU0';
NET_NAME
'TP_CHD_CPU0_DIMM2_FRU_1'
 '@S9S_MB_2U_LIB.S9S_MB_2U(SCH_1):TP_CHD_CPU0_DIMM2_FRU_1':
 C_SIGNAL='@s9s_mb_2u_lib.s9s_mb_2u(sch_1):tp_chd_cpu0_dimm2_fru_1';
NODE_NAME     J8 144
 '@S9S_MB_2U_LIB.S9S_MB_2U(SCH_1):PAGE89_I50@PURE_QUANTA.SCONN288_ADR50017P087CC(CHIPS)':
 'RFU1': CDS_PINID='RFU1';
NET_NAME
'TP_CHD_CPU0_DIMM2_FRU_2'
 '@S9S_MB_2U_LIB.S9S_MB_2U(SCH_1):TP_CHD_CPU0_DIMM2_FRU_2':
 C_SIGNAL='@s9s_mb_2u_lib.s9s_mb_2u(sch_1):tp_chd_cpu0_dimm2_fru_2';
NODE_NAME     J8 149
 '@S9S_MB_2U_LIB.S9S_MB_2U(SCH_1):PAGE89_I50@PURE_QUANTA.SCONN288_ADR50017P087CC(CHIPS)':
 'RFU2': CDS_PINID='RFU2';
NET_NAME
'TP_CHD_CPU0_DIMM2_FRU_3'
 '@S9S_MB_2U_LIB.S9S_MB_2U(SCH_1):TP_CHD_CPU0_DIMM2_FRU_3':
 C_SIGNAL='@s9s_mb_2u_lib.s9s_mb_2u(sch_1):tp_chd_cpu0_dimm2_fru_3';
NODE_NAME     J8 150
 '@S9S_MB_2U_LIB.S9S_MB_2U(SCH_1):PAGE89_I50@PURE_QUANTA.SCONN288_ADR50017P087CC(CHIPS)':
 'RFU3': CDS_PINID='RFU3';
NET_NAME
'TP_CHD_CPU0_DIMM2_FRU_4'
 '@S9S_MB_2U_LIB.S9S_MB_2U(SCH_1):TP_CHD_CPU0_DIMM2_FRU_4':
 C_SIGNAL='@s9s_mb_2u_lib.s9s_mb_2u(sch_1):tp_chd_cpu0_dimm2_fru_4';
NODE_NAME     J8 220
 '@S9S_MB_2U_LIB.S9S_MB_2U(SCH_1):PAGE89_I50@PURE_QUANTA.SCONN288_ADR50017P087CC(CHIPS)':
 'RFU4': CDS_PINID='RFU4';
NET_NAME
'TP_CHD_CPU0_DIMM2_FRU_5'
 '@S9S_MB_2U_LIB.S9S_MB_2U(SCH_1):TP_CHD_CPU0_DIMM2_FRU_5':
 C_SIGNAL='@s9s_mb_2u_lib.s9s_mb_2u(sch_1):tp_chd_cpu0_dimm2_fru_5';
NODE_NAME     J8 231
 '@S9S_MB_2U_LIB.S9S_MB_2U(SCH_1):PAGE89_I50@PURE_QUANTA.SCONN288_ADR50017P087CC(CHIPS)':
 'RFU5': CDS_PINID='RFU5';
NET_NAME
'TP_CHD_CPU0_DIMM2_FRU_6'
 '@S9S_MB_2U_LIB.S9S_MB_2U(SCH_1):TP_CHD_CPU0_DIMM2_FRU_6':
 C_SIGNAL='@s9s_mb_2u_lib.s9s_mb_2u(sch_1):tp_chd_cpu0_dimm2_fru_6';
NODE_NAME     J8 232
 '@S9S_MB_2U_LIB.S9S_MB_2U(SCH_1):PAGE89_I50@PURE_QUANTA.SCONN288_ADR50017P087CC(CHIPS)':
 'RFU6': CDS_PINID='RFU6';
NET_NAME
'TP_CHD_CPU1_DIMM1_FRU_0'
 '@S9S_MB_2U_LIB.S9S_MB_2U(SCH_1):TP_CHD_CPU1_DIMM1_FRU_0':
 C_SIGNAL='@s9s_mb_2u_lib.s9s_mb_2u(sch_1):tp_chd_cpu1_dimm1_fru_0';
NODE_NAME     J23 2
 '@S9S_MB_2U_LIB.S9S_MB_2U(SCH_1):PAGE104_I25@PURE_QUANTA.SCONN288_ADR50017P130CC(CHIPS)':
 'RFU0': CDS_PINID='RFU0';
NET_NAME
'TP_CHD_CPU1_DIMM1_FRU_1'
 '@S9S_MB_2U_LIB.S9S_MB_2U(SCH_1):TP_CHD_CPU1_DIMM1_FRU_1':
 C_SIGNAL='@s9s_mb_2u_lib.s9s_mb_2u(sch_1):tp_chd_cpu1_dimm1_fru_1';
NODE_NAME     J23 144
 '@S9S_MB_2U_LIB.S9S_MB_2U(SCH_1):PAGE104_I25@PURE_QUANTA.SCONN288_ADR50017P130CC(CHIPS)':
 'RFU1': CDS_PINID='RFU1';
NET_NAME
'TP_CHD_CPU1_DIMM1_FRU_2'
 '@S9S_MB_2U_LIB.S9S_MB_2U(SCH_1):TP_CHD_CPU1_DIMM1_FRU_2':
 C_SIGNAL='@s9s_mb_2u_lib.s9s_mb_2u(sch_1):tp_chd_cpu1_dimm1_fru_2';
NODE_NAME     J23 149
 '@S9S_MB_2U_LIB.S9S_MB_2U(SCH_1):PAGE104_I25@PURE_QUANTA.SCONN288_ADR50017P130CC(CHIPS)':
 'RFU2': CDS_PINID='RFU2';
NET_NAME
'TP_CHD_CPU1_DIMM1_FRU_3'
 '@S9S_MB_2U_LIB.S9S_MB_2U(SCH_1):TP_CHD_CPU1_DIMM1_FRU_3':
 C_SIGNAL='@s9s_mb_2u_lib.s9s_mb_2u(sch_1):tp_chd_cpu1_dimm1_fru_3';
NODE_NAME     J23 150
 '@S9S_MB_2U_LIB.S9S_MB_2U(SCH_1):PAGE104_I25@PURE_QUANTA.SCONN288_ADR50017P130CC(CHIPS)':
 'RFU3': CDS_PINID='RFU3';
NET_NAME
'TP_CHD_CPU1_DIMM1_FRU_4'
 '@S9S_MB_2U_LIB.S9S_MB_2U(SCH_1):TP_CHD_CPU1_DIMM1_FRU_4':
 C_SIGNAL='@s9s_mb_2u_lib.s9s_mb_2u(sch_1):tp_chd_cpu1_dimm1_fru_4';
NODE_NAME     J23 220
 '@S9S_MB_2U_LIB.S9S_MB_2U(SCH_1):PAGE104_I25@PURE_QUANTA.SCONN288_ADR50017P130CC(CHIPS)':
 'RFU4': CDS_PINID='RFU4';
NET_NAME
'TP_CHD_CPU1_DIMM1_FRU_5'
 '@S9S_MB_2U_LIB.S9S_MB_2U(SCH_1):TP_CHD_CPU1_DIMM1_FRU_5':
 C_SIGNAL='@s9s_mb_2u_lib.s9s_mb_2u(sch_1):tp_chd_cpu1_dimm1_fru_5';
NODE_NAME     J23 231
 '@S9S_MB_2U_LIB.S9S_MB_2U(SCH_1):PAGE104_I25@PURE_QUANTA.SCONN288_ADR50017P130CC(CHIPS)':
 'RFU5': CDS_PINID='RFU5';
NET_NAME
'TP_CHD_CPU1_DIMM1_FRU_6'
 '@S9S_MB_2U_LIB.S9S_MB_2U(SCH_1):TP_CHD_CPU1_DIMM1_FRU_6':
 C_SIGNAL='@s9s_mb_2u_lib.s9s_mb_2u(sch_1):tp_chd_cpu1_dimm1_fru_6';
NODE_NAME     J23 232
 '@S9S_MB_2U_LIB.S9S_MB_2U(SCH_1):PAGE104_I25@PURE_QUANTA.SCONN288_ADR50017P130CC(CHIPS)':
 'RFU6': CDS_PINID='RFU6';
NET_NAME
'TP_CHD_CPU1_DIMM2_FRU_0'
 '@S9S_MB_2U_LIB.S9S_MB_2U(SCH_1):TP_CHD_CPU1_DIMM2_FRU_0':
 C_SIGNAL='@s9s_mb_2u_lib.s9s_mb_2u(sch_1):tp_chd_cpu1_dimm2_fru_0';
NODE_NAME     J24 2
 '@S9S_MB_2U_LIB.S9S_MB_2U(SCH_1):PAGE105_I178@PURE_QUANTA.SCONN288_ADR50017P087CC(CHIPS)':
 'RFU0': CDS_PINID='RFU0';
NET_NAME
'TP_CHD_CPU1_DIMM2_FRU_1'
 '@S9S_MB_2U_LIB.S9S_MB_2U(SCH_1):TP_CHD_CPU1_DIMM2_FRU_1':
 C_SIGNAL='@s9s_mb_2u_lib.s9s_mb_2u(sch_1):tp_chd_cpu1_dimm2_fru_1';
NODE_NAME     J24 144
 '@S9S_MB_2U_LIB.S9S_MB_2U(SCH_1):PAGE105_I178@PURE_QUANTA.SCONN288_ADR50017P087CC(CHIPS)':
 'RFU1': CDS_PINID='RFU1';
NET_NAME
'TP_CHD_CPU1_DIMM2_FRU_2'
 '@S9S_MB_2U_LIB.S9S_MB_2U(SCH_1):TP_CHD_CPU1_DIMM2_FRU_2':
 C_SIGNAL='@s9s_mb_2u_lib.s9s_mb_2u(sch_1):tp_chd_cpu1_dimm2_fru_2';
NODE_NAME     J24 149
 '@S9S_MB_2U_LIB.S9S_MB_2U(SCH_1):PAGE105_I178@PURE_QUANTA.SCONN288_ADR50017P087CC(CHIPS)':
 'RFU2': CDS_PINID='RFU2';
NET_NAME
'TP_CHD_CPU1_DIMM2_FRU_3'
 '@S9S_MB_2U_LIB.S9S_MB_2U(SCH_1):TP_CHD_CPU1_DIMM2_FRU_3':
 C_SIGNAL='@s9s_mb_2u_lib.s9s_mb_2u(sch_1):tp_chd_cpu1_dimm2_fru_3';
NODE_NAME     J24 150
 '@S9S_MB_2U_LIB.S9S_MB_2U(SCH_1):PAGE105_I178@PURE_QUANTA.SCONN288_ADR50017P087CC(CHIPS)':
 'RFU3': CDS_PINID='RFU3';
NET_NAME
'TP_CHD_CPU1_DIMM2_FRU_4'
 '@S9S_MB_2U_LIB.S9S_MB_2U(SCH_1):TP_CHD_CPU1_DIMM2_FRU_4':
 C_SIGNAL='@s9s_mb_2u_lib.s9s_mb_2u(sch_1):tp_chd_cpu1_dimm2_fru_4';
NODE_NAME     J24 220
 '@S9S_MB_2U_LIB.S9S_MB_2U(SCH_1):PAGE105_I178@PURE_QUANTA.SCONN288_ADR50017P087CC(CHIPS)':
 'RFU4': CDS_PINID='RFU4';
NET_NAME
'TP_CHD_CPU1_DIMM2_FRU_5'
 '@S9S_MB_2U_LIB.S9S_MB_2U(SCH_1):TP_CHD_CPU1_DIMM2_FRU_5':
 C_SIGNAL='@s9s_mb_2u_lib.s9s_mb_2u(sch_1):tp_chd_cpu1_dimm2_fru_5';
NODE_NAME     J24 231
 '@S9S_MB_2U_LIB.S9S_MB_2U(SCH_1):PAGE105_I178@PURE_QUANTA.SCONN288_ADR50017P087CC(CHIPS)':
 'RFU5': CDS_PINID='RFU5';
NET_NAME
'TP_CHD_CPU1_DIMM2_FRU_6'
 '@S9S_MB_2U_LIB.S9S_MB_2U(SCH_1):TP_CHD_CPU1_DIMM2_FRU_6':
 C_SIGNAL='@s9s_mb_2u_lib.s9s_mb_2u(sch_1):tp_chd_cpu1_dimm2_fru_6';
NODE_NAME     J24 232
 '@S9S_MB_2U_LIB.S9S_MB_2U(SCH_1):PAGE105_I178@PURE_QUANTA.SCONN288_ADR50017P087CC(CHIPS)':
 'RFU6': CDS_PINID='RFU6';
NET_NAME
'TP_CHE_CPU0_DIMM1_FRU_0'
 '@S9S_MB_2U_LIB.S9S_MB_2U(SCH_1):TP_CHE_CPU0_DIMM1_FRU_0':
 C_SIGNAL='@s9s_mb_2u_lib.s9s_mb_2u(sch_1):tp_che_cpu0_dimm1_fru_0';
NODE_NAME     J9 2
 '@S9S_MB_2U_LIB.S9S_MB_2U(SCH_1):PAGE90_I12@PURE_QUANTA.SCONN288_ADR50017P130CC(CHIPS)':
 'RFU0': CDS_PINID='RFU0';
NET_NAME
'TP_CHE_CPU0_DIMM1_FRU_1'
 '@S9S_MB_2U_LIB.S9S_MB_2U(SCH_1):TP_CHE_CPU0_DIMM1_FRU_1':
 C_SIGNAL='@s9s_mb_2u_lib.s9s_mb_2u(sch_1):tp_che_cpu0_dimm1_fru_1';
NODE_NAME     J9 144
 '@S9S_MB_2U_LIB.S9S_MB_2U(SCH_1):PAGE90_I12@PURE_QUANTA.SCONN288_ADR50017P130CC(CHIPS)':
 'RFU1': CDS_PINID='RFU1';
NET_NAME
'TP_CHE_CPU0_DIMM1_FRU_2'
 '@S9S_MB_2U_LIB.S9S_MB_2U(SCH_1):TP_CHE_CPU0_DIMM1_FRU_2':
 C_SIGNAL='@s9s_mb_2u_lib.s9s_mb_2u(sch_1):tp_che_cpu0_dimm1_fru_2';
NODE_NAME     J9 149
 '@S9S_MB_2U_LIB.S9S_MB_2U(SCH_1):PAGE90_I12@PURE_QUANTA.SCONN288_ADR50017P130CC(CHIPS)':
 'RFU2': CDS_PINID='RFU2';
NET_NAME
'TP_CHE_CPU0_DIMM1_FRU_3'
 '@S9S_MB_2U_LIB.S9S_MB_2U(SCH_1):TP_CHE_CPU0_DIMM1_FRU_3':
 C_SIGNAL='@s9s_mb_2u_lib.s9s_mb_2u(sch_1):tp_che_cpu0_dimm1_fru_3';
NODE_NAME     J9 150
 '@S9S_MB_2U_LIB.S9S_MB_2U(SCH_1):PAGE90_I12@PURE_QUANTA.SCONN288_ADR50017P130CC(CHIPS)':
 'RFU3': CDS_PINID='RFU3';
NET_NAME
'TP_CHE_CPU0_DIMM1_FRU_4'
 '@S9S_MB_2U_LIB.S9S_MB_2U(SCH_1):TP_CHE_CPU0_DIMM1_FRU_4':
 C_SIGNAL='@s9s_mb_2u_lib.s9s_mb_2u(sch_1):tp_che_cpu0_dimm1_fru_4';
NODE_NAME     J9 220
 '@S9S_MB_2U_LIB.S9S_MB_2U(SCH_1):PAGE90_I12@PURE_QUANTA.SCONN288_ADR50017P130CC(CHIPS)':
 'RFU4': CDS_PINID='RFU4';
NET_NAME
'TP_CHE_CPU0_DIMM1_FRU_5'
 '@S9S_MB_2U_LIB.S9S_MB_2U(SCH_1):TP_CHE_CPU0_DIMM1_FRU_5':
 C_SIGNAL='@s9s_mb_2u_lib.s9s_mb_2u(sch_1):tp_che_cpu0_dimm1_fru_5';
NODE_NAME     J9 231
 '@S9S_MB_2U_LIB.S9S_MB_2U(SCH_1):PAGE90_I12@PURE_QUANTA.SCONN288_ADR50017P130CC(CHIPS)':
 'RFU5': CDS_PINID='RFU5';
NET_NAME
'TP_CHE_CPU0_DIMM1_FRU_6'
 '@S9S_MB_2U_LIB.S9S_MB_2U(SCH_1):TP_CHE_CPU0_DIMM1_FRU_6':
 C_SIGNAL='@s9s_mb_2u_lib.s9s_mb_2u(sch_1):tp_che_cpu0_dimm1_fru_6';
NODE_NAME     J9 232
 '@S9S_MB_2U_LIB.S9S_MB_2U(SCH_1):PAGE90_I12@PURE_QUANTA.SCONN288_ADR50017P130CC(CHIPS)':
 'RFU6': CDS_PINID='RFU6';
NET_NAME
'TP_CHE_CPU0_DIMM2_FRU_0'
 '@S9S_MB_2U_LIB.S9S_MB_2U(SCH_1):TP_CHE_CPU0_DIMM2_FRU_0':
 C_SIGNAL='@s9s_mb_2u_lib.s9s_mb_2u(sch_1):tp_che_cpu0_dimm2_fru_0';
NODE_NAME     J10 2
 '@S9S_MB_2U_LIB.S9S_MB_2U(SCH_1):PAGE91_I13@PURE_QUANTA.SCONN288_ADR50017P087CC(CHIPS)':
 'RFU0': CDS_PINID='RFU0';
NET_NAME
'TP_CHE_CPU0_DIMM2_FRU_1'
 '@S9S_MB_2U_LIB.S9S_MB_2U(SCH_1):TP_CHE_CPU0_DIMM2_FRU_1':
 C_SIGNAL='@s9s_mb_2u_lib.s9s_mb_2u(sch_1):tp_che_cpu0_dimm2_fru_1';
NODE_NAME     J10 144
 '@S9S_MB_2U_LIB.S9S_MB_2U(SCH_1):PAGE91_I13@PURE_QUANTA.SCONN288_ADR50017P087CC(CHIPS)':
 'RFU1': CDS_PINID='RFU1';
NET_NAME
'TP_CHE_CPU0_DIMM2_FRU_2'
 '@S9S_MB_2U_LIB.S9S_MB_2U(SCH_1):TP_CHE_CPU0_DIMM2_FRU_2':
 C_SIGNAL='@s9s_mb_2u_lib.s9s_mb_2u(sch_1):tp_che_cpu0_dimm2_fru_2';
NODE_NAME     J10 149
 '@S9S_MB_2U_LIB.S9S_MB_2U(SCH_1):PAGE91_I13@PURE_QUANTA.SCONN288_ADR50017P087CC(CHIPS)':
 'RFU2': CDS_PINID='RFU2';
NET_NAME
'TP_CHE_CPU0_DIMM2_FRU_3'
 '@S9S_MB_2U_LIB.S9S_MB_2U(SCH_1):TP_CHE_CPU0_DIMM2_FRU_3':
 C_SIGNAL='@s9s_mb_2u_lib.s9s_mb_2u(sch_1):tp_che_cpu0_dimm2_fru_3';
NODE_NAME     J10 150
 '@S9S_MB_2U_LIB.S9S_MB_2U(SCH_1):PAGE91_I13@PURE_QUANTA.SCONN288_ADR50017P087CC(CHIPS)':
 'RFU3': CDS_PINID='RFU3';
NET_NAME
'TP_CHE_CPU0_DIMM2_FRU_4'
 '@S9S_MB_2U_LIB.S9S_MB_2U(SCH_1):TP_CHE_CPU0_DIMM2_FRU_4':
 C_SIGNAL='@s9s_mb_2u_lib.s9s_mb_2u(sch_1):tp_che_cpu0_dimm2_fru_4';
NODE_NAME     J10 220
 '@S9S_MB_2U_LIB.S9S_MB_2U(SCH_1):PAGE91_I13@PURE_QUANTA.SCONN288_ADR50017P087CC(CHIPS)':
 'RFU4': CDS_PINID='RFU4';
NET_NAME
'TP_CHE_CPU0_DIMM2_FRU_5'
 '@S9S_MB_2U_LIB.S9S_MB_2U(SCH_1):TP_CHE_CPU0_DIMM2_FRU_5':
 C_SIGNAL='@s9s_mb_2u_lib.s9s_mb_2u(sch_1):tp_che_cpu0_dimm2_fru_5';
NODE_NAME     J10 231
 '@S9S_MB_2U_LIB.S9S_MB_2U(SCH_1):PAGE91_I13@PURE_QUANTA.SCONN288_ADR50017P087CC(CHIPS)':
 'RFU5': CDS_PINID='RFU5';
NET_NAME
'TP_CHE_CPU0_DIMM2_FRU_6'
 '@S9S_MB_2U_LIB.S9S_MB_2U(SCH_1):TP_CHE_CPU0_DIMM2_FRU_6':
 C_SIGNAL='@s9s_mb_2u_lib.s9s_mb_2u(sch_1):tp_che_cpu0_dimm2_fru_6';
NODE_NAME     J10 232
 '@S9S_MB_2U_LIB.S9S_MB_2U(SCH_1):PAGE91_I13@PURE_QUANTA.SCONN288_ADR50017P087CC(CHIPS)':
 'RFU6': CDS_PINID='RFU6';
NET_NAME
'TP_CHE_CPU1_DIMM1_FRU_0'
 '@S9S_MB_2U_LIB.S9S_MB_2U(SCH_1):TP_CHE_CPU1_DIMM1_FRU_0':
 C_SIGNAL='@s9s_mb_2u_lib.s9s_mb_2u(sch_1):tp_che_cpu1_dimm1_fru_0';
NODE_NAME     J25 2
 '@S9S_MB_2U_LIB.S9S_MB_2U(SCH_1):PAGE106_I180@PURE_QUANTA.SCONN288_ADR50017P130CC(CHIPS)':
 'RFU0': CDS_PINID='RFU0';
NET_NAME
'TP_CHE_CPU1_DIMM1_FRU_1'
 '@S9S_MB_2U_LIB.S9S_MB_2U(SCH_1):TP_CHE_CPU1_DIMM1_FRU_1':
 C_SIGNAL='@s9s_mb_2u_lib.s9s_mb_2u(sch_1):tp_che_cpu1_dimm1_fru_1';
NODE_NAME     J25 144
 '@S9S_MB_2U_LIB.S9S_MB_2U(SCH_1):PAGE106_I180@PURE_QUANTA.SCONN288_ADR50017P130CC(CHIPS)':
 'RFU1': CDS_PINID='RFU1';
NET_NAME
'TP_CHE_CPU1_DIMM1_FRU_2'
 '@S9S_MB_2U_LIB.S9S_MB_2U(SCH_1):TP_CHE_CPU1_DIMM1_FRU_2':
 C_SIGNAL='@s9s_mb_2u_lib.s9s_mb_2u(sch_1):tp_che_cpu1_dimm1_fru_2';
NODE_NAME     J25 149
 '@S9S_MB_2U_LIB.S9S_MB_2U(SCH_1):PAGE106_I180@PURE_QUANTA.SCONN288_ADR50017P130CC(CHIPS)':
 'RFU2': CDS_PINID='RFU2';
NET_NAME
'TP_CHE_CPU1_DIMM1_FRU_3'
 '@S9S_MB_2U_LIB.S9S_MB_2U(SCH_1):TP_CHE_CPU1_DIMM1_FRU_3':
 C_SIGNAL='@s9s_mb_2u_lib.s9s_mb_2u(sch_1):tp_che_cpu1_dimm1_fru_3';
NODE_NAME     J25 150
 '@S9S_MB_2U_LIB.S9S_MB_2U(SCH_1):PAGE106_I180@PURE_QUANTA.SCONN288_ADR50017P130CC(CHIPS)':
 'RFU3': CDS_PINID='RFU3';
NET_NAME
'TP_CHE_CPU1_DIMM1_FRU_4'
 '@S9S_MB_2U_LIB.S9S_MB_2U(SCH_1):TP_CHE_CPU1_DIMM1_FRU_4':
 C_SIGNAL='@s9s_mb_2u_lib.s9s_mb_2u(sch_1):tp_che_cpu1_dimm1_fru_4';
NODE_NAME     J25 220
 '@S9S_MB_2U_LIB.S9S_MB_2U(SCH_1):PAGE106_I180@PURE_QUANTA.SCONN288_ADR50017P130CC(CHIPS)':
 'RFU4': CDS_PINID='RFU4';
NET_NAME
'TP_CHE_CPU1_DIMM1_FRU_5'
 '@S9S_MB_2U_LIB.S9S_MB_2U(SCH_1):TP_CHE_CPU1_DIMM1_FRU_5':
 C_SIGNAL='@s9s_mb_2u_lib.s9s_mb_2u(sch_1):tp_che_cpu1_dimm1_fru_5';
NODE_NAME     J25 231
 '@S9S_MB_2U_LIB.S9S_MB_2U(SCH_1):PAGE106_I180@PURE_QUANTA.SCONN288_ADR50017P130CC(CHIPS)':
 'RFU5': CDS_PINID='RFU5';
NET_NAME
'TP_CHE_CPU1_DIMM1_FRU_6'
 '@S9S_MB_2U_LIB.S9S_MB_2U(SCH_1):TP_CHE_CPU1_DIMM1_FRU_6':
 C_SIGNAL='@s9s_mb_2u_lib.s9s_mb_2u(sch_1):tp_che_cpu1_dimm1_fru_6';
NODE_NAME     J25 232
 '@S9S_MB_2U_LIB.S9S_MB_2U(SCH_1):PAGE106_I180@PURE_QUANTA.SCONN288_ADR50017P130CC(CHIPS)':
 'RFU6': CDS_PINID='RFU6';
NET_NAME
'TP_CHE_CPU1_DIMM2_FRU_0'
 '@S9S_MB_2U_LIB.S9S_MB_2U(SCH_1):TP_CHE_CPU1_DIMM2_FRU_0':
 C_SIGNAL='@s9s_mb_2u_lib.s9s_mb_2u(sch_1):tp_che_cpu1_dimm2_fru_0';
NODE_NAME     J26 2
 '@S9S_MB_2U_LIB.S9S_MB_2U(SCH_1):PAGE107_I180@PURE_QUANTA.SCONN288_ADR50017P087CC(CHIPS)':
 'RFU0': CDS_PINID='RFU0';
NET_NAME
'TP_CHE_CPU1_DIMM2_FRU_1'
 '@S9S_MB_2U_LIB.S9S_MB_2U(SCH_1):TP_CHE_CPU1_DIMM2_FRU_1':
 C_SIGNAL='@s9s_mb_2u_lib.s9s_mb_2u(sch_1):tp_che_cpu1_dimm2_fru_1';
NODE_NAME     J26 144
 '@S9S_MB_2U_LIB.S9S_MB_2U(SCH_1):PAGE107_I180@PURE_QUANTA.SCONN288_ADR50017P087CC(CHIPS)':
 'RFU1': CDS_PINID='RFU1';
NET_NAME
'TP_CHE_CPU1_DIMM2_FRU_2'
 '@S9S_MB_2U_LIB.S9S_MB_2U(SCH_1):TP_CHE_CPU1_DIMM2_FRU_2':
 C_SIGNAL='@s9s_mb_2u_lib.s9s_mb_2u(sch_1):tp_che_cpu1_dimm2_fru_2';
NODE_NAME     J26 149
 '@S9S_MB_2U_LIB.S9S_MB_2U(SCH_1):PAGE107_I180@PURE_QUANTA.SCONN288_ADR50017P087CC(CHIPS)':
 'RFU2': CDS_PINID='RFU2';
NET_NAME
'TP_CHE_CPU1_DIMM2_FRU_3'
 '@S9S_MB_2U_LIB.S9S_MB_2U(SCH_1):TP_CHE_CPU1_DIMM2_FRU_3':
 C_SIGNAL='@s9s_mb_2u_lib.s9s_mb_2u(sch_1):tp_che_cpu1_dimm2_fru_3';
NODE_NAME     J26 150
 '@S9S_MB_2U_LIB.S9S_MB_2U(SCH_1):PAGE107_I180@PURE_QUANTA.SCONN288_ADR50017P087CC(CHIPS)':
 'RFU3': CDS_PINID='RFU3';
NET_NAME
'TP_CHE_CPU1_DIMM2_FRU_4'
 '@S9S_MB_2U_LIB.S9S_MB_2U(SCH_1):TP_CHE_CPU1_DIMM2_FRU_4':
 C_SIGNAL='@s9s_mb_2u_lib.s9s_mb_2u(sch_1):tp_che_cpu1_dimm2_fru_4';
NODE_NAME     J26 220
 '@S9S_MB_2U_LIB.S9S_MB_2U(SCH_1):PAGE107_I180@PURE_QUANTA.SCONN288_ADR50017P087CC(CHIPS)':
 'RFU4': CDS_PINID='RFU4';
NET_NAME
'TP_CHE_CPU1_DIMM2_FRU_5'
 '@S9S_MB_2U_LIB.S9S_MB_2U(SCH_1):TP_CHE_CPU1_DIMM2_FRU_5':
 C_SIGNAL='@s9s_mb_2u_lib.s9s_mb_2u(sch_1):tp_che_cpu1_dimm2_fru_5';
NODE_NAME     J26 231
 '@S9S_MB_2U_LIB.S9S_MB_2U(SCH_1):PAGE107_I180@PURE_QUANTA.SCONN288_ADR50017P087CC(CHIPS)':
 'RFU5': CDS_PINID='RFU5';
NET_NAME
'TP_CHE_CPU1_DIMM2_FRU_6'
 '@S9S_MB_2U_LIB.S9S_MB_2U(SCH_1):TP_CHE_CPU1_DIMM2_FRU_6':
 C_SIGNAL='@s9s_mb_2u_lib.s9s_mb_2u(sch_1):tp_che_cpu1_dimm2_fru_6';
NODE_NAME     J26 232
 '@S9S_MB_2U_LIB.S9S_MB_2U(SCH_1):PAGE107_I180@PURE_QUANTA.SCONN288_ADR50017P087CC(CHIPS)':
 'RFU6': CDS_PINID='RFU6';
NET_NAME
'TP_CHF_CPU0_DIMM1_FRU_0'
 '@S9S_MB_2U_LIB.S9S_MB_2U(SCH_1):TP_CHF_CPU0_DIMM1_FRU_0':
 C_SIGNAL='@s9s_mb_2u_lib.s9s_mb_2u(sch_1):tp_chf_cpu0_dimm1_fru_0';
NODE_NAME     J11 2
 '@S9S_MB_2U_LIB.S9S_MB_2U(SCH_1):PAGE92_I25@PURE_QUANTA.SCONN288_ADR50017P130CC(CHIPS)':
 'RFU0': CDS_PINID='RFU0';
NET_NAME
'TP_CHF_CPU0_DIMM1_FRU_1'
 '@S9S_MB_2U_LIB.S9S_MB_2U(SCH_1):TP_CHF_CPU0_DIMM1_FRU_1':
 C_SIGNAL='@s9s_mb_2u_lib.s9s_mb_2u(sch_1):tp_chf_cpu0_dimm1_fru_1';
NODE_NAME     J11 144
 '@S9S_MB_2U_LIB.S9S_MB_2U(SCH_1):PAGE92_I25@PURE_QUANTA.SCONN288_ADR50017P130CC(CHIPS)':
 'RFU1': CDS_PINID='RFU1';
NET_NAME
'TP_CHF_CPU0_DIMM1_FRU_2'
 '@S9S_MB_2U_LIB.S9S_MB_2U(SCH_1):TP_CHF_CPU0_DIMM1_FRU_2':
 C_SIGNAL='@s9s_mb_2u_lib.s9s_mb_2u(sch_1):tp_chf_cpu0_dimm1_fru_2';
NODE_NAME     J11 149
 '@S9S_MB_2U_LIB.S9S_MB_2U(SCH_1):PAGE92_I25@PURE_QUANTA.SCONN288_ADR50017P130CC(CHIPS)':
 'RFU2': CDS_PINID='RFU2';
NET_NAME
'TP_CHF_CPU0_DIMM1_FRU_3'
 '@S9S_MB_2U_LIB.S9S_MB_2U(SCH_1):TP_CHF_CPU0_DIMM1_FRU_3':
 C_SIGNAL='@s9s_mb_2u_lib.s9s_mb_2u(sch_1):tp_chf_cpu0_dimm1_fru_3';
NODE_NAME     J11 150
 '@S9S_MB_2U_LIB.S9S_MB_2U(SCH_1):PAGE92_I25@PURE_QUANTA.SCONN288_ADR50017P130CC(CHIPS)':
 'RFU3': CDS_PINID='RFU3';
NET_NAME
'TP_CHF_CPU0_DIMM1_FRU_4'
 '@S9S_MB_2U_LIB.S9S_MB_2U(SCH_1):TP_CHF_CPU0_DIMM1_FRU_4':
 C_SIGNAL='@s9s_mb_2u_lib.s9s_mb_2u(sch_1):tp_chf_cpu0_dimm1_fru_4';
NODE_NAME     J11 220
 '@S9S_MB_2U_LIB.S9S_MB_2U(SCH_1):PAGE92_I25@PURE_QUANTA.SCONN288_ADR50017P130CC(CHIPS)':
 'RFU4': CDS_PINID='RFU4';
NET_NAME
'TP_CHF_CPU0_DIMM1_FRU_5'
 '@S9S_MB_2U_LIB.S9S_MB_2U(SCH_1):TP_CHF_CPU0_DIMM1_FRU_5':
 C_SIGNAL='@s9s_mb_2u_lib.s9s_mb_2u(sch_1):tp_chf_cpu0_dimm1_fru_5';
NODE_NAME     J11 231
 '@S9S_MB_2U_LIB.S9S_MB_2U(SCH_1):PAGE92_I25@PURE_QUANTA.SCONN288_ADR50017P130CC(CHIPS)':
 'RFU5': CDS_PINID='RFU5';
NET_NAME
'TP_CHF_CPU0_DIMM1_FRU_6'
 '@S9S_MB_2U_LIB.S9S_MB_2U(SCH_1):TP_CHF_CPU0_DIMM1_FRU_6':
 C_SIGNAL='@s9s_mb_2u_lib.s9s_mb_2u(sch_1):tp_chf_cpu0_dimm1_fru_6';
NODE_NAME     J11 232
 '@S9S_MB_2U_LIB.S9S_MB_2U(SCH_1):PAGE92_I25@PURE_QUANTA.SCONN288_ADR50017P130CC(CHIPS)':
 'RFU6': CDS_PINID='RFU6';
NET_NAME
'TP_CHF_CPU0_DIMM2_FRU_0'
 '@S9S_MB_2U_LIB.S9S_MB_2U(SCH_1):TP_CHF_CPU0_DIMM2_FRU_0':
 C_SIGNAL='@s9s_mb_2u_lib.s9s_mb_2u(sch_1):tp_chf_cpu0_dimm2_fru_0';
NODE_NAME     J12 2
 '@S9S_MB_2U_LIB.S9S_MB_2U(SCH_1):PAGE93_I24@PURE_QUANTA.SCONN288_ADR50017P087CC(CHIPS)':
 'RFU0': CDS_PINID='RFU0';
NET_NAME
'TP_CHF_CPU0_DIMM2_FRU_1'
 '@S9S_MB_2U_LIB.S9S_MB_2U(SCH_1):TP_CHF_CPU0_DIMM2_FRU_1':
 C_SIGNAL='@s9s_mb_2u_lib.s9s_mb_2u(sch_1):tp_chf_cpu0_dimm2_fru_1';
NODE_NAME     J12 144
 '@S9S_MB_2U_LIB.S9S_MB_2U(SCH_1):PAGE93_I24@PURE_QUANTA.SCONN288_ADR50017P087CC(CHIPS)':
 'RFU1': CDS_PINID='RFU1';
NET_NAME
'TP_CHF_CPU0_DIMM2_FRU_2'
 '@S9S_MB_2U_LIB.S9S_MB_2U(SCH_1):TP_CHF_CPU0_DIMM2_FRU_2':
 C_SIGNAL='@s9s_mb_2u_lib.s9s_mb_2u(sch_1):tp_chf_cpu0_dimm2_fru_2';
NODE_NAME     J12 149
 '@S9S_MB_2U_LIB.S9S_MB_2U(SCH_1):PAGE93_I24@PURE_QUANTA.SCONN288_ADR50017P087CC(CHIPS)':
 'RFU2': CDS_PINID='RFU2';
NET_NAME
'TP_CHF_CPU0_DIMM2_FRU_3'
 '@S9S_MB_2U_LIB.S9S_MB_2U(SCH_1):TP_CHF_CPU0_DIMM2_FRU_3':
 C_SIGNAL='@s9s_mb_2u_lib.s9s_mb_2u(sch_1):tp_chf_cpu0_dimm2_fru_3';
NODE_NAME     J12 150
 '@S9S_MB_2U_LIB.S9S_MB_2U(SCH_1):PAGE93_I24@PURE_QUANTA.SCONN288_ADR50017P087CC(CHIPS)':
 'RFU3': CDS_PINID='RFU3';
NET_NAME
'TP_CHF_CPU0_DIMM2_FRU_4'
 '@S9S_MB_2U_LIB.S9S_MB_2U(SCH_1):TP_CHF_CPU0_DIMM2_FRU_4':
 C_SIGNAL='@s9s_mb_2u_lib.s9s_mb_2u(sch_1):tp_chf_cpu0_dimm2_fru_4';
NODE_NAME     J12 220
 '@S9S_MB_2U_LIB.S9S_MB_2U(SCH_1):PAGE93_I24@PURE_QUANTA.SCONN288_ADR50017P087CC(CHIPS)':
 'RFU4': CDS_PINID='RFU4';
NET_NAME
'TP_CHF_CPU0_DIMM2_FRU_5'
 '@S9S_MB_2U_LIB.S9S_MB_2U(SCH_1):TP_CHF_CPU0_DIMM2_FRU_5':
 C_SIGNAL='@s9s_mb_2u_lib.s9s_mb_2u(sch_1):tp_chf_cpu0_dimm2_fru_5';
NODE_NAME     J12 231
 '@S9S_MB_2U_LIB.S9S_MB_2U(SCH_1):PAGE93_I24@PURE_QUANTA.SCONN288_ADR50017P087CC(CHIPS)':
 'RFU5': CDS_PINID='RFU5';
NET_NAME
'TP_CHF_CPU0_DIMM2_FRU_6'
 '@S9S_MB_2U_LIB.S9S_MB_2U(SCH_1):TP_CHF_CPU0_DIMM2_FRU_6':
 C_SIGNAL='@s9s_mb_2u_lib.s9s_mb_2u(sch_1):tp_chf_cpu0_dimm2_fru_6';
NODE_NAME     J12 232
 '@S9S_MB_2U_LIB.S9S_MB_2U(SCH_1):PAGE93_I24@PURE_QUANTA.SCONN288_ADR50017P087CC(CHIPS)':
 'RFU6': CDS_PINID='RFU6';
NET_NAME
'TP_CHF_CPU1_DIMM1_FRU_0'
 '@S9S_MB_2U_LIB.S9S_MB_2U(SCH_1):TP_CHF_CPU1_DIMM1_FRU_0':
 C_SIGNAL='@s9s_mb_2u_lib.s9s_mb_2u(sch_1):tp_chf_cpu1_dimm1_fru_0';
NODE_NAME     J27 2
 '@S9S_MB_2U_LIB.S9S_MB_2U(SCH_1):PAGE108_I179@PURE_QUANTA.SCONN288_ADR50017P130CC(CHIPS)':
 'RFU0': CDS_PINID='RFU0';
NET_NAME
'TP_CHF_CPU1_DIMM1_FRU_1'
 '@S9S_MB_2U_LIB.S9S_MB_2U(SCH_1):TP_CHF_CPU1_DIMM1_FRU_1':
 C_SIGNAL='@s9s_mb_2u_lib.s9s_mb_2u(sch_1):tp_chf_cpu1_dimm1_fru_1';
NODE_NAME     J27 144
 '@S9S_MB_2U_LIB.S9S_MB_2U(SCH_1):PAGE108_I179@PURE_QUANTA.SCONN288_ADR50017P130CC(CHIPS)':
 'RFU1': CDS_PINID='RFU1';
NET_NAME
'TP_CHF_CPU1_DIMM1_FRU_2'
 '@S9S_MB_2U_LIB.S9S_MB_2U(SCH_1):TP_CHF_CPU1_DIMM1_FRU_2':
 C_SIGNAL='@s9s_mb_2u_lib.s9s_mb_2u(sch_1):tp_chf_cpu1_dimm1_fru_2';
NODE_NAME     J27 149
 '@S9S_MB_2U_LIB.S9S_MB_2U(SCH_1):PAGE108_I179@PURE_QUANTA.SCONN288_ADR50017P130CC(CHIPS)':
 'RFU2': CDS_PINID='RFU2';
NET_NAME
'TP_CHF_CPU1_DIMM1_FRU_3'
 '@S9S_MB_2U_LIB.S9S_MB_2U(SCH_1):TP_CHF_CPU1_DIMM1_FRU_3':
 C_SIGNAL='@s9s_mb_2u_lib.s9s_mb_2u(sch_1):tp_chf_cpu1_dimm1_fru_3';
NODE_NAME     J27 150
 '@S9S_MB_2U_LIB.S9S_MB_2U(SCH_1):PAGE108_I179@PURE_QUANTA.SCONN288_ADR50017P130CC(CHIPS)':
 'RFU3': CDS_PINID='RFU3';
NET_NAME
'TP_CHF_CPU1_DIMM1_FRU_4'
 '@S9S_MB_2U_LIB.S9S_MB_2U(SCH_1):TP_CHF_CPU1_DIMM1_FRU_4':
 C_SIGNAL='@s9s_mb_2u_lib.s9s_mb_2u(sch_1):tp_chf_cpu1_dimm1_fru_4';
NODE_NAME     J27 220
 '@S9S_MB_2U_LIB.S9S_MB_2U(SCH_1):PAGE108_I179@PURE_QUANTA.SCONN288_ADR50017P130CC(CHIPS)':
 'RFU4': CDS_PINID='RFU4';
NET_NAME
'TP_CHF_CPU1_DIMM1_FRU_5'
 '@S9S_MB_2U_LIB.S9S_MB_2U(SCH_1):TP_CHF_CPU1_DIMM1_FRU_5':
 C_SIGNAL='@s9s_mb_2u_lib.s9s_mb_2u(sch_1):tp_chf_cpu1_dimm1_fru_5';
NODE_NAME     J27 231
 '@S9S_MB_2U_LIB.S9S_MB_2U(SCH_1):PAGE108_I179@PURE_QUANTA.SCONN288_ADR50017P130CC(CHIPS)':
 'RFU5': CDS_PINID='RFU5';
NET_NAME
'TP_CHF_CPU1_DIMM1_FRU_6'
 '@S9S_MB_2U_LIB.S9S_MB_2U(SCH_1):TP_CHF_CPU1_DIMM1_FRU_6':
 C_SIGNAL='@s9s_mb_2u_lib.s9s_mb_2u(sch_1):tp_chf_cpu1_dimm1_fru_6';
NODE_NAME     J27 232
 '@S9S_MB_2U_LIB.S9S_MB_2U(SCH_1):PAGE108_I179@PURE_QUANTA.SCONN288_ADR50017P130CC(CHIPS)':
 'RFU6': CDS_PINID='RFU6';
NET_NAME
'TP_CHF_CPU1_DIMM2_FRU_0'
 '@S9S_MB_2U_LIB.S9S_MB_2U(SCH_1):TP_CHF_CPU1_DIMM2_FRU_0':
 C_SIGNAL='@s9s_mb_2u_lib.s9s_mb_2u(sch_1):tp_chf_cpu1_dimm2_fru_0';
NODE_NAME     J28 2
 '@S9S_MB_2U_LIB.S9S_MB_2U(SCH_1):PAGE109_I47@PURE_QUANTA.SCONN288_ADR50017P087CC(CHIPS)':
 'RFU0': CDS_PINID='RFU0';
NET_NAME
'TP_CHF_CPU1_DIMM2_FRU_1'
 '@S9S_MB_2U_LIB.S9S_MB_2U(SCH_1):TP_CHF_CPU1_DIMM2_FRU_1':
 C_SIGNAL='@s9s_mb_2u_lib.s9s_mb_2u(sch_1):tp_chf_cpu1_dimm2_fru_1';
NODE_NAME     J28 144
 '@S9S_MB_2U_LIB.S9S_MB_2U(SCH_1):PAGE109_I47@PURE_QUANTA.SCONN288_ADR50017P087CC(CHIPS)':
 'RFU1': CDS_PINID='RFU1';
NET_NAME
'TP_CHF_CPU1_DIMM2_FRU_2'
 '@S9S_MB_2U_LIB.S9S_MB_2U(SCH_1):TP_CHF_CPU1_DIMM2_FRU_2':
 C_SIGNAL='@s9s_mb_2u_lib.s9s_mb_2u(sch_1):tp_chf_cpu1_dimm2_fru_2';
NODE_NAME     J28 149
 '@S9S_MB_2U_LIB.S9S_MB_2U(SCH_1):PAGE109_I47@PURE_QUANTA.SCONN288_ADR50017P087CC(CHIPS)':
 'RFU2': CDS_PINID='RFU2';
NET_NAME
'TP_CHF_CPU1_DIMM2_FRU_3'
 '@S9S_MB_2U_LIB.S9S_MB_2U(SCH_1):TP_CHF_CPU1_DIMM2_FRU_3':
 C_SIGNAL='@s9s_mb_2u_lib.s9s_mb_2u(sch_1):tp_chf_cpu1_dimm2_fru_3';
NODE_NAME     J28 150
 '@S9S_MB_2U_LIB.S9S_MB_2U(SCH_1):PAGE109_I47@PURE_QUANTA.SCONN288_ADR50017P087CC(CHIPS)':
 'RFU3': CDS_PINID='RFU3';
NET_NAME
'TP_CHF_CPU1_DIMM2_FRU_4'
 '@S9S_MB_2U_LIB.S9S_MB_2U(SCH_1):TP_CHF_CPU1_DIMM2_FRU_4':
 C_SIGNAL='@s9s_mb_2u_lib.s9s_mb_2u(sch_1):tp_chf_cpu1_dimm2_fru_4';
NODE_NAME     J28 220
 '@S9S_MB_2U_LIB.S9S_MB_2U(SCH_1):PAGE109_I47@PURE_QUANTA.SCONN288_ADR50017P087CC(CHIPS)':
 'RFU4': CDS_PINID='RFU4';
NET_NAME
'TP_CHF_CPU1_DIMM2_FRU_5'
 '@S9S_MB_2U_LIB.S9S_MB_2U(SCH_1):TP_CHF_CPU1_DIMM2_FRU_5':
 C_SIGNAL='@s9s_mb_2u_lib.s9s_mb_2u(sch_1):tp_chf_cpu1_dimm2_fru_5';
NODE_NAME     J28 231
 '@S9S_MB_2U_LIB.S9S_MB_2U(SCH_1):PAGE109_I47@PURE_QUANTA.SCONN288_ADR50017P087CC(CHIPS)':
 'RFU5': CDS_PINID='RFU5';
NET_NAME
'TP_CHF_CPU1_DIMM2_FRU_6'
 '@S9S_MB_2U_LIB.S9S_MB_2U(SCH_1):TP_CHF_CPU1_DIMM2_FRU_6':
 C_SIGNAL='@s9s_mb_2u_lib.s9s_mb_2u(sch_1):tp_chf_cpu1_dimm2_fru_6';
NODE_NAME     J28 232
 '@S9S_MB_2U_LIB.S9S_MB_2U(SCH_1):PAGE109_I47@PURE_QUANTA.SCONN288_ADR50017P087CC(CHIPS)':
 'RFU6': CDS_PINID='RFU6';
NET_NAME
'TP_CHG_CPU0_DIMM1_FRU_0'
 '@S9S_MB_2U_LIB.S9S_MB_2U(SCH_1):TP_CHG_CPU0_DIMM1_FRU_0':
 C_SIGNAL='@s9s_mb_2u_lib.s9s_mb_2u(sch_1):tp_chg_cpu0_dimm1_fru_0';
NODE_NAME     J13 2
 '@S9S_MB_2U_LIB.S9S_MB_2U(SCH_1):PAGE94_I11@PURE_QUANTA.SCONN288_ADR50017P130CC(CHIPS)':
 'RFU0': CDS_PINID='RFU0';
NET_NAME
'TP_CHG_CPU0_DIMM1_FRU_1'
 '@S9S_MB_2U_LIB.S9S_MB_2U(SCH_1):TP_CHG_CPU0_DIMM1_FRU_1':
 C_SIGNAL='@s9s_mb_2u_lib.s9s_mb_2u(sch_1):tp_chg_cpu0_dimm1_fru_1';
NODE_NAME     J13 144
 '@S9S_MB_2U_LIB.S9S_MB_2U(SCH_1):PAGE94_I11@PURE_QUANTA.SCONN288_ADR50017P130CC(CHIPS)':
 'RFU1': CDS_PINID='RFU1';
NET_NAME
'TP_CHG_CPU0_DIMM1_FRU_2'
 '@S9S_MB_2U_LIB.S9S_MB_2U(SCH_1):TP_CHG_CPU0_DIMM1_FRU_2':
 C_SIGNAL='@s9s_mb_2u_lib.s9s_mb_2u(sch_1):tp_chg_cpu0_dimm1_fru_2';
NODE_NAME     J13 149
 '@S9S_MB_2U_LIB.S9S_MB_2U(SCH_1):PAGE94_I11@PURE_QUANTA.SCONN288_ADR50017P130CC(CHIPS)':
 'RFU2': CDS_PINID='RFU2';
NET_NAME
'TP_CHG_CPU0_DIMM1_FRU_3'
 '@S9S_MB_2U_LIB.S9S_MB_2U(SCH_1):TP_CHG_CPU0_DIMM1_FRU_3':
 C_SIGNAL='@s9s_mb_2u_lib.s9s_mb_2u(sch_1):tp_chg_cpu0_dimm1_fru_3';
NODE_NAME     J13 150
 '@S9S_MB_2U_LIB.S9S_MB_2U(SCH_1):PAGE94_I11@PURE_QUANTA.SCONN288_ADR50017P130CC(CHIPS)':
 'RFU3': CDS_PINID='RFU3';
NET_NAME
'TP_CHG_CPU0_DIMM1_FRU_4'
 '@S9S_MB_2U_LIB.S9S_MB_2U(SCH_1):TP_CHG_CPU0_DIMM1_FRU_4':
 C_SIGNAL='@s9s_mb_2u_lib.s9s_mb_2u(sch_1):tp_chg_cpu0_dimm1_fru_4';
NODE_NAME     J13 220
 '@S9S_MB_2U_LIB.S9S_MB_2U(SCH_1):PAGE94_I11@PURE_QUANTA.SCONN288_ADR50017P130CC(CHIPS)':
 'RFU4': CDS_PINID='RFU4';
NET_NAME
'TP_CHG_CPU0_DIMM1_FRU_5'
 '@S9S_MB_2U_LIB.S9S_MB_2U(SCH_1):TP_CHG_CPU0_DIMM1_FRU_5':
 C_SIGNAL='@s9s_mb_2u_lib.s9s_mb_2u(sch_1):tp_chg_cpu0_dimm1_fru_5';
NODE_NAME     J13 231
 '@S9S_MB_2U_LIB.S9S_MB_2U(SCH_1):PAGE94_I11@PURE_QUANTA.SCONN288_ADR50017P130CC(CHIPS)':
 'RFU5': CDS_PINID='RFU5';
NET_NAME
'TP_CHG_CPU0_DIMM1_FRU_6'
 '@S9S_MB_2U_LIB.S9S_MB_2U(SCH_1):TP_CHG_CPU0_DIMM1_FRU_6':
 C_SIGNAL='@s9s_mb_2u_lib.s9s_mb_2u(sch_1):tp_chg_cpu0_dimm1_fru_6';
NODE_NAME     J13 232
 '@S9S_MB_2U_LIB.S9S_MB_2U(SCH_1):PAGE94_I11@PURE_QUANTA.SCONN288_ADR50017P130CC(CHIPS)':
 'RFU6': CDS_PINID='RFU6';
NET_NAME
'TP_CHG_CPU0_DIMM2_FRU_0'
 '@S9S_MB_2U_LIB.S9S_MB_2U(SCH_1):TP_CHG_CPU0_DIMM2_FRU_0':
 C_SIGNAL='@s9s_mb_2u_lib.s9s_mb_2u(sch_1):tp_chg_cpu0_dimm2_fru_0';
NODE_NAME     J14 2
 '@S9S_MB_2U_LIB.S9S_MB_2U(SCH_1):PAGE95_I47@PURE_QUANTA.SCONN288_ADR50017P087CC(CHIPS)':
 'RFU0': CDS_PINID='RFU0';
NET_NAME
'TP_CHG_CPU0_DIMM2_FRU_1'
 '@S9S_MB_2U_LIB.S9S_MB_2U(SCH_1):TP_CHG_CPU0_DIMM2_FRU_1':
 C_SIGNAL='@s9s_mb_2u_lib.s9s_mb_2u(sch_1):tp_chg_cpu0_dimm2_fru_1';
NODE_NAME     J14 144
 '@S9S_MB_2U_LIB.S9S_MB_2U(SCH_1):PAGE95_I47@PURE_QUANTA.SCONN288_ADR50017P087CC(CHIPS)':
 'RFU1': CDS_PINID='RFU1';
NET_NAME
'TP_CHG_CPU0_DIMM2_FRU_2'
 '@S9S_MB_2U_LIB.S9S_MB_2U(SCH_1):TP_CHG_CPU0_DIMM2_FRU_2':
 C_SIGNAL='@s9s_mb_2u_lib.s9s_mb_2u(sch_1):tp_chg_cpu0_dimm2_fru_2';
NODE_NAME     J14 149
 '@S9S_MB_2U_LIB.S9S_MB_2U(SCH_1):PAGE95_I47@PURE_QUANTA.SCONN288_ADR50017P087CC(CHIPS)':
 'RFU2': CDS_PINID='RFU2';
NET_NAME
'TP_CHG_CPU0_DIMM2_FRU_3'
 '@S9S_MB_2U_LIB.S9S_MB_2U(SCH_1):TP_CHG_CPU0_DIMM2_FRU_3':
 C_SIGNAL='@s9s_mb_2u_lib.s9s_mb_2u(sch_1):tp_chg_cpu0_dimm2_fru_3';
NODE_NAME     J14 150
 '@S9S_MB_2U_LIB.S9S_MB_2U(SCH_1):PAGE95_I47@PURE_QUANTA.SCONN288_ADR50017P087CC(CHIPS)':
 'RFU3': CDS_PINID='RFU3';
NET_NAME
'TP_CHG_CPU0_DIMM2_FRU_4'
 '@S9S_MB_2U_LIB.S9S_MB_2U(SCH_1):TP_CHG_CPU0_DIMM2_FRU_4':
 C_SIGNAL='@s9s_mb_2u_lib.s9s_mb_2u(sch_1):tp_chg_cpu0_dimm2_fru_4';
NODE_NAME     J14 220
 '@S9S_MB_2U_LIB.S9S_MB_2U(SCH_1):PAGE95_I47@PURE_QUANTA.SCONN288_ADR50017P087CC(CHIPS)':
 'RFU4': CDS_PINID='RFU4';
NET_NAME
'TP_CHG_CPU0_DIMM2_FRU_5'
 '@S9S_MB_2U_LIB.S9S_MB_2U(SCH_1):TP_CHG_CPU0_DIMM2_FRU_5':
 C_SIGNAL='@s9s_mb_2u_lib.s9s_mb_2u(sch_1):tp_chg_cpu0_dimm2_fru_5';
NODE_NAME     J14 231
 '@S9S_MB_2U_LIB.S9S_MB_2U(SCH_1):PAGE95_I47@PURE_QUANTA.SCONN288_ADR50017P087CC(CHIPS)':
 'RFU5': CDS_PINID='RFU5';
NET_NAME
'TP_CHG_CPU0_DIMM2_FRU_6'
 '@S9S_MB_2U_LIB.S9S_MB_2U(SCH_1):TP_CHG_CPU0_DIMM2_FRU_6':
 C_SIGNAL='@s9s_mb_2u_lib.s9s_mb_2u(sch_1):tp_chg_cpu0_dimm2_fru_6';
NODE_NAME     J14 232
 '@S9S_MB_2U_LIB.S9S_MB_2U(SCH_1):PAGE95_I47@PURE_QUANTA.SCONN288_ADR50017P087CC(CHIPS)':
 'RFU6': CDS_PINID='RFU6';
NET_NAME
'TP_CHG_CPU1_DIMM1_FRU_0'
 '@S9S_MB_2U_LIB.S9S_MB_2U(SCH_1):TP_CHG_CPU1_DIMM1_FRU_0':
 C_SIGNAL='@s9s_mb_2u_lib.s9s_mb_2u(sch_1):tp_chg_cpu1_dimm1_fru_0';
NODE_NAME     J29 2
 '@S9S_MB_2U_LIB.S9S_MB_2U(SCH_1):PAGE110_I179@PURE_QUANTA.SCONN288_ADR50017P130CC(CHIPS)':
 'RFU0': CDS_PINID='RFU0';
NET_NAME
'TP_CHG_CPU1_DIMM1_FRU_1'
 '@S9S_MB_2U_LIB.S9S_MB_2U(SCH_1):TP_CHG_CPU1_DIMM1_FRU_1':
 C_SIGNAL='@s9s_mb_2u_lib.s9s_mb_2u(sch_1):tp_chg_cpu1_dimm1_fru_1';
NODE_NAME     J29 144
 '@S9S_MB_2U_LIB.S9S_MB_2U(SCH_1):PAGE110_I179@PURE_QUANTA.SCONN288_ADR50017P130CC(CHIPS)':
 'RFU1': CDS_PINID='RFU1';
NET_NAME
'TP_CHG_CPU1_DIMM1_FRU_2'
 '@S9S_MB_2U_LIB.S9S_MB_2U(SCH_1):TP_CHG_CPU1_DIMM1_FRU_2':
 C_SIGNAL='@s9s_mb_2u_lib.s9s_mb_2u(sch_1):tp_chg_cpu1_dimm1_fru_2';
NODE_NAME     J29 149
 '@S9S_MB_2U_LIB.S9S_MB_2U(SCH_1):PAGE110_I179@PURE_QUANTA.SCONN288_ADR50017P130CC(CHIPS)':
 'RFU2': CDS_PINID='RFU2';
NET_NAME
'TP_CHG_CPU1_DIMM1_FRU_3'
 '@S9S_MB_2U_LIB.S9S_MB_2U(SCH_1):TP_CHG_CPU1_DIMM1_FRU_3':
 C_SIGNAL='@s9s_mb_2u_lib.s9s_mb_2u(sch_1):tp_chg_cpu1_dimm1_fru_3';
NODE_NAME     J29 150
 '@S9S_MB_2U_LIB.S9S_MB_2U(SCH_1):PAGE110_I179@PURE_QUANTA.SCONN288_ADR50017P130CC(CHIPS)':
 'RFU3': CDS_PINID='RFU3';
NET_NAME
'TP_CHG_CPU1_DIMM1_FRU_4'
 '@S9S_MB_2U_LIB.S9S_MB_2U(SCH_1):TP_CHG_CPU1_DIMM1_FRU_4':
 C_SIGNAL='@s9s_mb_2u_lib.s9s_mb_2u(sch_1):tp_chg_cpu1_dimm1_fru_4';
NODE_NAME     J29 220
 '@S9S_MB_2U_LIB.S9S_MB_2U(SCH_1):PAGE110_I179@PURE_QUANTA.SCONN288_ADR50017P130CC(CHIPS)':
 'RFU4': CDS_PINID='RFU4';
NET_NAME
'TP_CHG_CPU1_DIMM1_FRU_5'
 '@S9S_MB_2U_LIB.S9S_MB_2U(SCH_1):TP_CHG_CPU1_DIMM1_FRU_5':
 C_SIGNAL='@s9s_mb_2u_lib.s9s_mb_2u(sch_1):tp_chg_cpu1_dimm1_fru_5';
NODE_NAME     J29 231
 '@S9S_MB_2U_LIB.S9S_MB_2U(SCH_1):PAGE110_I179@PURE_QUANTA.SCONN288_ADR50017P130CC(CHIPS)':
 'RFU5': CDS_PINID='RFU5';
NET_NAME
'TP_CHG_CPU1_DIMM1_FRU_6'
 '@S9S_MB_2U_LIB.S9S_MB_2U(SCH_1):TP_CHG_CPU1_DIMM1_FRU_6':
 C_SIGNAL='@s9s_mb_2u_lib.s9s_mb_2u(sch_1):tp_chg_cpu1_dimm1_fru_6';
NODE_NAME     J29 232
 '@S9S_MB_2U_LIB.S9S_MB_2U(SCH_1):PAGE110_I179@PURE_QUANTA.SCONN288_ADR50017P130CC(CHIPS)':
 'RFU6': CDS_PINID='RFU6';
NET_NAME
'TP_CHG_CPU1_DIMM2_FRU_0'
 '@S9S_MB_2U_LIB.S9S_MB_2U(SCH_1):TP_CHG_CPU1_DIMM2_FRU_0':
 C_SIGNAL='@s9s_mb_2u_lib.s9s_mb_2u(sch_1):tp_chg_cpu1_dimm2_fru_0';
NODE_NAME     J30 2
 '@S9S_MB_2U_LIB.S9S_MB_2U(SCH_1):PAGE111_I179@PURE_QUANTA.SCONN288_ADR50017P087CC(CHIPS)':
 'RFU0': CDS_PINID='RFU0';
NET_NAME
'TP_CHG_CPU1_DIMM2_FRU_1'
 '@S9S_MB_2U_LIB.S9S_MB_2U(SCH_1):TP_CHG_CPU1_DIMM2_FRU_1':
 C_SIGNAL='@s9s_mb_2u_lib.s9s_mb_2u(sch_1):tp_chg_cpu1_dimm2_fru_1';
NODE_NAME     J30 144
 '@S9S_MB_2U_LIB.S9S_MB_2U(SCH_1):PAGE111_I179@PURE_QUANTA.SCONN288_ADR50017P087CC(CHIPS)':
 'RFU1': CDS_PINID='RFU1';
NET_NAME
'TP_CHG_CPU1_DIMM2_FRU_2'
 '@S9S_MB_2U_LIB.S9S_MB_2U(SCH_1):TP_CHG_CPU1_DIMM2_FRU_2':
 C_SIGNAL='@s9s_mb_2u_lib.s9s_mb_2u(sch_1):tp_chg_cpu1_dimm2_fru_2';
NODE_NAME     J30 149
 '@S9S_MB_2U_LIB.S9S_MB_2U(SCH_1):PAGE111_I179@PURE_QUANTA.SCONN288_ADR50017P087CC(CHIPS)':
 'RFU2': CDS_PINID='RFU2';
NET_NAME
'TP_CHG_CPU1_DIMM2_FRU_3'
 '@S9S_MB_2U_LIB.S9S_MB_2U(SCH_1):TP_CHG_CPU1_DIMM2_FRU_3':
 C_SIGNAL='@s9s_mb_2u_lib.s9s_mb_2u(sch_1):tp_chg_cpu1_dimm2_fru_3';
NODE_NAME     J30 150
 '@S9S_MB_2U_LIB.S9S_MB_2U(SCH_1):PAGE111_I179@PURE_QUANTA.SCONN288_ADR50017P087CC(CHIPS)':
 'RFU3': CDS_PINID='RFU3';
NET_NAME
'TP_CHG_CPU1_DIMM2_FRU_4'
 '@S9S_MB_2U_LIB.S9S_MB_2U(SCH_1):TP_CHG_CPU1_DIMM2_FRU_4':
 C_SIGNAL='@s9s_mb_2u_lib.s9s_mb_2u(sch_1):tp_chg_cpu1_dimm2_fru_4';
NODE_NAME     J30 220
 '@S9S_MB_2U_LIB.S9S_MB_2U(SCH_1):PAGE111_I179@PURE_QUANTA.SCONN288_ADR50017P087CC(CHIPS)':
 'RFU4': CDS_PINID='RFU4';
NET_NAME
'TP_CHG_CPU1_DIMM2_FRU_5'
 '@S9S_MB_2U_LIB.S9S_MB_2U(SCH_1):TP_CHG_CPU1_DIMM2_FRU_5':
 C_SIGNAL='@s9s_mb_2u_lib.s9s_mb_2u(sch_1):tp_chg_cpu1_dimm2_fru_5';
NODE_NAME     J30 231
 '@S9S_MB_2U_LIB.S9S_MB_2U(SCH_1):PAGE111_I179@PURE_QUANTA.SCONN288_ADR50017P087CC(CHIPS)':
 'RFU5': CDS_PINID='RFU5';
NET_NAME
'TP_CHG_CPU1_DIMM2_FRU_6'
 '@S9S_MB_2U_LIB.S9S_MB_2U(SCH_1):TP_CHG_CPU1_DIMM2_FRU_6':
 C_SIGNAL='@s9s_mb_2u_lib.s9s_mb_2u(sch_1):tp_chg_cpu1_dimm2_fru_6';
NODE_NAME     J30 232
 '@S9S_MB_2U_LIB.S9S_MB_2U(SCH_1):PAGE111_I179@PURE_QUANTA.SCONN288_ADR50017P087CC(CHIPS)':
 'RFU6': CDS_PINID='RFU6';
NET_NAME
'TP_CHH_CPU0_DIMM1_FRU_0'
 '@S9S_MB_2U_LIB.S9S_MB_2U(SCH_1):TP_CHH_CPU0_DIMM1_FRU_0':
 C_SIGNAL='@s9s_mb_2u_lib.s9s_mb_2u(sch_1):tp_chh_cpu0_dimm1_fru_0';
NODE_NAME     J15 2
 '@S9S_MB_2U_LIB.S9S_MB_2U(SCH_1):PAGE96_I48@PURE_QUANTA.SCONN288_ADR50017P130CC(CHIPS)':
 'RFU0': CDS_PINID='RFU0';
NET_NAME
'TP_CHH_CPU0_DIMM1_FRU_1'
 '@S9S_MB_2U_LIB.S9S_MB_2U(SCH_1):TP_CHH_CPU0_DIMM1_FRU_1':
 C_SIGNAL='@s9s_mb_2u_lib.s9s_mb_2u(sch_1):tp_chh_cpu0_dimm1_fru_1';
NODE_NAME     J15 144
 '@S9S_MB_2U_LIB.S9S_MB_2U(SCH_1):PAGE96_I48@PURE_QUANTA.SCONN288_ADR50017P130CC(CHIPS)':
 'RFU1': CDS_PINID='RFU1';
NET_NAME
'TP_CHH_CPU0_DIMM1_FRU_2'
 '@S9S_MB_2U_LIB.S9S_MB_2U(SCH_1):TP_CHH_CPU0_DIMM1_FRU_2':
 C_SIGNAL='@s9s_mb_2u_lib.s9s_mb_2u(sch_1):tp_chh_cpu0_dimm1_fru_2';
NODE_NAME     J15 149
 '@S9S_MB_2U_LIB.S9S_MB_2U(SCH_1):PAGE96_I48@PURE_QUANTA.SCONN288_ADR50017P130CC(CHIPS)':
 'RFU2': CDS_PINID='RFU2';
NET_NAME
'TP_CHH_CPU0_DIMM1_FRU_3'
 '@S9S_MB_2U_LIB.S9S_MB_2U(SCH_1):TP_CHH_CPU0_DIMM1_FRU_3':
 C_SIGNAL='@s9s_mb_2u_lib.s9s_mb_2u(sch_1):tp_chh_cpu0_dimm1_fru_3';
NODE_NAME     J15 150
 '@S9S_MB_2U_LIB.S9S_MB_2U(SCH_1):PAGE96_I48@PURE_QUANTA.SCONN288_ADR50017P130CC(CHIPS)':
 'RFU3': CDS_PINID='RFU3';
NET_NAME
'TP_CHH_CPU0_DIMM1_FRU_4'
 '@S9S_MB_2U_LIB.S9S_MB_2U(SCH_1):TP_CHH_CPU0_DIMM1_FRU_4':
 C_SIGNAL='@s9s_mb_2u_lib.s9s_mb_2u(sch_1):tp_chh_cpu0_dimm1_fru_4';
NODE_NAME     J15 220
 '@S9S_MB_2U_LIB.S9S_MB_2U(SCH_1):PAGE96_I48@PURE_QUANTA.SCONN288_ADR50017P130CC(CHIPS)':
 'RFU4': CDS_PINID='RFU4';
NET_NAME
'TP_CHH_CPU0_DIMM1_FRU_5'
 '@S9S_MB_2U_LIB.S9S_MB_2U(SCH_1):TP_CHH_CPU0_DIMM1_FRU_5':
 C_SIGNAL='@s9s_mb_2u_lib.s9s_mb_2u(sch_1):tp_chh_cpu0_dimm1_fru_5';
NODE_NAME     J15 231
 '@S9S_MB_2U_LIB.S9S_MB_2U(SCH_1):PAGE96_I48@PURE_QUANTA.SCONN288_ADR50017P130CC(CHIPS)':
 'RFU5': CDS_PINID='RFU5';
NET_NAME
'TP_CHH_CPU0_DIMM1_FRU_6'
 '@S9S_MB_2U_LIB.S9S_MB_2U(SCH_1):TP_CHH_CPU0_DIMM1_FRU_6':
 C_SIGNAL='@s9s_mb_2u_lib.s9s_mb_2u(sch_1):tp_chh_cpu0_dimm1_fru_6';
NODE_NAME     J15 232
 '@S9S_MB_2U_LIB.S9S_MB_2U(SCH_1):PAGE96_I48@PURE_QUANTA.SCONN288_ADR50017P130CC(CHIPS)':
 'RFU6': CDS_PINID='RFU6';
NET_NAME
'TP_CHH_CPU0_DIMM2_FRU_0'
 '@S9S_MB_2U_LIB.S9S_MB_2U(SCH_1):TP_CHH_CPU0_DIMM2_FRU_0':
 C_SIGNAL='@s9s_mb_2u_lib.s9s_mb_2u(sch_1):tp_chh_cpu0_dimm2_fru_0';
NODE_NAME     J16 2
 '@S9S_MB_2U_LIB.S9S_MB_2U(SCH_1):PAGE97_I6@PURE_QUANTA.SCONN288_ADR50017P087CC(CHIPS)':
 'RFU0': CDS_PINID='RFU0';
NET_NAME
'TP_CHH_CPU0_DIMM2_FRU_1'
 '@S9S_MB_2U_LIB.S9S_MB_2U(SCH_1):TP_CHH_CPU0_DIMM2_FRU_1':
 C_SIGNAL='@s9s_mb_2u_lib.s9s_mb_2u(sch_1):tp_chh_cpu0_dimm2_fru_1';
NODE_NAME     J16 144
 '@S9S_MB_2U_LIB.S9S_MB_2U(SCH_1):PAGE97_I6@PURE_QUANTA.SCONN288_ADR50017P087CC(CHIPS)':
 'RFU1': CDS_PINID='RFU1';
NET_NAME
'TP_CHH_CPU0_DIMM2_FRU_2'
 '@S9S_MB_2U_LIB.S9S_MB_2U(SCH_1):TP_CHH_CPU0_DIMM2_FRU_2':
 C_SIGNAL='@s9s_mb_2u_lib.s9s_mb_2u(sch_1):tp_chh_cpu0_dimm2_fru_2';
NODE_NAME     J16 149
 '@S9S_MB_2U_LIB.S9S_MB_2U(SCH_1):PAGE97_I6@PURE_QUANTA.SCONN288_ADR50017P087CC(CHIPS)':
 'RFU2': CDS_PINID='RFU2';
NET_NAME
'TP_CHH_CPU0_DIMM2_FRU_3'
 '@S9S_MB_2U_LIB.S9S_MB_2U(SCH_1):TP_CHH_CPU0_DIMM2_FRU_3':
 C_SIGNAL='@s9s_mb_2u_lib.s9s_mb_2u(sch_1):tp_chh_cpu0_dimm2_fru_3';
NODE_NAME     J16 150
 '@S9S_MB_2U_LIB.S9S_MB_2U(SCH_1):PAGE97_I6@PURE_QUANTA.SCONN288_ADR50017P087CC(CHIPS)':
 'RFU3': CDS_PINID='RFU3';
NET_NAME
'TP_CHH_CPU0_DIMM2_FRU_4'
 '@S9S_MB_2U_LIB.S9S_MB_2U(SCH_1):TP_CHH_CPU0_DIMM2_FRU_4':
 C_SIGNAL='@s9s_mb_2u_lib.s9s_mb_2u(sch_1):tp_chh_cpu0_dimm2_fru_4';
NODE_NAME     J16 220
 '@S9S_MB_2U_LIB.S9S_MB_2U(SCH_1):PAGE97_I6@PURE_QUANTA.SCONN288_ADR50017P087CC(CHIPS)':
 'RFU4': CDS_PINID='RFU4';
NET_NAME
'TP_CHH_CPU0_DIMM2_FRU_5'
 '@S9S_MB_2U_LIB.S9S_MB_2U(SCH_1):TP_CHH_CPU0_DIMM2_FRU_5':
 C_SIGNAL='@s9s_mb_2u_lib.s9s_mb_2u(sch_1):tp_chh_cpu0_dimm2_fru_5';
NODE_NAME     J16 231
 '@S9S_MB_2U_LIB.S9S_MB_2U(SCH_1):PAGE97_I6@PURE_QUANTA.SCONN288_ADR50017P087CC(CHIPS)':
 'RFU5': CDS_PINID='RFU5';
NET_NAME
'TP_CHH_CPU0_DIMM2_FRU_6'
 '@S9S_MB_2U_LIB.S9S_MB_2U(SCH_1):TP_CHH_CPU0_DIMM2_FRU_6':
 C_SIGNAL='@s9s_mb_2u_lib.s9s_mb_2u(sch_1):tp_chh_cpu0_dimm2_fru_6';
NODE_NAME     J16 232
 '@S9S_MB_2U_LIB.S9S_MB_2U(SCH_1):PAGE97_I6@PURE_QUANTA.SCONN288_ADR50017P087CC(CHIPS)':
 'RFU6': CDS_PINID='RFU6';
NET_NAME
'TP_CHH_CPU1_DIMM1_FRU_0'
 '@S9S_MB_2U_LIB.S9S_MB_2U(SCH_1):TP_CHH_CPU1_DIMM1_FRU_0':
 C_SIGNAL='@s9s_mb_2u_lib.s9s_mb_2u(sch_1):tp_chh_cpu1_dimm1_fru_0';
NODE_NAME     J31 2
 '@S9S_MB_2U_LIB.S9S_MB_2U(SCH_1):PAGE112_I180@PURE_QUANTA.SCONN288_ADR50017P130CC(CHIPS)':
 'RFU0': CDS_PINID='RFU0';
NET_NAME
'TP_CHH_CPU1_DIMM1_FRU_1'
 '@S9S_MB_2U_LIB.S9S_MB_2U(SCH_1):TP_CHH_CPU1_DIMM1_FRU_1':
 C_SIGNAL='@s9s_mb_2u_lib.s9s_mb_2u(sch_1):tp_chh_cpu1_dimm1_fru_1';
NODE_NAME     J31 144
 '@S9S_MB_2U_LIB.S9S_MB_2U(SCH_1):PAGE112_I180@PURE_QUANTA.SCONN288_ADR50017P130CC(CHIPS)':
 'RFU1': CDS_PINID='RFU1';
NET_NAME
'TP_CHH_CPU1_DIMM1_FRU_2'
 '@S9S_MB_2U_LIB.S9S_MB_2U(SCH_1):TP_CHH_CPU1_DIMM1_FRU_2':
 C_SIGNAL='@s9s_mb_2u_lib.s9s_mb_2u(sch_1):tp_chh_cpu1_dimm1_fru_2';
NODE_NAME     J31 149
 '@S9S_MB_2U_LIB.S9S_MB_2U(SCH_1):PAGE112_I180@PURE_QUANTA.SCONN288_ADR50017P130CC(CHIPS)':
 'RFU2': CDS_PINID='RFU2';
NET_NAME
'TP_CHH_CPU1_DIMM1_FRU_3'
 '@S9S_MB_2U_LIB.S9S_MB_2U(SCH_1):TP_CHH_CPU1_DIMM1_FRU_3':
 C_SIGNAL='@s9s_mb_2u_lib.s9s_mb_2u(sch_1):tp_chh_cpu1_dimm1_fru_3';
NODE_NAME     J31 150
 '@S9S_MB_2U_LIB.S9S_MB_2U(SCH_1):PAGE112_I180@PURE_QUANTA.SCONN288_ADR50017P130CC(CHIPS)':
 'RFU3': CDS_PINID='RFU3';
NET_NAME
'TP_CHH_CPU1_DIMM1_FRU_4'
 '@S9S_MB_2U_LIB.S9S_MB_2U(SCH_1):TP_CHH_CPU1_DIMM1_FRU_4':
 C_SIGNAL='@s9s_mb_2u_lib.s9s_mb_2u(sch_1):tp_chh_cpu1_dimm1_fru_4';
NODE_NAME     J31 220
 '@S9S_MB_2U_LIB.S9S_MB_2U(SCH_1):PAGE112_I180@PURE_QUANTA.SCONN288_ADR50017P130CC(CHIPS)':
 'RFU4': CDS_PINID='RFU4';
NET_NAME
'TP_CHH_CPU1_DIMM1_FRU_5'
 '@S9S_MB_2U_LIB.S9S_MB_2U(SCH_1):TP_CHH_CPU1_DIMM1_FRU_5':
 C_SIGNAL='@s9s_mb_2u_lib.s9s_mb_2u(sch_1):tp_chh_cpu1_dimm1_fru_5';
NODE_NAME     J31 231
 '@S9S_MB_2U_LIB.S9S_MB_2U(SCH_1):PAGE112_I180@PURE_QUANTA.SCONN288_ADR50017P130CC(CHIPS)':
 'RFU5': CDS_PINID='RFU5';
NET_NAME
'TP_CHH_CPU1_DIMM1_FRU_6'
 '@S9S_MB_2U_LIB.S9S_MB_2U(SCH_1):TP_CHH_CPU1_DIMM1_FRU_6':
 C_SIGNAL='@s9s_mb_2u_lib.s9s_mb_2u(sch_1):tp_chh_cpu1_dimm1_fru_6';
NODE_NAME     J31 232
 '@S9S_MB_2U_LIB.S9S_MB_2U(SCH_1):PAGE112_I180@PURE_QUANTA.SCONN288_ADR50017P130CC(CHIPS)':
 'RFU6': CDS_PINID='RFU6';
NET_NAME
'TP_CHH_CPU1_DIMM2_FRU_0'
 '@S9S_MB_2U_LIB.S9S_MB_2U(SCH_1):TP_CHH_CPU1_DIMM2_FRU_0':
 C_SIGNAL='@s9s_mb_2u_lib.s9s_mb_2u(sch_1):tp_chh_cpu1_dimm2_fru_0';
NODE_NAME     J32 2
 '@S9S_MB_2U_LIB.S9S_MB_2U(SCH_1):PAGE113_I179@PURE_QUANTA.SCONN288_ADR50017P087CC(CHIPS)':
 'RFU0': CDS_PINID='RFU0';
NET_NAME
'TP_CHH_CPU1_DIMM2_FRU_1'
 '@S9S_MB_2U_LIB.S9S_MB_2U(SCH_1):TP_CHH_CPU1_DIMM2_FRU_1':
 C_SIGNAL='@s9s_mb_2u_lib.s9s_mb_2u(sch_1):tp_chh_cpu1_dimm2_fru_1';
NODE_NAME     J32 144
 '@S9S_MB_2U_LIB.S9S_MB_2U(SCH_1):PAGE113_I179@PURE_QUANTA.SCONN288_ADR50017P087CC(CHIPS)':
 'RFU1': CDS_PINID='RFU1';
NET_NAME
'TP_CHH_CPU1_DIMM2_FRU_2'
 '@S9S_MB_2U_LIB.S9S_MB_2U(SCH_1):TP_CHH_CPU1_DIMM2_FRU_2':
 C_SIGNAL='@s9s_mb_2u_lib.s9s_mb_2u(sch_1):tp_chh_cpu1_dimm2_fru_2';
NODE_NAME     J32 149
 '@S9S_MB_2U_LIB.S9S_MB_2U(SCH_1):PAGE113_I179@PURE_QUANTA.SCONN288_ADR50017P087CC(CHIPS)':
 'RFU2': CDS_PINID='RFU2';
NET_NAME
'TP_CHH_CPU1_DIMM2_FRU_3'
 '@S9S_MB_2U_LIB.S9S_MB_2U(SCH_1):TP_CHH_CPU1_DIMM2_FRU_3':
 C_SIGNAL='@s9s_mb_2u_lib.s9s_mb_2u(sch_1):tp_chh_cpu1_dimm2_fru_3';
NODE_NAME     J32 150
 '@S9S_MB_2U_LIB.S9S_MB_2U(SCH_1):PAGE113_I179@PURE_QUANTA.SCONN288_ADR50017P087CC(CHIPS)':
 'RFU3': CDS_PINID='RFU3';
NET_NAME
'TP_CHH_CPU1_DIMM2_FRU_4'
 '@S9S_MB_2U_LIB.S9S_MB_2U(SCH_1):TP_CHH_CPU1_DIMM2_FRU_4':
 C_SIGNAL='@s9s_mb_2u_lib.s9s_mb_2u(sch_1):tp_chh_cpu1_dimm2_fru_4';
NODE_NAME     J32 220
 '@S9S_MB_2U_LIB.S9S_MB_2U(SCH_1):PAGE113_I179@PURE_QUANTA.SCONN288_ADR50017P087CC(CHIPS)':
 'RFU4': CDS_PINID='RFU4';
NET_NAME
'TP_CHH_CPU1_DIMM2_FRU_5'
 '@S9S_MB_2U_LIB.S9S_MB_2U(SCH_1):TP_CHH_CPU1_DIMM2_FRU_5':
 C_SIGNAL='@s9s_mb_2u_lib.s9s_mb_2u(sch_1):tp_chh_cpu1_dimm2_fru_5';
NODE_NAME     J32 231
 '@S9S_MB_2U_LIB.S9S_MB_2U(SCH_1):PAGE113_I179@PURE_QUANTA.SCONN288_ADR50017P087CC(CHIPS)':
 'RFU5': CDS_PINID='RFU5';
NET_NAME
'TP_CHH_CPU1_DIMM2_FRU_6'
 '@S9S_MB_2U_LIB.S9S_MB_2U(SCH_1):TP_CHH_CPU1_DIMM2_FRU_6':
 C_SIGNAL='@s9s_mb_2u_lib.s9s_mb_2u(sch_1):tp_chh_cpu1_dimm2_fru_6';
NODE_NAME     J32 232
 '@S9S_MB_2U_LIB.S9S_MB_2U(SCH_1):PAGE113_I179@PURE_QUANTA.SCONN288_ADR50017P087CC(CHIPS)':
 'RFU6': CDS_PINID='RFU6';
NET_NAME
'TP_CK440_SBI_DATA_OUT'
 '@S9S_MB_2U_LIB.S9S_MB_2U(SCH_1):TP_CK440_SBI_DATA_OUT':
 C_SIGNAL='@s9s_mb_2u_lib.s9s_mb_2u(sch_1):tp_ck440_sbi_data_out';
NODE_NAME     U13 A53
 '@S9S_MB_2U_LIB.S9S_MB_2U(SCH_1):PAGE197_I180@PURE_QUANTA.9SQ440NQQI8(CHIPS)':
 'SBI_OUT': CDS_PINID='SBI_OUT';
NET_NAME
'TP_CLK_100M_BUF_DIF3_DN'
 '@S9S_MB_2U_LIB.S9S_MB_2U(SCH_1):TP_CLK_100M_BUF_DIF3_DN':
 C_SIGNAL='@s9s_mb_2u_lib.s9s_mb_2u(sch_1):tp_clk_100m_buf_dif3_dn';
NODE_NAME     U314 28
 '@S9S_MB_2U_LIB.S9S_MB_2U(SCH_1):PAGE200_I1@PURE_QUANTA.9ZXL0451EKILFT(CHIPS)':
 'DIF3#': CDS_PINID='\dif3#\';
NET_NAME
'TP_CLK_100M_BUF_DIF3_DP'
 '@S9S_MB_2U_LIB.S9S_MB_2U(SCH_1):TP_CLK_100M_BUF_DIF3_DP':
 C_SIGNAL='@s9s_mb_2u_lib.s9s_mb_2u(sch_1):tp_clk_100m_buf_dif3_dp';
NODE_NAME     U314 27
 '@S9S_MB_2U_LIB.S9S_MB_2U(SCH_1):PAGE200_I1@PURE_QUANTA.9ZXL0451EKILFT(CHIPS)':
 'DIF3': CDS_PINID='DIF3';
NET_NAME
'TP_CLK_100M_DIF13_DN'
 '@S9S_MB_2U_LIB.S9S_MB_2U(SCH_1):TP_CLK_100M_DIF13_DN':
 C_SIGNAL='@s9s_mb_2u_lib.s9s_mb_2u(sch_1):tp_clk_100m_dif13_dn';
NODE_NAME     U38 A8
 '@S9S_MB_2U_LIB.S9S_MB_2U(SCH_1):PAGE195_I119@PURE_QUANTA.9QXL2001BNHGI8(CHIPS)':
 'DIF13#': CDS_PINID='\dif13#\';
NET_NAME
'TP_CLK_100M_DIF13_DP'
 '@S9S_MB_2U_LIB.S9S_MB_2U(SCH_1):TP_CLK_100M_DIF13_DP':
 C_SIGNAL='@s9s_mb_2u_lib.s9s_mb_2u(sch_1):tp_clk_100m_dif13_dp';
NODE_NAME     U38 A9
 '@S9S_MB_2U_LIB.S9S_MB_2U(SCH_1):PAGE195_I119@PURE_QUANTA.9QXL2001BNHGI8(CHIPS)':
 'DIF13': CDS_PINID='DIF13';
NET_NAME
'TP_CLK_100M_DIF18_DN'
 '@S9S_MB_2U_LIB.S9S_MB_2U(SCH_1):TP_CLK_100M_DIF18_DN':
 C_SIGNAL='@s9s_mb_2u_lib.s9s_mb_2u(sch_1):tp_clk_100m_dif18_dn';
NODE_NAME     U38 D1
 '@S9S_MB_2U_LIB.S9S_MB_2U(SCH_1):PAGE195_I119@PURE_QUANTA.9QXL2001BNHGI8(CHIPS)':
 'DIF18#': CDS_PINID='\dif18#\';
NET_NAME
'TP_CLK_100M_DIF18_DP'
 '@S9S_MB_2U_LIB.S9S_MB_2U(SCH_1):TP_CLK_100M_DIF18_DP':
 C_SIGNAL='@s9s_mb_2u_lib.s9s_mb_2u(sch_1):tp_clk_100m_dif18_dp';
NODE_NAME     U38 C1
 '@S9S_MB_2U_LIB.S9S_MB_2U(SCH_1):PAGE195_I119@PURE_QUANTA.9QXL2001BNHGI8(CHIPS)':
 'DIF18': CDS_PINID='DIF18';
NET_NAME
'TP_CLK_100M_DIF19_DN'
 '@S9S_MB_2U_LIB.S9S_MB_2U(SCH_1):TP_CLK_100M_DIF19_DN':
 C_SIGNAL='@s9s_mb_2u_lib.s9s_mb_2u(sch_1):tp_clk_100m_dif19_dn';
NODE_NAME     U38 F1
 '@S9S_MB_2U_LIB.S9S_MB_2U(SCH_1):PAGE195_I119@PURE_QUANTA.9QXL2001BNHGI8(CHIPS)':
 'DIF19#': CDS_PINID='\dif19#\';
NET_NAME
'TP_CLK_100M_DIF19_DP'
 '@S9S_MB_2U_LIB.S9S_MB_2U(SCH_1):TP_CLK_100M_DIF19_DP':
 C_SIGNAL='@s9s_mb_2u_lib.s9s_mb_2u(sch_1):tp_clk_100m_dif19_dp';
NODE_NAME     U38 E1
 '@S9S_MB_2U_LIB.S9S_MB_2U(SCH_1):PAGE195_I119@PURE_QUANTA.9QXL2001BNHGI8(CHIPS)':
 'DIF19': CDS_PINID='DIF19';
NET_NAME
'TP_CLK_100M_E1S_0_DN'
 '@S9S_MB_2U_LIB.S9S_MB_2U(SCH_1):TP_CLK_100M_E1S_0_DN':
 C_SIGNAL='@s9s_mb_2u_lib.s9s_mb_2u(sch_1):tp_clk_100m_e1s_0_dn';
NODE_NAME     J90 A14
 '@S9S_MB_2U_LIB.S9S_MB_2U(SCH_1):PAGE297_I318@PURE_QUANTA.SCONN56_123276793(CHIPS)':
 'REFCLK_N1': CDS_PINID='REFCLK_N1';
NET_NAME
'TP_CLK_100M_E1S_0_DP'
 '@S9S_MB_2U_LIB.S9S_MB_2U(SCH_1):TP_CLK_100M_E1S_0_DP':
 C_SIGNAL='@s9s_mb_2u_lib.s9s_mb_2u(sch_1):tp_clk_100m_e1s_0_dp';
NODE_NAME     J90 A15
 '@S9S_MB_2U_LIB.S9S_MB_2U(SCH_1):PAGE297_I318@PURE_QUANTA.SCONN56_123276793(CHIPS)':
 'REFCLK_P1': CDS_PINID='REFCLK_P1';
NET_NAME
'TP_CLK_100M_PCH_0_DN'
 '@S9S_MB_2U_LIB.S9S_MB_2U(SCH_1):TP_CLK_100M_PCH_0_DN':
 C_SIGNAL='@s9s_mb_2u_lib.s9s_mb_2u(sch_1):tp_clk_100m_pch_0_dn';
NODE_NAME     U4 A16
 '@S9S_MB_2U_LIB.S9S_MB_2U(SCH_1):PAGE171_I78@PURE_QUANTA.EMMITSBURG_REV0P9(CHIPS)':
 'CLKOUT_SRC_N_0': CDS_PINID='CLKOUT_SRC_N_0';
NET_NAME
'TP_CLK_100M_PCH_0_DP'
 '@S9S_MB_2U_LIB.S9S_MB_2U(SCH_1):TP_CLK_100M_PCH_0_DP':
 C_SIGNAL='@s9s_mb_2u_lib.s9s_mb_2u(sch_1):tp_clk_100m_pch_0_dp';
NODE_NAME     U4 C16
 '@S9S_MB_2U_LIB.S9S_MB_2U(SCH_1):PAGE171_I78@PURE_QUANTA.EMMITSBURG_REV0P9(CHIPS)':
 'CLKOUT_SRC_P_0': CDS_PINID='CLKOUT_SRC_P_0';
NET_NAME
'TP_CLK_100M_PCH_10_DN'
 '@S9S_MB_2U_LIB.S9S_MB_2U(SCH_1):TP_CLK_100M_PCH_10_DN':
 C_SIGNAL='@s9s_mb_2u_lib.s9s_mb_2u(sch_1):tp_clk_100m_pch_10_dn';
NODE_NAME     U4 J16
 '@S9S_MB_2U_LIB.S9S_MB_2U(SCH_1):PAGE171_I78@PURE_QUANTA.EMMITSBURG_REV0P9(CHIPS)':
 'CLKOUT_SRC_N_10': CDS_PINID='CLKOUT_SRC_N_10';
NET_NAME
'TP_CLK_100M_PCH_10_DP'
 '@S9S_MB_2U_LIB.S9S_MB_2U(SCH_1):TP_CLK_100M_PCH_10_DP':
 C_SIGNAL='@s9s_mb_2u_lib.s9s_mb_2u(sch_1):tp_clk_100m_pch_10_dp';
NODE_NAME     U4 K18
 '@S9S_MB_2U_LIB.S9S_MB_2U(SCH_1):PAGE171_I78@PURE_QUANTA.EMMITSBURG_REV0P9(CHIPS)':
 'CLKOUT_SRC_P_10': CDS_PINID='CLKOUT_SRC_P_10';
NET_NAME
'TP_CLK_100M_PCH_11_DN'
 '@S9S_MB_2U_LIB.S9S_MB_2U(SCH_1):TP_CLK_100M_PCH_11_DN':
 C_SIGNAL='@s9s_mb_2u_lib.s9s_mb_2u(sch_1):tp_clk_100m_pch_11_dn';
NODE_NAME     U4 G16
 '@S9S_MB_2U_LIB.S9S_MB_2U(SCH_1):PAGE171_I78@PURE_QUANTA.EMMITSBURG_REV0P9(CHIPS)':
 'CLKOUT_SRC_N_11': CDS_PINID='CLKOUT_SRC_N_11';
NET_NAME
'TP_CLK_100M_PCH_11_DP'
 '@S9S_MB_2U_LIB.S9S_MB_2U(SCH_1):TP_CLK_100M_PCH_11_DP':
 C_SIGNAL='@s9s_mb_2u_lib.s9s_mb_2u(sch_1):tp_clk_100m_pch_11_dp';
NODE_NAME     U4 H15
 '@S9S_MB_2U_LIB.S9S_MB_2U(SCH_1):PAGE171_I78@PURE_QUANTA.EMMITSBURG_REV0P9(CHIPS)':
 'CLKOUT_SRC_P_11': CDS_PINID='CLKOUT_SRC_P_11';
NET_NAME
'TP_CLK_100M_PCH_12_DN'
 '@S9S_MB_2U_LIB.S9S_MB_2U(SCH_1):TP_CLK_100M_PCH_12_DN':
 C_SIGNAL='@s9s_mb_2u_lib.s9s_mb_2u(sch_1):tp_clk_100m_pch_12_dn';
NODE_NAME     U4 A10
 '@S9S_MB_2U_LIB.S9S_MB_2U(SCH_1):PAGE171_I78@PURE_QUANTA.EMMITSBURG_REV0P9(CHIPS)':
 'CLKOUT_SRC_N_12': CDS_PINID='CLKOUT_SRC_N_12';
NET_NAME
'TP_CLK_100M_PCH_12_DP'
 '@S9S_MB_2U_LIB.S9S_MB_2U(SCH_1):TP_CLK_100M_PCH_12_DP':
 C_SIGNAL='@s9s_mb_2u_lib.s9s_mb_2u(sch_1):tp_clk_100m_pch_12_dp';
NODE_NAME     U4 C10
 '@S9S_MB_2U_LIB.S9S_MB_2U(SCH_1):PAGE171_I78@PURE_QUANTA.EMMITSBURG_REV0P9(CHIPS)':
 'CLKOUT_SRC_P_12': CDS_PINID='CLKOUT_SRC_P_12';
NET_NAME
'TP_CLK_100M_PCH_13_DN'
 '@S9S_MB_2U_LIB.S9S_MB_2U(SCH_1):TP_CLK_100M_PCH_13_DN':
 C_SIGNAL='@s9s_mb_2u_lib.s9s_mb_2u(sch_1):tp_clk_100m_pch_13_dn';
NODE_NAME     U4 A8
 '@S9S_MB_2U_LIB.S9S_MB_2U(SCH_1):PAGE171_I78@PURE_QUANTA.EMMITSBURG_REV0P9(CHIPS)':
 'CLKOUT_SRC_N_13': CDS_PINID='CLKOUT_SRC_N_13';
NET_NAME
'TP_CLK_100M_PCH_13_DP'
 '@S9S_MB_2U_LIB.S9S_MB_2U(SCH_1):TP_CLK_100M_PCH_13_DP':
 C_SIGNAL='@s9s_mb_2u_lib.s9s_mb_2u(sch_1):tp_clk_100m_pch_13_dp';
NODE_NAME     U4 C8
 '@S9S_MB_2U_LIB.S9S_MB_2U(SCH_1):PAGE171_I78@PURE_QUANTA.EMMITSBURG_REV0P9(CHIPS)':
 'CLKOUT_SRC_P_13': CDS_PINID='CLKOUT_SRC_P_13';
NET_NAME
'TP_CLK_100M_PCH_14_DN'
 '@S9S_MB_2U_LIB.S9S_MB_2U(SCH_1):TP_CLK_100M_PCH_14_DN':
 C_SIGNAL='@s9s_mb_2u_lib.s9s_mb_2u(sch_1):tp_clk_100m_pch_14_dn';
NODE_NAME     U4 B7
 '@S9S_MB_2U_LIB.S9S_MB_2U(SCH_1):PAGE171_I78@PURE_QUANTA.EMMITSBURG_REV0P9(CHIPS)':
 'CLKOUT_SRC_N_14': CDS_PINID='CLKOUT_SRC_N_14';
NET_NAME
'TP_CLK_100M_PCH_14_DP'
 '@S9S_MB_2U_LIB.S9S_MB_2U(SCH_1):TP_CLK_100M_PCH_14_DP':
 C_SIGNAL='@s9s_mb_2u_lib.s9s_mb_2u(sch_1):tp_clk_100m_pch_14_dp';
NODE_NAME     U4 D7
 '@S9S_MB_2U_LIB.S9S_MB_2U(SCH_1):PAGE171_I78@PURE_QUANTA.EMMITSBURG_REV0P9(CHIPS)':
 'CLKOUT_SRC_P_14': CDS_PINID='CLKOUT_SRC_P_14';
NET_NAME
'TP_CLK_100M_PCH_15_DN'
 '@S9S_MB_2U_LIB.S9S_MB_2U(SCH_1):TP_CLK_100M_PCH_15_DN':
 C_SIGNAL='@s9s_mb_2u_lib.s9s_mb_2u(sch_1):tp_clk_100m_pch_15_dn';
NODE_NAME     U4 B5
 '@S9S_MB_2U_LIB.S9S_MB_2U(SCH_1):PAGE171_I78@PURE_QUANTA.EMMITSBURG_REV0P9(CHIPS)':
 'CLKOUT_SRC_N_15': CDS_PINID='CLKOUT_SRC_N_15';
NET_NAME
'TP_CLK_100M_PCH_15_DP'
 '@S9S_MB_2U_LIB.S9S_MB_2U(SCH_1):TP_CLK_100M_PCH_15_DP':
 C_SIGNAL='@s9s_mb_2u_lib.s9s_mb_2u(sch_1):tp_clk_100m_pch_15_dp';
NODE_NAME     U4 C6
 '@S9S_MB_2U_LIB.S9S_MB_2U(SCH_1):PAGE171_I78@PURE_QUANTA.EMMITSBURG_REV0P9(CHIPS)':
 'CLKOUT_SRC_P_15': CDS_PINID='CLKOUT_SRC_P_15';
NET_NAME
'TP_CLK_100M_PCH_16_DN'
 '@S9S_MB_2U_LIB.S9S_MB_2U(SCH_1):TP_CLK_100M_PCH_16_DN':
 C_SIGNAL='@s9s_mb_2u_lib.s9s_mb_2u(sch_1):tp_clk_100m_pch_16_dn';
NODE_NAME     U4 A18
 '@S9S_MB_2U_LIB.S9S_MB_2U(SCH_1):PAGE171_I78@PURE_QUANTA.EMMITSBURG_REV0P9(CHIPS)':
 'CLKOUT_SRC_N_16': CDS_PINID='CLKOUT_SRC_N_16';
NET_NAME
'TP_CLK_100M_PCH_16_DP'
 '@S9S_MB_2U_LIB.S9S_MB_2U(SCH_1):TP_CLK_100M_PCH_16_DP':
 C_SIGNAL='@s9s_mb_2u_lib.s9s_mb_2u(sch_1):tp_clk_100m_pch_16_dp';
NODE_NAME     U4 C18
 '@S9S_MB_2U_LIB.S9S_MB_2U(SCH_1):PAGE171_I78@PURE_QUANTA.EMMITSBURG_REV0P9(CHIPS)':
 'CLKOUT_SRC_P_16': CDS_PINID='CLKOUT_SRC_P_16';
NET_NAME
'TP_CLK_100M_PCH_1_DN'
 '@S9S_MB_2U_LIB.S9S_MB_2U(SCH_1):TP_CLK_100M_PCH_1_DN':
 C_SIGNAL='@s9s_mb_2u_lib.s9s_mb_2u(sch_1):tp_clk_100m_pch_1_dn';
NODE_NAME     U4 G23
 '@S9S_MB_2U_LIB.S9S_MB_2U(SCH_1):PAGE171_I78@PURE_QUANTA.EMMITSBURG_REV0P9(CHIPS)':
 'CLKOUT_SRC_N_1': CDS_PINID='CLKOUT_SRC_N_1';
NET_NAME
'TP_CLK_100M_PCH_1_DP'
 '@S9S_MB_2U_LIB.S9S_MB_2U(SCH_1):TP_CLK_100M_PCH_1_DP':
 C_SIGNAL='@s9s_mb_2u_lib.s9s_mb_2u(sch_1):tp_clk_100m_pch_1_dp';
NODE_NAME     U4 F21
 '@S9S_MB_2U_LIB.S9S_MB_2U(SCH_1):PAGE171_I78@PURE_QUANTA.EMMITSBURG_REV0P9(CHIPS)':
 'CLKOUT_SRC_P_1': CDS_PINID='CLKOUT_SRC_P_1';
NET_NAME
'TP_CLK_100M_PCH_4_DN'
 '@S9S_MB_2U_LIB.S9S_MB_2U(SCH_1):TP_CLK_100M_PCH_4_DN':
 C_SIGNAL='@s9s_mb_2u_lib.s9s_mb_2u(sch_1):tp_clk_100m_pch_4_dn';
NODE_NAME     U4 B19
 '@S9S_MB_2U_LIB.S9S_MB_2U(SCH_1):PAGE171_I78@PURE_QUANTA.EMMITSBURG_REV0P9(CHIPS)':
 'CLKOUT_SRC_N_4': CDS_PINID='CLKOUT_SRC_N_4';
NET_NAME
'TP_CLK_100M_PCH_4_DP'
 '@S9S_MB_2U_LIB.S9S_MB_2U(SCH_1):TP_CLK_100M_PCH_4_DP':
 C_SIGNAL='@s9s_mb_2u_lib.s9s_mb_2u(sch_1):tp_clk_100m_pch_4_dp';
NODE_NAME     U4 D19
 '@S9S_MB_2U_LIB.S9S_MB_2U(SCH_1):PAGE171_I78@PURE_QUANTA.EMMITSBURG_REV0P9(CHIPS)':
 'CLKOUT_SRC_P_4': CDS_PINID='CLKOUT_SRC_P_4';
NET_NAME
'TP_CLK_100M_PCH_5_DN'
 '@S9S_MB_2U_LIB.S9S_MB_2U(SCH_1):TP_CLK_100M_PCH_5_DN':
 C_SIGNAL='@s9s_mb_2u_lib.s9s_mb_2u(sch_1):tp_clk_100m_pch_5_dn';
NODE_NAME     U4 A12
 '@S9S_MB_2U_LIB.S9S_MB_2U(SCH_1):PAGE171_I78@PURE_QUANTA.EMMITSBURG_REV0P9(CHIPS)':
 'CLKOUT_SRC_N_5': CDS_PINID='CLKOUT_SRC_N_5';
NET_NAME
'TP_CLK_100M_PCH_5_DP'
 '@S9S_MB_2U_LIB.S9S_MB_2U(SCH_1):TP_CLK_100M_PCH_5_DP':
 C_SIGNAL='@s9s_mb_2u_lib.s9s_mb_2u(sch_1):tp_clk_100m_pch_5_dp';
NODE_NAME     U4 C12
 '@S9S_MB_2U_LIB.S9S_MB_2U(SCH_1):PAGE171_I78@PURE_QUANTA.EMMITSBURG_REV0P9(CHIPS)':
 'CLKOUT_SRC_P_5': CDS_PINID='CLKOUT_SRC_P_5';
NET_NAME
'TP_CLK_100M_PCH_7_DN'
 '@S9S_MB_2U_LIB.S9S_MB_2U(SCH_1):TP_CLK_100M_PCH_7_DN':
 C_SIGNAL='@s9s_mb_2u_lib.s9s_mb_2u(sch_1):tp_clk_100m_pch_7_dn';
NODE_NAME     U4 A14
 '@S9S_MB_2U_LIB.S9S_MB_2U(SCH_1):PAGE171_I78@PURE_QUANTA.EMMITSBURG_REV0P9(CHIPS)':
 'CLKOUT_SRC_N_7': CDS_PINID='CLKOUT_SRC_N_7';
NET_NAME
'TP_CLK_100M_PCH_7_DP'
 '@S9S_MB_2U_LIB.S9S_MB_2U(SCH_1):TP_CLK_100M_PCH_7_DP':
 C_SIGNAL='@s9s_mb_2u_lib.s9s_mb_2u(sch_1):tp_clk_100m_pch_7_dp';
NODE_NAME     U4 C14
 '@S9S_MB_2U_LIB.S9S_MB_2U(SCH_1):PAGE171_I78@PURE_QUANTA.EMMITSBURG_REV0P9(CHIPS)':
 'CLKOUT_SRC_P_7': CDS_PINID='CLKOUT_SRC_P_7';
NET_NAME
'TP_CLK_100M_PCH_8_DN'
 '@S9S_MB_2U_LIB.S9S_MB_2U(SCH_1):TP_CLK_100M_PCH_8_DN':
 C_SIGNAL='@s9s_mb_2u_lib.s9s_mb_2u(sch_1):tp_clk_100m_pch_8_dn';
NODE_NAME     U4 F18
 '@S9S_MB_2U_LIB.S9S_MB_2U(SCH_1):PAGE171_I78@PURE_QUANTA.EMMITSBURG_REV0P9(CHIPS)':
 'CLKOUT_SRC_N_8': CDS_PINID='CLKOUT_SRC_N_8';
NET_NAME
'TP_CLK_100M_PCH_8_DP'
 '@S9S_MB_2U_LIB.S9S_MB_2U(SCH_1):TP_CLK_100M_PCH_8_DP':
 C_SIGNAL='@s9s_mb_2u_lib.s9s_mb_2u(sch_1):tp_clk_100m_pch_8_dp';
NODE_NAME     U4 H18
 '@S9S_MB_2U_LIB.S9S_MB_2U(SCH_1):PAGE171_I78@PURE_QUANTA.EMMITSBURG_REV0P9(CHIPS)':
 'CLKOUT_SRC_P_8': CDS_PINID='CLKOUT_SRC_P_8';
NET_NAME
'TP_CLK_100M_PCH_9_DN'
 '@S9S_MB_2U_LIB.S9S_MB_2U(SCH_1):TP_CLK_100M_PCH_9_DN':
 C_SIGNAL='@s9s_mb_2u_lib.s9s_mb_2u(sch_1):tp_clk_100m_pch_9_dn';
NODE_NAME     U4 B15
 '@S9S_MB_2U_LIB.S9S_MB_2U(SCH_1):PAGE171_I78@PURE_QUANTA.EMMITSBURG_REV0P9(CHIPS)':
 'CLKOUT_SRC_N_9': CDS_PINID='CLKOUT_SRC_N_9';
NET_NAME
'TP_CLK_100M_PCH_9_DP'
 '@S9S_MB_2U_LIB.S9S_MB_2U(SCH_1):TP_CLK_100M_PCH_9_DP':
 C_SIGNAL='@s9s_mb_2u_lib.s9s_mb_2u(sch_1):tp_clk_100m_pch_9_dp';
NODE_NAME     U4 D15
 '@S9S_MB_2U_LIB.S9S_MB_2U(SCH_1):PAGE171_I78@PURE_QUANTA.EMMITSBURG_REV0P9(CHIPS)':
 'CLKOUT_SRC_P_9': CDS_PINID='CLKOUT_SRC_P_9';
NET_NAME
'TP_CLK_50M_PCH_LOM'
 '@S9S_MB_2U_LIB.S9S_MB_2U(SCH_1):TP_CLK_50M_PCH_LOM':
 C_SIGNAL='@s9s_mb_2u_lib.s9s_mb_2u(sch_1):tp_clk_50m_pch_lom';
NODE_NAME     U90 8
 '@S9S_MB_2U_LIB.S9S_MB_2U(SCH_1):PAGE152_I46@PURE_QUANTA.PI6CV304LE(CHIPS)':
 'Y3': CDS_PINID='Y3';
NET_NAME
'TP_CLK_66M_ESPI_IBL_CPU0_LVC1'
 '@S9S_MB_2U_LIB.S9S_MB_2U(SCH_1):TP_CLK_66M_ESPI_IBL_CPU0_LVC1':
 C_SIGNAL='@s9s_mb_2u_lib.s9s_mb_2u(sch_1):tp_clk_66m_espi_ibl_cpu0_lvc1';
NODE_NAME     U2 BG62
 '@S9S_MB_2U_LIB.S9S_MB_2U(SCH_1):PAGE15_I1@PURE_QUANTA.SOCKET4677_AZIF0045P001C01CS(CHIPS)':
 'RSVD52': CDS_PINID='RSVD52';
NET_NAME
'TP_CLK_CK440_PFT_OUT_DN'
 '@S9S_MB_2U_LIB.S9S_MB_2U(SCH_1):TP_CLK_CK440_PFT_OUT_DN':
 C_SIGNAL='@s9s_mb_2u_lib.s9s_mb_2u(sch_1):tp_clk_ck440_pft_out_dn';
NODE_NAME     U13 A7
 '@S9S_MB_2U_LIB.S9S_MB_2U(SCH_1):PAGE197_I180@PURE_QUANTA.9SQ440NQQI8(CHIPS)':
 'PFT_OUT#': CDS_PINID='\pft_out#\';
NET_NAME
'TP_CLK_CK440_PFT_OUT_DP'
 '@S9S_MB_2U_LIB.S9S_MB_2U(SCH_1):TP_CLK_CK440_PFT_OUT_DP':
 C_SIGNAL='@s9s_mb_2u_lib.s9s_mb_2u(sch_1):tp_clk_ck440_pft_out_dp';
NODE_NAME     U13 A6
 '@S9S_MB_2U_LIB.S9S_MB_2U(SCH_1):PAGE197_I180@PURE_QUANTA.9SQ440NQQI8(CHIPS)':
 'PFT_OUT': CDS_PINID='PFT_OUT';
NET_NAME
'TP_CLK_PFT_IN_DN'
 '@S9S_MB_2U_LIB.S9S_MB_2U(SCH_1):TP_CLK_PFT_IN_DN':
 C_SIGNAL='@s9s_mb_2u_lib.s9s_mb_2u(sch_1):tp_clk_pft_in_dn';
NODE_NAME     U13 A9
 '@S9S_MB_2U_LIB.S9S_MB_2U(SCH_1):PAGE197_I180@PURE_QUANTA.9SQ440NQQI8(CHIPS)':
 'PFT_IN#': CDS_PINID='\pft_in#\';
NET_NAME
'TP_CLK_PFT_IN_DP'
 '@S9S_MB_2U_LIB.S9S_MB_2U(SCH_1):TP_CLK_PFT_IN_DP':
 C_SIGNAL='@s9s_mb_2u_lib.s9s_mb_2u(sch_1):tp_clk_pft_in_dp';
NODE_NAME     U13 A8
 '@S9S_MB_2U_LIB.S9S_MB_2U(SCH_1):PAGE197_I180@PURE_QUANTA.9SQ440NQQI8(CHIPS)':
 'PFT_IN': CDS_PINID='PFT_IN';
NET_NAME
'TP_CPU0_A0_DEBUG_EN'
 '@S9S_MB_2U_LIB.S9S_MB_2U(SCH_1):TP_CPU0_A0_DEBUG_EN':
 C_SIGNAL='@s9s_mb_2u_lib.s9s_mb_2u(sch_1):tp_cpu0_a0_debug_en';
NODE_NAME     U2 H12
 '@S9S_MB_2U_LIB.S9S_MB_2U(SCH_1):PAGE16_I1@PURE_QUANTA.SOCKET4677_AZIF0045P001C01CS(CHIPS)':
 'RSVD162': CDS_PINID='RSVD162';
NET_NAME
'TP_CPU0_BR23'
 '@S9S_MB_2U_LIB.S9S_MB_2U(SCH_1):TP_CPU0_BR23':
 C_SIGNAL='@s9s_mb_2u_lib.s9s_mb_2u(sch_1):tp_cpu0_br23';
NODE_NAME     U2 BR23
 '@S9S_MB_2U_LIB.S9S_MB_2U(SCH_1):PAGE13_I57@PURE_QUANTA.SOCKET4677_AZIF0045P001C01CS(CHIPS)':
 'RSVD72': CDS_PINID='RSVD72';
NET_NAME
'TP_CPU0_DIE_HVM_EN_LVC1'
 '@S9S_MB_2U_LIB.S9S_MB_2U(SCH_1):TP_CPU0_DIE_HVM_EN_LVC1':
 C_SIGNAL='@s9s_mb_2u_lib.s9s_mb_2u(sch_1):tp_cpu0_die_hvm_en_lvc1';
NODE_NAME     U2 BE21
 '@S9S_MB_2U_LIB.S9S_MB_2U(SCH_1):PAGE17_I1@PURE_QUANTA.SOCKET4677_AZIF0045P001C01CS(CHIPS)':
 'RSVD45': CDS_PINID='RSVD45';
NET_NAME
'TP_CPU0_IFST_DONE_LVC1_R'
 '@S9S_MB_2U_LIB.S9S_MB_2U(SCH_1):TP_CPU0_IFST_DONE_LVC1_R':
 C_SIGNAL='@s9s_mb_2u_lib.s9s_mb_2u(sch_1):tp_cpu0_ifst_done_lvc1_r';
NODE_NAME     U2 BC23
 '@S9S_MB_2U_LIB.S9S_MB_2U(SCH_1):PAGE16_I1@PURE_QUANTA.SOCKET4677_AZIF0045P001C01CS(CHIPS)':
 'RSVD37': CDS_PINID='RSVD37';
NET_NAME
'TP_CPU0_IFST_KOT_LVC1_R'
 '@S9S_MB_2U_LIB.S9S_MB_2U(SCH_1):TP_CPU0_IFST_KOT_LVC1_R':
 C_SIGNAL='@s9s_mb_2u_lib.s9s_mb_2u(sch_1):tp_cpu0_ifst_kot_lvc1_r';
NODE_NAME     U2 BE23
 '@S9S_MB_2U_LIB.S9S_MB_2U(SCH_1):PAGE16_I1@PURE_QUANTA.SOCKET4677_AZIF0045P001C01CS(CHIPS)':
 'RSVD46': CDS_PINID='RSVD46';
NET_NAME
'TP_CPU0_IFST_TRIG_LVC1_R'
 '@S9S_MB_2U_LIB.S9S_MB_2U(SCH_1):TP_CPU0_IFST_TRIG_LVC1_R':
 C_SIGNAL='@s9s_mb_2u_lib.s9s_mb_2u(sch_1):tp_cpu0_ifst_trig_lvc1_r';
NODE_NAME     U2 BF24
 '@S9S_MB_2U_LIB.S9S_MB_2U(SCH_1):PAGE16_I1@PURE_QUANTA.SOCKET4677_AZIF0045P001C01CS(CHIPS)':
 'RSVD49': CDS_PINID='RSVD49';
NET_NAME
'TP_CPU0_PPD'
 '@S9S_MB_2U_LIB.S9S_MB_2U(SCH_1):TP_CPU0_PPD':
 C_SIGNAL='@s9s_mb_2u_lib.s9s_mb_2u(sch_1):tp_cpu0_ppd';
NODE_NAME     U2 J13
 '@S9S_MB_2U_LIB.S9S_MB_2U(SCH_1):PAGE18_I1@PURE_QUANTA.SOCKET4677_AZIF0045P001C01CS(CHIPS)':
 'RSVD163': CDS_PINID='RSVD163';
NET_NAME
'TP_CPU0_PROCDIS_COD_GTL_N'
 '@S9S_MB_2U_LIB.S9S_MB_2U(SCH_1):TP_CPU0_PROCDIS_COD_GTL_N':
 C_SIGNAL='@s9s_mb_2u_lib.s9s_mb_2u(sch_1):tp_cpu0_procdis_cod_gtl_n';
NODE_NAME     U2 DA52
 '@S9S_MB_2U_LIB.S9S_MB_2U(SCH_1):PAGE13_I57@PURE_QUANTA.SOCKET4677_AZIF0045P001C01CS(CHIPS)':
 'PROCDIS_N': CDS_PINID='PROCDIS_N';
NET_NAME
'TP_CPU0_PWRBTN_N'
 '@S9S_MB_2U_LIB.S9S_MB_2U(SCH_1):TP_CPU0_PWRBTN_N':
 C_SIGNAL='@s9s_mb_2u_lib.s9s_mb_2u(sch_1):tp_cpu0_pwrbtn_n';
NODE_NAME     U2 CK24
 '@S9S_MB_2U_LIB.S9S_MB_2U(SCH_1):PAGE15_I1@PURE_QUANTA.SOCKET4677_AZIF0045P001C01CS(CHIPS)':
 'RSVD110': CDS_PINID='RSVD110';
NET_NAME
'TP_CPU0_SPARE10'
 '@S9S_MB_2U_LIB.S9S_MB_2U(SCH_1):TP_CPU0_SPARE10':
 C_SIGNAL='@s9s_mb_2u_lib.s9s_mb_2u(sch_1):tp_cpu0_spare10';
NODE_NAME     U2 CG60
 '@S9S_MB_2U_LIB.S9S_MB_2U(SCH_1):PAGE18_I1@PURE_QUANTA.SOCKET4677_AZIF0045P001C01CS(CHIPS)':
 'RSVD95': CDS_PINID='RSVD95';
NET_NAME
'TP_CPU0_SPARE11'
 '@S9S_MB_2U_LIB.S9S_MB_2U(SCH_1):TP_CPU0_SPARE11':
 C_SIGNAL='@s9s_mb_2u_lib.s9s_mb_2u(sch_1):tp_cpu0_spare11';
NODE_NAME     U2 CD69
 '@S9S_MB_2U_LIB.S9S_MB_2U(SCH_1):PAGE18_I1@PURE_QUANTA.SOCKET4677_AZIF0045P001C01CS(CHIPS)':
 'RSVD87': CDS_PINID='RSVD87';
NET_NAME
'TP_CPU0_SPARE12'
 '@S9S_MB_2U_LIB.S9S_MB_2U(SCH_1):TP_CPU0_SPARE12':
 C_SIGNAL='@s9s_mb_2u_lib.s9s_mb_2u(sch_1):tp_cpu0_spare12';
NODE_NAME     U2 CL70
 '@S9S_MB_2U_LIB.S9S_MB_2U(SCH_1):PAGE18_I1@PURE_QUANTA.SOCKET4677_AZIF0045P001C01CS(CHIPS)':
 'RSVD119': CDS_PINID='RSVD119';
NET_NAME
'TP_CPU0_SPARE13'
 '@S9S_MB_2U_LIB.S9S_MB_2U(SCH_1):TP_CPU0_SPARE13':
 C_SIGNAL='@s9s_mb_2u_lib.s9s_mb_2u(sch_1):tp_cpu0_spare13';
NODE_NAME     U2 BD77
 '@S9S_MB_2U_LIB.S9S_MB_2U(SCH_1):PAGE18_I1@PURE_QUANTA.SOCKET4677_AZIF0045P001C01CS(CHIPS)':
 'RSVD44': CDS_PINID='RSVD44';
NET_NAME
'TP_CPU0_SPARE4'
 '@S9S_MB_2U_LIB.S9S_MB_2U(SCH_1):TP_CPU0_SPARE4':
 C_SIGNAL='@s9s_mb_2u_lib.s9s_mb_2u(sch_1):tp_cpu0_spare4';
NODE_NAME     U2 DA70
 '@S9S_MB_2U_LIB.S9S_MB_2U(SCH_1):PAGE18_I1@PURE_QUANTA.SOCKET4677_AZIF0045P001C01CS(CHIPS)':
 'RSVD159': CDS_PINID='RSVD159';
NET_NAME
'TP_CPU0_SPARE5'
 '@S9S_MB_2U_LIB.S9S_MB_2U(SCH_1):TP_CPU0_SPARE5':
 C_SIGNAL='@s9s_mb_2u_lib.s9s_mb_2u(sch_1):tp_cpu0_spare5';
NODE_NAME     U2 AU52
 '@S9S_MB_2U_LIB.S9S_MB_2U(SCH_1):PAGE18_I1@PURE_QUANTA.SOCKET4677_AZIF0045P001C01CS(CHIPS)':
 'RSVD8': CDS_PINID='RSVD8';
NET_NAME
'TP_CPU0_SPARE6'
 '@S9S_MB_2U_LIB.S9S_MB_2U(SCH_1):TP_CPU0_SPARE6':
 C_SIGNAL='@s9s_mb_2u_lib.s9s_mb_2u(sch_1):tp_cpu0_spare6';
NODE_NAME     U2 CW43
 '@S9S_MB_2U_LIB.S9S_MB_2U(SCH_1):PAGE18_I1@PURE_QUANTA.SOCKET4677_AZIF0045P001C01CS(CHIPS)':
 'RSVD148': CDS_PINID='RSVD148';
NET_NAME
'TP_CPU0_SPARE7'
 '@S9S_MB_2U_LIB.S9S_MB_2U(SCH_1):TP_CPU0_SPARE7':
 C_SIGNAL='@s9s_mb_2u_lib.s9s_mb_2u(sch_1):tp_cpu0_spare7';
NODE_NAME     U2 CL60
 '@S9S_MB_2U_LIB.S9S_MB_2U(SCH_1):PAGE18_I1@PURE_QUANTA.SOCKET4677_AZIF0045P001C01CS(CHIPS)':
 'RSVD115': CDS_PINID='RSVD115';
NET_NAME
'TP_CPU0_SPARE8'
 '@S9S_MB_2U_LIB.S9S_MB_2U(SCH_1):TP_CPU0_SPARE8':
 C_SIGNAL='@s9s_mb_2u_lib.s9s_mb_2u(sch_1):tp_cpu0_spare8';
NODE_NAME     U2 CK61
 '@S9S_MB_2U_LIB.S9S_MB_2U(SCH_1):PAGE18_I1@PURE_QUANTA.SOCKET4677_AZIF0045P001C01CS(CHIPS)':
 'RSVD111': CDS_PINID='RSVD111';
NET_NAME
'TP_CPU0_SPARE9'
 '@S9S_MB_2U_LIB.S9S_MB_2U(SCH_1):TP_CPU0_SPARE9':
 C_SIGNAL='@s9s_mb_2u_lib.s9s_mb_2u(sch_1):tp_cpu0_spare9';
NODE_NAME     U2 CH61
 '@S9S_MB_2U_LIB.S9S_MB_2U(SCH_1):PAGE18_I1@PURE_QUANTA.SOCKET4677_AZIF0045P001C01CS(CHIPS)':
 'RSVD97': CDS_PINID='RSVD97';
NET_NAME
'TP_CPU0_SSC_SYNC'
 '@S9S_MB_2U_LIB.S9S_MB_2U(SCH_1):TP_CPU0_SSC_SYNC':
 C_SIGNAL='@s9s_mb_2u_lib.s9s_mb_2u(sch_1):tp_cpu0_ssc_sync';
NODE_NAME     U2 CL66
 '@S9S_MB_2U_LIB.S9S_MB_2U(SCH_1):PAGE15_I1@PURE_QUANTA.SOCKET4677_AZIF0045P001C01CS(CHIPS)':
 'RSVD117': CDS_PINID='RSVD117';
NET_NAME
'TP_CPU1_A0_DEBUG_EN'
 '@S9S_MB_2U_LIB.S9S_MB_2U(SCH_1):TP_CPU1_A0_DEBUG_EN':
 C_SIGNAL='@s9s_mb_2u_lib.s9s_mb_2u(sch_1):tp_cpu1_a0_debug_en';
NODE_NAME     U1 H12
 '@S9S_MB_2U_LIB.S9S_MB_2U(SCH_1):PAGE47_I16@PURE_QUANTA.SOCKET4677_AZIF0045P001C01CS(CHIPS)':
 'RSVD162': CDS_PINID='RSVD162';
NET_NAME
'TP_CPU1_BR23'
 '@S9S_MB_2U_LIB.S9S_MB_2U(SCH_1):TP_CPU1_BR23':
 C_SIGNAL='@s9s_mb_2u_lib.s9s_mb_2u(sch_1):tp_cpu1_br23';
NODE_NAME     U1 BR23
 '@S9S_MB_2U_LIB.S9S_MB_2U(SCH_1):PAGE44_I51@PURE_QUANTA.SOCKET4677_AZIF0045P001C01CS(CHIPS)':
 'RSVD72': CDS_PINID='RSVD72';
NET_NAME
'TP_CPU1_DIE_HVM_EN_LVC1'
 '@S9S_MB_2U_LIB.S9S_MB_2U(SCH_1):TP_CPU1_DIE_HVM_EN_LVC1':
 C_SIGNAL='@s9s_mb_2u_lib.s9s_mb_2u(sch_1):tp_cpu1_die_hvm_en_lvc1';
NODE_NAME     U1 BE21
 '@S9S_MB_2U_LIB.S9S_MB_2U(SCH_1):PAGE48_I1@PURE_QUANTA.SOCKET4677_AZIF0045P001C01CS(CHIPS)':
 'RSVD45': CDS_PINID='RSVD45';
NET_NAME
'TP_CPU1_IBL_GRST_WARN_CPU1_N'
 '@S9S_MB_2U_LIB.S9S_MB_2U(SCH_1):TP_CPU1_IBL_GRST_WARN_CPU1_N':
 C_SIGNAL='@s9s_mb_2u_lib.s9s_mb_2u(sch_1):tp_cpu1_ibl_grst_warn_cpu1_n';
NODE_NAME     U1 CJ21
 '@S9S_MB_2U_LIB.S9S_MB_2U(SCH_1):PAGE46_I5@PURE_QUANTA.SOCKET4677_AZIF0045P001C01CS(CHIPS)':
 'RSVD101': CDS_PINID='RSVD101';
NET_NAME
'TP_CPU1_IFST_DONE_LVC1_R'
 '@S9S_MB_2U_LIB.S9S_MB_2U(SCH_1):TP_CPU1_IFST_DONE_LVC1_R':
 C_SIGNAL='@s9s_mb_2u_lib.s9s_mb_2u(sch_1):tp_cpu1_ifst_done_lvc1_r';
NODE_NAME     U1 BC23
 '@S9S_MB_2U_LIB.S9S_MB_2U(SCH_1):PAGE47_I16@PURE_QUANTA.SOCKET4677_AZIF0045P001C01CS(CHIPS)':
 'RSVD37': CDS_PINID='RSVD37';
NET_NAME
'TP_CPU1_IFST_KOT_LVC1_R'
 '@S9S_MB_2U_LIB.S9S_MB_2U(SCH_1):TP_CPU1_IFST_KOT_LVC1_R':
 C_SIGNAL='@s9s_mb_2u_lib.s9s_mb_2u(sch_1):tp_cpu1_ifst_kot_lvc1_r';
NODE_NAME     U1 BE23
 '@S9S_MB_2U_LIB.S9S_MB_2U(SCH_1):PAGE47_I16@PURE_QUANTA.SOCKET4677_AZIF0045P001C01CS(CHIPS)':
 'RSVD46': CDS_PINID='RSVD46';
NET_NAME
'TP_CPU1_IFST_TRIG_LVC1_R'
 '@S9S_MB_2U_LIB.S9S_MB_2U(SCH_1):TP_CPU1_IFST_TRIG_LVC1_R':
 C_SIGNAL='@s9s_mb_2u_lib.s9s_mb_2u(sch_1):tp_cpu1_ifst_trig_lvc1_r';
NODE_NAME     U1 BF24
 '@S9S_MB_2U_LIB.S9S_MB_2U(SCH_1):PAGE47_I16@PURE_QUANTA.SOCKET4677_AZIF0045P001C01CS(CHIPS)':
 'RSVD49': CDS_PINID='RSVD49';
NET_NAME
'TP_CPU1_PPD'
 '@S9S_MB_2U_LIB.S9S_MB_2U(SCH_1):TP_CPU1_PPD':
 C_SIGNAL='@s9s_mb_2u_lib.s9s_mb_2u(sch_1):tp_cpu1_ppd';
NODE_NAME     U1 J13
 '@S9S_MB_2U_LIB.S9S_MB_2U(SCH_1):PAGE49_I2@PURE_QUANTA.SOCKET4677_AZIF0045P001C01CS(CHIPS)':
 'RSVD163': CDS_PINID='RSVD163';
NET_NAME
'TP_CPU1_SPARE10'
 '@S9S_MB_2U_LIB.S9S_MB_2U(SCH_1):TP_CPU1_SPARE10':
 C_SIGNAL='@s9s_mb_2u_lib.s9s_mb_2u(sch_1):tp_cpu1_spare10';
NODE_NAME     U1 CG60
 '@S9S_MB_2U_LIB.S9S_MB_2U(SCH_1):PAGE49_I2@PURE_QUANTA.SOCKET4677_AZIF0045P001C01CS(CHIPS)':
 'RSVD95': CDS_PINID='RSVD95';
NET_NAME
'TP_CPU1_SPARE11'
 '@S9S_MB_2U_LIB.S9S_MB_2U(SCH_1):TP_CPU1_SPARE11':
 C_SIGNAL='@s9s_mb_2u_lib.s9s_mb_2u(sch_1):tp_cpu1_spare11';
NODE_NAME     U1 CD69
 '@S9S_MB_2U_LIB.S9S_MB_2U(SCH_1):PAGE49_I2@PURE_QUANTA.SOCKET4677_AZIF0045P001C01CS(CHIPS)':
 'RSVD87': CDS_PINID='RSVD87';
NET_NAME
'TP_CPU1_SPARE12'
 '@S9S_MB_2U_LIB.S9S_MB_2U(SCH_1):TP_CPU1_SPARE12':
 C_SIGNAL='@s9s_mb_2u_lib.s9s_mb_2u(sch_1):tp_cpu1_spare12';
NODE_NAME     U1 CL70
 '@S9S_MB_2U_LIB.S9S_MB_2U(SCH_1):PAGE49_I2@PURE_QUANTA.SOCKET4677_AZIF0045P001C01CS(CHIPS)':
 'RSVD119': CDS_PINID='RSVD119';
NET_NAME
'TP_CPU1_SPARE13'
 '@S9S_MB_2U_LIB.S9S_MB_2U(SCH_1):TP_CPU1_SPARE13':
 C_SIGNAL='@s9s_mb_2u_lib.s9s_mb_2u(sch_1):tp_cpu1_spare13';
NODE_NAME     U1 BD77
 '@S9S_MB_2U_LIB.S9S_MB_2U(SCH_1):PAGE49_I2@PURE_QUANTA.SOCKET4677_AZIF0045P001C01CS(CHIPS)':
 'RSVD44': CDS_PINID='RSVD44';
NET_NAME
'TP_CPU1_SPARE4'
 '@S9S_MB_2U_LIB.S9S_MB_2U(SCH_1):TP_CPU1_SPARE4':
 C_SIGNAL='@s9s_mb_2u_lib.s9s_mb_2u(sch_1):tp_cpu1_spare4';
NODE_NAME     U1 DA70
 '@S9S_MB_2U_LIB.S9S_MB_2U(SCH_1):PAGE49_I2@PURE_QUANTA.SOCKET4677_AZIF0045P001C01CS(CHIPS)':
 'RSVD159': CDS_PINID='RSVD159';
NET_NAME
'TP_CPU1_SPARE5'
 '@S9S_MB_2U_LIB.S9S_MB_2U(SCH_1):TP_CPU1_SPARE5':
 C_SIGNAL='@s9s_mb_2u_lib.s9s_mb_2u(sch_1):tp_cpu1_spare5';
NODE_NAME     U1 AU52
 '@S9S_MB_2U_LIB.S9S_MB_2U(SCH_1):PAGE49_I2@PURE_QUANTA.SOCKET4677_AZIF0045P001C01CS(CHIPS)':
 'RSVD8': CDS_PINID='RSVD8';
NET_NAME
'TP_CPU1_SPARE6'
 '@S9S_MB_2U_LIB.S9S_MB_2U(SCH_1):TP_CPU1_SPARE6':
 C_SIGNAL='@s9s_mb_2u_lib.s9s_mb_2u(sch_1):tp_cpu1_spare6';
NODE_NAME     U1 CW43
 '@S9S_MB_2U_LIB.S9S_MB_2U(SCH_1):PAGE49_I2@PURE_QUANTA.SOCKET4677_AZIF0045P001C01CS(CHIPS)':
 'RSVD148': CDS_PINID='RSVD148';
NET_NAME
'TP_CPU1_SPARE7'
 '@S9S_MB_2U_LIB.S9S_MB_2U(SCH_1):TP_CPU1_SPARE7':
 C_SIGNAL='@s9s_mb_2u_lib.s9s_mb_2u(sch_1):tp_cpu1_spare7';
NODE_NAME     U1 CL60
 '@S9S_MB_2U_LIB.S9S_MB_2U(SCH_1):PAGE49_I2@PURE_QUANTA.SOCKET4677_AZIF0045P001C01CS(CHIPS)':
 'RSVD115': CDS_PINID='RSVD115';
NET_NAME
'TP_CPU1_SPARE8'
 '@S9S_MB_2U_LIB.S9S_MB_2U(SCH_1):TP_CPU1_SPARE8':
 C_SIGNAL='@s9s_mb_2u_lib.s9s_mb_2u(sch_1):tp_cpu1_spare8';
NODE_NAME     U1 CK61
 '@S9S_MB_2U_LIB.S9S_MB_2U(SCH_1):PAGE49_I2@PURE_QUANTA.SOCKET4677_AZIF0045P001C01CS(CHIPS)':
 'RSVD111': CDS_PINID='RSVD111';
NET_NAME
'TP_CPU1_SPARE9'
 '@S9S_MB_2U_LIB.S9S_MB_2U(SCH_1):TP_CPU1_SPARE9':
 C_SIGNAL='@s9s_mb_2u_lib.s9s_mb_2u(sch_1):tp_cpu1_spare9';
NODE_NAME     U1 CH61
 '@S9S_MB_2U_LIB.S9S_MB_2U(SCH_1):PAGE49_I2@PURE_QUANTA.SOCKET4677_AZIF0045P001C01CS(CHIPS)':
 'RSVD97': CDS_PINID='RSVD97';
NET_NAME
'TP_CPU1_SSC_SYNC'
 '@S9S_MB_2U_LIB.S9S_MB_2U(SCH_1):TP_CPU1_SSC_SYNC':
 C_SIGNAL='@s9s_mb_2u_lib.s9s_mb_2u(sch_1):tp_cpu1_ssc_sync';
NODE_NAME     U1 CL66
 '@S9S_MB_2U_LIB.S9S_MB_2U(SCH_1):PAGE46_I5@PURE_QUANTA.SOCKET4677_AZIF0045P001C01CS(CHIPS)':
 'RSVD117': CDS_PINID='RSVD117';
NET_NAME
'TP_DMI_CPU1_PCH_RX_C_DN<0>'
 '@S9S_MB_2U_LIB.S9S_MB_2U(SCH_1):TP_DMI_CPU1_PCH_RX_C_DN'<0>:
 C_SIGNAL='@s9s_mb_2u_lib.s9s_mb_2u(sch_1):tp_dmi_cpu1_pch_rx_c_dn(0)';
NODE_NAME     U1 BB18
 '@S9S_MB_2U_LIB.S9S_MB_2U(SCH_1):PAGE59_I20@PURE_QUANTA.SOCKET4677_AZIF0045P001C01CS(CHIPS)':
 'DMI_RX_DN0': CDS_PINID='DMI_RX_DN0';
NET_NAME
'TP_DMI_CPU1_PCH_RX_C_DN<1>'
 '@S9S_MB_2U_LIB.S9S_MB_2U(SCH_1):TP_DMI_CPU1_PCH_RX_C_DN'<1>:
 C_SIGNAL='@s9s_mb_2u_lib.s9s_mb_2u(sch_1):tp_dmi_cpu1_pch_rx_c_dn(1)';
NODE_NAME     U1 BE17
 '@S9S_MB_2U_LIB.S9S_MB_2U(SCH_1):PAGE59_I20@PURE_QUANTA.SOCKET4677_AZIF0045P001C01CS(CHIPS)':
 'DMI_RX_DN1': CDS_PINID='DMI_RX_DN1';
NET_NAME
'TP_DMI_CPU1_PCH_RX_C_DN<2>'
 '@S9S_MB_2U_LIB.S9S_MB_2U(SCH_1):TP_DMI_CPU1_PCH_RX_C_DN'<2>:
 C_SIGNAL='@s9s_mb_2u_lib.s9s_mb_2u(sch_1):tp_dmi_cpu1_pch_rx_c_dn(2)';
NODE_NAME     U1 BF18
 '@S9S_MB_2U_LIB.S9S_MB_2U(SCH_1):PAGE59_I20@PURE_QUANTA.SOCKET4677_AZIF0045P001C01CS(CHIPS)':
 'DMI_RX_DN2': CDS_PINID='DMI_RX_DN2';
NET_NAME
'TP_DMI_CPU1_PCH_RX_C_DN<3>'
 '@S9S_MB_2U_LIB.S9S_MB_2U(SCH_1):TP_DMI_CPU1_PCH_RX_C_DN'<3>:
 C_SIGNAL='@s9s_mb_2u_lib.s9s_mb_2u(sch_1):tp_dmi_cpu1_pch_rx_c_dn(3)';
NODE_NAME     U1 BJ17
 '@S9S_MB_2U_LIB.S9S_MB_2U(SCH_1):PAGE59_I20@PURE_QUANTA.SOCKET4677_AZIF0045P001C01CS(CHIPS)':
 'DMI_RX_DN3': CDS_PINID='DMI_RX_DN3';
NET_NAME
'TP_DMI_CPU1_PCH_RX_C_DN<4>'
 '@S9S_MB_2U_LIB.S9S_MB_2U(SCH_1):TP_DMI_CPU1_PCH_RX_C_DN'<4>:
 C_SIGNAL='@s9s_mb_2u_lib.s9s_mb_2u(sch_1):tp_dmi_cpu1_pch_rx_c_dn(4)';
NODE_NAME     U1 BK18
 '@S9S_MB_2U_LIB.S9S_MB_2U(SCH_1):PAGE59_I20@PURE_QUANTA.SOCKET4677_AZIF0045P001C01CS(CHIPS)':
 'DMI_RX_DN4': CDS_PINID='DMI_RX_DN4';
NET_NAME
'TP_DMI_CPU1_PCH_RX_C_DN<5>'
 '@S9S_MB_2U_LIB.S9S_MB_2U(SCH_1):TP_DMI_CPU1_PCH_RX_C_DN'<5>:
 C_SIGNAL='@s9s_mb_2u_lib.s9s_mb_2u(sch_1):tp_dmi_cpu1_pch_rx_c_dn(5)';
NODE_NAME     U1 BN17
 '@S9S_MB_2U_LIB.S9S_MB_2U(SCH_1):PAGE59_I20@PURE_QUANTA.SOCKET4677_AZIF0045P001C01CS(CHIPS)':
 'DMI_RX_DN5': CDS_PINID='DMI_RX_DN5';
NET_NAME
'TP_DMI_CPU1_PCH_RX_C_DN<6>'
 '@S9S_MB_2U_LIB.S9S_MB_2U(SCH_1):TP_DMI_CPU1_PCH_RX_C_DN'<6>:
 C_SIGNAL='@s9s_mb_2u_lib.s9s_mb_2u(sch_1):tp_dmi_cpu1_pch_rx_c_dn(6)';
NODE_NAME     U1 BP18
 '@S9S_MB_2U_LIB.S9S_MB_2U(SCH_1):PAGE59_I20@PURE_QUANTA.SOCKET4677_AZIF0045P001C01CS(CHIPS)':
 'DMI_RX_DN6': CDS_PINID='DMI_RX_DN6';
NET_NAME
'TP_DMI_CPU1_PCH_RX_C_DN<7>'
 '@S9S_MB_2U_LIB.S9S_MB_2U(SCH_1):TP_DMI_CPU1_PCH_RX_C_DN'<7>:
 C_SIGNAL='@s9s_mb_2u_lib.s9s_mb_2u(sch_1):tp_dmi_cpu1_pch_rx_c_dn(7)';
NODE_NAME     U1 BU17
 '@S9S_MB_2U_LIB.S9S_MB_2U(SCH_1):PAGE59_I20@PURE_QUANTA.SOCKET4677_AZIF0045P001C01CS(CHIPS)':
 'DMI_RX_DN7': CDS_PINID='DMI_RX_DN7';
NET_NAME
'TP_DMI_CPU1_PCH_RX_C_DP<0>'
 '@S9S_MB_2U_LIB.S9S_MB_2U(SCH_1):TP_DMI_CPU1_PCH_RX_C_DP'<0>:
 C_SIGNAL='@s9s_mb_2u_lib.s9s_mb_2u(sch_1):tp_dmi_cpu1_pch_rx_c_dp(0)';
NODE_NAME     U1 BC19
 '@S9S_MB_2U_LIB.S9S_MB_2U(SCH_1):PAGE59_I20@PURE_QUANTA.SOCKET4677_AZIF0045P001C01CS(CHIPS)':
 'DMI_RX_DP0': CDS_PINID='DMI_RX_DP0';
NET_NAME
'TP_DMI_CPU1_PCH_RX_C_DP<1>'
 '@S9S_MB_2U_LIB.S9S_MB_2U(SCH_1):TP_DMI_CPU1_PCH_RX_C_DP'<1>:
 C_SIGNAL='@s9s_mb_2u_lib.s9s_mb_2u(sch_1):tp_dmi_cpu1_pch_rx_c_dp(1)';
NODE_NAME     U1 BD18
 '@S9S_MB_2U_LIB.S9S_MB_2U(SCH_1):PAGE59_I20@PURE_QUANTA.SOCKET4677_AZIF0045P001C01CS(CHIPS)':
 'DMI_RX_DP1': CDS_PINID='DMI_RX_DP1';
NET_NAME
'TP_DMI_CPU1_PCH_RX_C_DP<2>'
 '@S9S_MB_2U_LIB.S9S_MB_2U(SCH_1):TP_DMI_CPU1_PCH_RX_C_DP'<2>:
 C_SIGNAL='@s9s_mb_2u_lib.s9s_mb_2u(sch_1):tp_dmi_cpu1_pch_rx_c_dp(2)';
NODE_NAME     U1 BG19
 '@S9S_MB_2U_LIB.S9S_MB_2U(SCH_1):PAGE59_I20@PURE_QUANTA.SOCKET4677_AZIF0045P001C01CS(CHIPS)':
 'DMI_RX_DP2': CDS_PINID='DMI_RX_DP2';
NET_NAME
'TP_DMI_CPU1_PCH_RX_C_DP<3>'
 '@S9S_MB_2U_LIB.S9S_MB_2U(SCH_1):TP_DMI_CPU1_PCH_RX_C_DP'<3>:
 C_SIGNAL='@s9s_mb_2u_lib.s9s_mb_2u(sch_1):tp_dmi_cpu1_pch_rx_c_dp(3)';
NODE_NAME     U1 BH18
 '@S9S_MB_2U_LIB.S9S_MB_2U(SCH_1):PAGE59_I20@PURE_QUANTA.SOCKET4677_AZIF0045P001C01CS(CHIPS)':
 'DMI_RX_DP3': CDS_PINID='DMI_RX_DP3';
NET_NAME
'TP_DMI_CPU1_PCH_RX_C_DP<4>'
 '@S9S_MB_2U_LIB.S9S_MB_2U(SCH_1):TP_DMI_CPU1_PCH_RX_C_DP'<4>:
 C_SIGNAL='@s9s_mb_2u_lib.s9s_mb_2u(sch_1):tp_dmi_cpu1_pch_rx_c_dp(4)';
NODE_NAME     U1 BL19
 '@S9S_MB_2U_LIB.S9S_MB_2U(SCH_1):PAGE59_I20@PURE_QUANTA.SOCKET4677_AZIF0045P001C01CS(CHIPS)':
 'DMI_RX_DP4': CDS_PINID='DMI_RX_DP4';
NET_NAME
'TP_DMI_CPU1_PCH_RX_C_DP<5>'
 '@S9S_MB_2U_LIB.S9S_MB_2U(SCH_1):TP_DMI_CPU1_PCH_RX_C_DP'<5>:
 C_SIGNAL='@s9s_mb_2u_lib.s9s_mb_2u(sch_1):tp_dmi_cpu1_pch_rx_c_dp(5)';
NODE_NAME     U1 BM18
 '@S9S_MB_2U_LIB.S9S_MB_2U(SCH_1):PAGE59_I20@PURE_QUANTA.SOCKET4677_AZIF0045P001C01CS(CHIPS)':
 'DMI_RX_DP5': CDS_PINID='DMI_RX_DP5';
NET_NAME
'TP_DMI_CPU1_PCH_RX_C_DP<6>'
 '@S9S_MB_2U_LIB.S9S_MB_2U(SCH_1):TP_DMI_CPU1_PCH_RX_C_DP'<6>:
 C_SIGNAL='@s9s_mb_2u_lib.s9s_mb_2u(sch_1):tp_dmi_cpu1_pch_rx_c_dp(6)';
NODE_NAME     U1 BR19
 '@S9S_MB_2U_LIB.S9S_MB_2U(SCH_1):PAGE59_I20@PURE_QUANTA.SOCKET4677_AZIF0045P001C01CS(CHIPS)':
 'DMI_RX_DP6': CDS_PINID='DMI_RX_DP6';
NET_NAME
'TP_DMI_CPU1_PCH_RX_C_DP<7>'
 '@S9S_MB_2U_LIB.S9S_MB_2U(SCH_1):TP_DMI_CPU1_PCH_RX_C_DP'<7>:
 C_SIGNAL='@s9s_mb_2u_lib.s9s_mb_2u(sch_1):tp_dmi_cpu1_pch_rx_c_dp(7)';
NODE_NAME     U1 BT18
 '@S9S_MB_2U_LIB.S9S_MB_2U(SCH_1):PAGE59_I20@PURE_QUANTA.SOCKET4677_AZIF0045P001C01CS(CHIPS)':
 'DMI_RX_DP7': CDS_PINID='DMI_RX_DP7';
NET_NAME
'TP_DMI_CPU1_PCH_TX_DN<0>'
 '@S9S_MB_2U_LIB.S9S_MB_2U(SCH_1):TP_DMI_CPU1_PCH_TX_DN'<0>:
 C_SIGNAL='@s9s_mb_2u_lib.s9s_mb_2u(sch_1):tp_dmi_cpu1_pch_tx_dn(0)';
NODE_NAME     U1 BW19
 '@S9S_MB_2U_LIB.S9S_MB_2U(SCH_1):PAGE59_I20@PURE_QUANTA.SOCKET4677_AZIF0045P001C01CS(CHIPS)':
 'DMI_TX_DN0': CDS_PINID='DMI_TX_DN0';
NET_NAME
'TP_DMI_CPU1_PCH_TX_DN<1>'
 '@S9S_MB_2U_LIB.S9S_MB_2U(SCH_1):TP_DMI_CPU1_PCH_TX_DN'<1>:
 C_SIGNAL='@s9s_mb_2u_lib.s9s_mb_2u(sch_1):tp_dmi_cpu1_pch_tx_dn(1)';
NODE_NAME     U1 CA17
 '@S9S_MB_2U_LIB.S9S_MB_2U(SCH_1):PAGE59_I20@PURE_QUANTA.SOCKET4677_AZIF0045P001C01CS(CHIPS)':
 'DMI_TX_DN1': CDS_PINID='DMI_TX_DN1';
NET_NAME
'TP_DMI_CPU1_PCH_TX_DN<2>'
 '@S9S_MB_2U_LIB.S9S_MB_2U(SCH_1):TP_DMI_CPU1_PCH_TX_DN'<2>:
 C_SIGNAL='@s9s_mb_2u_lib.s9s_mb_2u(sch_1):tp_dmi_cpu1_pch_tx_dn(2)';
NODE_NAME     U1 CB18
 '@S9S_MB_2U_LIB.S9S_MB_2U(SCH_1):PAGE59_I20@PURE_QUANTA.SOCKET4677_AZIF0045P001C01CS(CHIPS)':
 'DMI_TX_DN2': CDS_PINID='DMI_TX_DN2';
NET_NAME
'TP_DMI_CPU1_PCH_TX_DN<3>'
 '@S9S_MB_2U_LIB.S9S_MB_2U(SCH_1):TP_DMI_CPU1_PCH_TX_DN'<3>:
 C_SIGNAL='@s9s_mb_2u_lib.s9s_mb_2u(sch_1):tp_dmi_cpu1_pch_tx_dn(3)';
NODE_NAME     U1 CE17
 '@S9S_MB_2U_LIB.S9S_MB_2U(SCH_1):PAGE59_I20@PURE_QUANTA.SOCKET4677_AZIF0045P001C01CS(CHIPS)':
 'DMI_TX_DN3': CDS_PINID='DMI_TX_DN3';
NET_NAME
'TP_DMI_CPU1_PCH_TX_DN<4>'
 '@S9S_MB_2U_LIB.S9S_MB_2U(SCH_1):TP_DMI_CPU1_PCH_TX_DN'<4>:
 C_SIGNAL='@s9s_mb_2u_lib.s9s_mb_2u(sch_1):tp_dmi_cpu1_pch_tx_dn(4)';
NODE_NAME     U1 CF18
 '@S9S_MB_2U_LIB.S9S_MB_2U(SCH_1):PAGE59_I20@PURE_QUANTA.SOCKET4677_AZIF0045P001C01CS(CHIPS)':
 'DMI_TX_DN4': CDS_PINID='DMI_TX_DN4';
NET_NAME
'TP_DMI_CPU1_PCH_TX_DN<5>'
 '@S9S_MB_2U_LIB.S9S_MB_2U(SCH_1):TP_DMI_CPU1_PCH_TX_DN'<5>:
 C_SIGNAL='@s9s_mb_2u_lib.s9s_mb_2u(sch_1):tp_dmi_cpu1_pch_tx_dn(5)';
NODE_NAME     U1 CJ17
 '@S9S_MB_2U_LIB.S9S_MB_2U(SCH_1):PAGE59_I20@PURE_QUANTA.SOCKET4677_AZIF0045P001C01CS(CHIPS)':
 'DMI_TX_DN5': CDS_PINID='DMI_TX_DN5';
NET_NAME
'TP_DMI_CPU1_PCH_TX_DN<6>'
 '@S9S_MB_2U_LIB.S9S_MB_2U(SCH_1):TP_DMI_CPU1_PCH_TX_DN'<6>:
 C_SIGNAL='@s9s_mb_2u_lib.s9s_mb_2u(sch_1):tp_dmi_cpu1_pch_tx_dn(6)';
NODE_NAME     U1 CK18
 '@S9S_MB_2U_LIB.S9S_MB_2U(SCH_1):PAGE59_I20@PURE_QUANTA.SOCKET4677_AZIF0045P001C01CS(CHIPS)':
 'DMI_TX_DN6': CDS_PINID='DMI_TX_DN6';
NET_NAME
'TP_DMI_CPU1_PCH_TX_DN<7>'
 '@S9S_MB_2U_LIB.S9S_MB_2U(SCH_1):TP_DMI_CPU1_PCH_TX_DN'<7>:
 C_SIGNAL='@s9s_mb_2u_lib.s9s_mb_2u(sch_1):tp_dmi_cpu1_pch_tx_dn(7)';
NODE_NAME     U1 CN17
 '@S9S_MB_2U_LIB.S9S_MB_2U(SCH_1):PAGE59_I20@PURE_QUANTA.SOCKET4677_AZIF0045P001C01CS(CHIPS)':
 'DMI_TX_DN7': CDS_PINID='DMI_TX_DN7';
NET_NAME
'TP_DMI_CPU1_PCH_TX_DP<0>'
 '@S9S_MB_2U_LIB.S9S_MB_2U(SCH_1):TP_DMI_CPU1_PCH_TX_DP'<0>:
 C_SIGNAL='@s9s_mb_2u_lib.s9s_mb_2u(sch_1):tp_dmi_cpu1_pch_tx_dp(0)';
NODE_NAME     U1 CA19
 '@S9S_MB_2U_LIB.S9S_MB_2U(SCH_1):PAGE59_I20@PURE_QUANTA.SOCKET4677_AZIF0045P001C01CS(CHIPS)':
 'DMI_TX_DP0': CDS_PINID='DMI_TX_DP0';
NET_NAME
'TP_DMI_CPU1_PCH_TX_DP<1>'
 '@S9S_MB_2U_LIB.S9S_MB_2U(SCH_1):TP_DMI_CPU1_PCH_TX_DP'<1>:
 C_SIGNAL='@s9s_mb_2u_lib.s9s_mb_2u(sch_1):tp_dmi_cpu1_pch_tx_dp(1)';
NODE_NAME     U1 BY18
 '@S9S_MB_2U_LIB.S9S_MB_2U(SCH_1):PAGE59_I20@PURE_QUANTA.SOCKET4677_AZIF0045P001C01CS(CHIPS)':
 'DMI_TX_DP1': CDS_PINID='DMI_TX_DP1';
NET_NAME
'TP_DMI_CPU1_PCH_TX_DP<2>'
 '@S9S_MB_2U_LIB.S9S_MB_2U(SCH_1):TP_DMI_CPU1_PCH_TX_DP'<2>:
 C_SIGNAL='@s9s_mb_2u_lib.s9s_mb_2u(sch_1):tp_dmi_cpu1_pch_tx_dp(2)';
NODE_NAME     U1 CC19
 '@S9S_MB_2U_LIB.S9S_MB_2U(SCH_1):PAGE59_I20@PURE_QUANTA.SOCKET4677_AZIF0045P001C01CS(CHIPS)':
 'DMI_TX_DP2': CDS_PINID='DMI_TX_DP2';
NET_NAME
'TP_DMI_CPU1_PCH_TX_DP<3>'
 '@S9S_MB_2U_LIB.S9S_MB_2U(SCH_1):TP_DMI_CPU1_PCH_TX_DP'<3>:
 C_SIGNAL='@s9s_mb_2u_lib.s9s_mb_2u(sch_1):tp_dmi_cpu1_pch_tx_dp(3)';
NODE_NAME     U1 CD18
 '@S9S_MB_2U_LIB.S9S_MB_2U(SCH_1):PAGE59_I20@PURE_QUANTA.SOCKET4677_AZIF0045P001C01CS(CHIPS)':
 'DMI_TX_DP3': CDS_PINID='DMI_TX_DP3';
NET_NAME
'TP_DMI_CPU1_PCH_TX_DP<4>'
 '@S9S_MB_2U_LIB.S9S_MB_2U(SCH_1):TP_DMI_CPU1_PCH_TX_DP'<4>:
 C_SIGNAL='@s9s_mb_2u_lib.s9s_mb_2u(sch_1):tp_dmi_cpu1_pch_tx_dp(4)';
NODE_NAME     U1 CG19
 '@S9S_MB_2U_LIB.S9S_MB_2U(SCH_1):PAGE59_I20@PURE_QUANTA.SOCKET4677_AZIF0045P001C01CS(CHIPS)':
 'DMI_TX_DP4': CDS_PINID='DMI_TX_DP4';
NET_NAME
'TP_DMI_CPU1_PCH_TX_DP<5>'
 '@S9S_MB_2U_LIB.S9S_MB_2U(SCH_1):TP_DMI_CPU1_PCH_TX_DP'<5>:
 C_SIGNAL='@s9s_mb_2u_lib.s9s_mb_2u(sch_1):tp_dmi_cpu1_pch_tx_dp(5)';
NODE_NAME     U1 CH18
 '@S9S_MB_2U_LIB.S9S_MB_2U(SCH_1):PAGE59_I20@PURE_QUANTA.SOCKET4677_AZIF0045P001C01CS(CHIPS)':
 'DMI_TX_DP5': CDS_PINID='DMI_TX_DP5';
NET_NAME
'TP_DMI_CPU1_PCH_TX_DP<6>'
 '@S9S_MB_2U_LIB.S9S_MB_2U(SCH_1):TP_DMI_CPU1_PCH_TX_DP'<6>:
 C_SIGNAL='@s9s_mb_2u_lib.s9s_mb_2u(sch_1):tp_dmi_cpu1_pch_tx_dp(6)';
NODE_NAME     U1 CL19
 '@S9S_MB_2U_LIB.S9S_MB_2U(SCH_1):PAGE59_I20@PURE_QUANTA.SOCKET4677_AZIF0045P001C01CS(CHIPS)':
 'DMI_TX_DP6': CDS_PINID='DMI_TX_DP6';
NET_NAME
'TP_DMI_CPU1_PCH_TX_DP<7>'
 '@S9S_MB_2U_LIB.S9S_MB_2U(SCH_1):TP_DMI_CPU1_PCH_TX_DP'<7>:
 C_SIGNAL='@s9s_mb_2u_lib.s9s_mb_2u(sch_1):tp_dmi_cpu1_pch_tx_dp(7)';
NODE_NAME     U1 CM18
 '@S9S_MB_2U_LIB.S9S_MB_2U(SCH_1):PAGE59_I20@PURE_QUANTA.SOCKET4677_AZIF0045P001C01CS(CHIPS)':
 'DMI_TX_DP7': CDS_PINID='DMI_TX_DP7';
NET_NAME
'TP_E1S_0_MFG'
 '@S9S_MB_2U_LIB.S9S_MB_2U(SCH_1):TP_E1S_0_MFG':
 C_SIGNAL='@s9s_mb_2u_lib.s9s_mb_2u(sch_1):tp_e1s_0_mfg';
NODE_NAME     J90 B7
 '@S9S_MB_2U_LIB.S9S_MB_2U(SCH_1):PAGE297_I318@PURE_QUANTA.SCONN56_123276793(CHIPS)':
 'MFG': CDS_PINID='MFG';
NET_NAME
'TP_E1S_0_RFU'
 '@S9S_MB_2U_LIB.S9S_MB_2U(SCH_1):TP_E1S_0_RFU':
 C_SIGNAL='@s9s_mb_2u_lib.s9s_mb_2u(sch_1):tp_e1s_0_rfu';
NODE_NAME     J90 B8
 '@S9S_MB_2U_LIB.S9S_MB_2U(SCH_1):PAGE297_I318@PURE_QUANTA.SCONN56_123276793(CHIPS)':
 'RFU': CDS_PINID='RFU';
NET_NAME
'TP_EDSFF1A_TYPE_ID'
 '@S9S_MB_2U_LIB.S9S_MB_2U(SCH_1):TP_EDSFF1A_TYPE_ID':
 C_SIGNAL='@s9s_mb_2u_lib.s9s_mb_2u(sch_1):tp_edsff1a_type_id';
NODE_NAME     U4 AV24
 '@S9S_MB_2U_LIB.S9S_MB_2U(SCH_1):PAGE176_I22@PURE_QUANTA.EMMITSBURG_REV0P9(CHIPS)':
 'GPP_E_4_SATA0_XPCIE_2': CDS_PINID='GPP_E_4_SATA0_XPCIE_2';
NET_NAME
'TP_EDSFF1B_TYPE_ID'
 '@S9S_MB_2U_LIB.S9S_MB_2U(SCH_1):TP_EDSFF1B_TYPE_ID':
 C_SIGNAL='@s9s_mb_2u_lib.s9s_mb_2u(sch_1):tp_edsff1b_type_id';
NODE_NAME     U4 AV28
 '@S9S_MB_2U_LIB.S9S_MB_2U(SCH_1):PAGE176_I22@PURE_QUANTA.EMMITSBURG_REV0P9(CHIPS)':
 'GPP_E_5_SATA0_XPCIE_3': CDS_PINID='GPP_E_5_SATA0_XPCIE_3';
NET_NAME
'TP_ESPI_IBL_CPU0_ALERT0_LVC1_N'
 '@S9S_MB_2U_LIB.S9S_MB_2U(SCH_1):TP_ESPI_IBL_CPU0_ALERT0_LVC1_N':
 C_SIGNAL='@s9s_mb_2u_lib.s9s_mb_2u(sch_1):tp_espi_ibl_cpu0_alert0_lvc1_n';
NODE_NAME     U2 BE62
 '@S9S_MB_2U_LIB.S9S_MB_2U(SCH_1):PAGE15_I1@PURE_QUANTA.SOCKET4677_AZIF0045P001C01CS(CHIPS)':
 'RSVD48': CDS_PINID='RSVD48';
NET_NAME
'TP_ESPI_IBL_CPU0_ALERT1_N'
 '@S9S_MB_2U_LIB.S9S_MB_2U(SCH_1):TP_ESPI_IBL_CPU0_ALERT1_N':
 C_SIGNAL='@s9s_mb_2u_lib.s9s_mb_2u(sch_1):tp_espi_ibl_cpu0_alert1_n';
NODE_NAME     U2 BD63
 '@S9S_MB_2U_LIB.S9S_MB_2U(SCH_1):PAGE15_I1@PURE_QUANTA.SOCKET4677_AZIF0045P001C01CS(CHIPS)':
 'RSVD41': CDS_PINID='RSVD41';
NET_NAME
'TP_ESPI_IBL_CPU0_CS0_LVC1_N'
 '@S9S_MB_2U_LIB.S9S_MB_2U(SCH_1):TP_ESPI_IBL_CPU0_CS0_LVC1_N':
 C_SIGNAL='@s9s_mb_2u_lib.s9s_mb_2u(sch_1):tp_espi_ibl_cpu0_cs0_lvc1_n';
NODE_NAME     U2 BF65
 '@S9S_MB_2U_LIB.S9S_MB_2U(SCH_1):PAGE15_I1@PURE_QUANTA.SOCKET4677_AZIF0045P001C01CS(CHIPS)':
 'RSVD50': CDS_PINID='RSVD50';
NET_NAME
'TP_ESPI_IBL_CPU0_CS1_N'
 '@S9S_MB_2U_LIB.S9S_MB_2U(SCH_1):TP_ESPI_IBL_CPU0_CS1_N':
 C_SIGNAL='@s9s_mb_2u_lib.s9s_mb_2u(sch_1):tp_espi_ibl_cpu0_cs1_n';
NODE_NAME     U2 BH65
 '@S9S_MB_2U_LIB.S9S_MB_2U(SCH_1):PAGE15_I1@PURE_QUANTA.SOCKET4677_AZIF0045P001C01CS(CHIPS)':
 'RSVD56': CDS_PINID='RSVD56';
NET_NAME
'TP_ESPI_IBL_CPU0_IO0_LVC1'
 '@S9S_MB_2U_LIB.S9S_MB_2U(SCH_1):TP_ESPI_IBL_CPU0_IO0_LVC1':
 C_SIGNAL='@s9s_mb_2u_lib.s9s_mb_2u(sch_1):tp_espi_ibl_cpu0_io0_lvc1';
NODE_NAME     U2 BK63
 '@S9S_MB_2U_LIB.S9S_MB_2U(SCH_1):PAGE15_I1@PURE_QUANTA.SOCKET4677_AZIF0045P001C01CS(CHIPS)':
 'RSVD61': CDS_PINID='RSVD61';
NET_NAME
'TP_ESPI_IBL_CPU0_IO1_LVC1'
 '@S9S_MB_2U_LIB.S9S_MB_2U(SCH_1):TP_ESPI_IBL_CPU0_IO1_LVC1':
 C_SIGNAL='@s9s_mb_2u_lib.s9s_mb_2u(sch_1):tp_espi_ibl_cpu0_io1_lvc1';
NODE_NAME     U2 BJ64
 '@S9S_MB_2U_LIB.S9S_MB_2U(SCH_1):PAGE15_I1@PURE_QUANTA.SOCKET4677_AZIF0045P001C01CS(CHIPS)':
 'RSVD58': CDS_PINID='RSVD58';
NET_NAME
'TP_ESPI_IBL_CPU0_IO2_LVC1'
 '@S9S_MB_2U_LIB.S9S_MB_2U(SCH_1):TP_ESPI_IBL_CPU0_IO2_LVC1':
 C_SIGNAL='@s9s_mb_2u_lib.s9s_mb_2u(sch_1):tp_espi_ibl_cpu0_io2_lvc1';
NODE_NAME     U2 AU64
 '@S9S_MB_2U_LIB.S9S_MB_2U(SCH_1):PAGE15_I1@PURE_QUANTA.SOCKET4677_AZIF0045P001C01CS(CHIPS)':
 'RSVD12': CDS_PINID='RSVD12';
NET_NAME
'TP_ESPI_IBL_CPU0_IO3_LVC1'
 '@S9S_MB_2U_LIB.S9S_MB_2U(SCH_1):TP_ESPI_IBL_CPU0_IO3_LVC1':
 C_SIGNAL='@s9s_mb_2u_lib.s9s_mb_2u(sch_1):tp_espi_ibl_cpu0_io3_lvc1';
NODE_NAME     U2 BM63
 '@S9S_MB_2U_LIB.S9S_MB_2U(SCH_1):PAGE15_I1@PURE_QUANTA.SOCKET4677_AZIF0045P001C01CS(CHIPS)':
 'RSVD64': CDS_PINID='RSVD64';
NET_NAME
'TP_ESPI_IBL_CPU0_OE_LVC1_N'
 '@S9S_MB_2U_LIB.S9S_MB_2U(SCH_1):TP_ESPI_IBL_CPU0_OE_LVC1_N':
 C_SIGNAL='@s9s_mb_2u_lib.s9s_mb_2u(sch_1):tp_espi_ibl_cpu0_oe_lvc1_n';
NODE_NAME     U2 BH63
 '@S9S_MB_2U_LIB.S9S_MB_2U(SCH_1):PAGE15_I1@PURE_QUANTA.SOCKET4677_AZIF0045P001C01CS(CHIPS)':
 'RSVD55': CDS_PINID='RSVD55';
NET_NAME
'TP_EV_CPU0_EXT_BGREF'
 '@S9S_MB_2U_LIB.S9S_MB_2U(SCH_1):TP_EV_CPU0_EXT_BGREF':
 C_SIGNAL='@s9s_mb_2u_lib.s9s_mb_2u(sch_1):tp_ev_cpu0_ext_bgref';
NODE_NAME     U2 AV59
 '@S9S_MB_2U_LIB.S9S_MB_2U(SCH_1):PAGE14_I1@PURE_QUANTA.SOCKET4677_AZIF0045P001C01CS(CHIPS)':
 'RSVD19': CDS_PINID='RSVD19';
NET_NAME
'TP_EV_CPU1_EXT_BGREF'
 '@S9S_MB_2U_LIB.S9S_MB_2U(SCH_1):TP_EV_CPU1_EXT_BGREF':
 C_SIGNAL='@s9s_mb_2u_lib.s9s_mb_2u(sch_1):tp_ev_cpu1_ext_bgref';
NODE_NAME     U1 AV59
 '@S9S_MB_2U_LIB.S9S_MB_2U(SCH_1):PAGE45_I29@PURE_QUANTA.SOCKET4677_AZIF0045P001C01CS(CHIPS)':
 'RSVD19': CDS_PINID='RSVD19';
NET_NAME
'TP_FM_IBL_ADR_ACK_CPU0'
 '@S9S_MB_2U_LIB.S9S_MB_2U(SCH_1):TP_FM_IBL_ADR_ACK_CPU0':
 C_SIGNAL='@s9s_mb_2u_lib.s9s_mb_2u(sch_1):tp_fm_ibl_adr_ack_cpu0';
NODE_NAME     U2 CN23
 '@S9S_MB_2U_LIB.S9S_MB_2U(SCH_1):PAGE15_I1@PURE_QUANTA.SOCKET4677_AZIF0045P001C01CS(CHIPS)':
 'RSVD124': CDS_PINID='RSVD124';
NET_NAME
'TP_FM_IBL_ADR_COMPLETE_CPU0_R'
 '@S9S_MB_2U_LIB.S9S_MB_2U(SCH_1):TP_FM_IBL_ADR_COMPLETE_CPU0_R':
 C_SIGNAL='@s9s_mb_2u_lib.s9s_mb_2u(sch_1):tp_fm_ibl_adr_complete_cpu0_r';
NODE_NAME     U2 CP24
 '@S9S_MB_2U_LIB.S9S_MB_2U(SCH_1):PAGE15_I1@PURE_QUANTA.SOCKET4677_AZIF0045P001C01CS(CHIPS)':
 'RSVD128': CDS_PINID='RSVD128';
NET_NAME
'TP_FM_IBL_ADR_TRIGGER_CPU0_R'
 '@S9S_MB_2U_LIB.S9S_MB_2U(SCH_1):TP_FM_IBL_ADR_TRIGGER_CPU0_R':
 C_SIGNAL='@s9s_mb_2u_lib.s9s_mb_2u(sch_1):tp_fm_ibl_adr_trigger_cpu0_r';
NODE_NAME     U2 CT24
 '@S9S_MB_2U_LIB.S9S_MB_2U(SCH_1):PAGE15_I1@PURE_QUANTA.SOCKET4677_AZIF0045P001C01CS(CHIPS)':
 'RSVD137': CDS_PINID='RSVD137';
NET_NAME
'TP_FM_IBL_PWRBTN_CPU1_N'
 '@S9S_MB_2U_LIB.S9S_MB_2U(SCH_1):TP_FM_IBL_PWRBTN_CPU1_N':
 C_SIGNAL='@s9s_mb_2u_lib.s9s_mb_2u(sch_1):tp_fm_ibl_pwrbtn_cpu1_n';
NODE_NAME     U1 CK24
 '@S9S_MB_2U_LIB.S9S_MB_2U(SCH_1):PAGE46_I5@PURE_QUANTA.SOCKET4677_AZIF0045P001C01CS(CHIPS)':
 'RSVD110': CDS_PINID='RSVD110';
NET_NAME
'TP_FM_IBL_SLPS3_CPU1_R_N'
 '@S9S_MB_2U_LIB.S9S_MB_2U(SCH_1):TP_FM_IBL_SLPS3_CPU1_R_N':
 C_SIGNAL='@s9s_mb_2u_lib.s9s_mb_2u(sch_1):tp_fm_ibl_slps3_cpu1_r_n';
NODE_NAME     U1 CR21
 '@S9S_MB_2U_LIB.S9S_MB_2U(SCH_1):PAGE46_I5@PURE_QUANTA.SOCKET4677_AZIF0045P001C01CS(CHIPS)':
 'RSVD131': CDS_PINID='RSVD131';
NET_NAME
'TP_FM_IBL_SLPS4_CPU1_R_N'
 '@S9S_MB_2U_LIB.S9S_MB_2U(SCH_1):TP_FM_IBL_SLPS4_CPU1_R_N':
 C_SIGNAL='@s9s_mb_2u_lib.s9s_mb_2u(sch_1):tp_fm_ibl_slps4_cpu1_r_n';
NODE_NAME     U1 CN21
 '@S9S_MB_2U_LIB.S9S_MB_2U(SCH_1):PAGE46_I5@PURE_QUANTA.SOCKET4677_AZIF0045P001C01CS(CHIPS)':
 'RSVD123': CDS_PINID='RSVD123';
NET_NAME
'TP_FM_IBL_SLPS5_CPU1_R_N'
 '@S9S_MB_2U_LIB.S9S_MB_2U(SCH_1):TP_FM_IBL_SLPS5_CPU1_R_N':
 C_SIGNAL='@s9s_mb_2u_lib.s9s_mb_2u(sch_1):tp_fm_ibl_slps5_cpu1_r_n';
NODE_NAME     U1 CW21
 '@S9S_MB_2U_LIB.S9S_MB_2U(SCH_1):PAGE46_I5@PURE_QUANTA.SOCKET4677_AZIF0045P001C01CS(CHIPS)':
 'RSVD144': CDS_PINID='RSVD144';
NET_NAME
'TP_FM_IBL_SYS_RST_CPU0_N'
 '@S9S_MB_2U_LIB.S9S_MB_2U(SCH_1):TP_FM_IBL_SYS_RST_CPU0_N':
 C_SIGNAL='@s9s_mb_2u_lib.s9s_mb_2u(sch_1):tp_fm_ibl_sys_rst_cpu0_n';
NODE_NAME     U2 CK22
 '@S9S_MB_2U_LIB.S9S_MB_2U(SCH_1):PAGE15_I1@PURE_QUANTA.SOCKET4677_AZIF0045P001C01CS(CHIPS)':
 'RSVD109': CDS_PINID='RSVD109';
NET_NAME
'TP_FM_IBL_WAKE_CPU0_N'
 '@S9S_MB_2U_LIB.S9S_MB_2U(SCH_1):TP_FM_IBL_WAKE_CPU0_N':
 C_SIGNAL='@s9s_mb_2u_lib.s9s_mb_2u(sch_1):tp_fm_ibl_wake_cpu0_n';
NODE_NAME     U2 AW19
 '@S9S_MB_2U_LIB.S9S_MB_2U(SCH_1):PAGE15_I1@PURE_QUANTA.SOCKET4677_AZIF0045P001C01CS(CHIPS)':
 'RSVD23': CDS_PINID='RSVD23';
NET_NAME
'TP_FM_SYS_RST_CPU1_N'
 '@S9S_MB_2U_LIB.S9S_MB_2U(SCH_1):TP_FM_SYS_RST_CPU1_N':
 C_SIGNAL='@s9s_mb_2u_lib.s9s_mb_2u(sch_1):tp_fm_sys_rst_cpu1_n';
NODE_NAME     U1 CK22
 '@S9S_MB_2U_LIB.S9S_MB_2U(SCH_1):PAGE46_I5@PURE_QUANTA.SOCKET4677_AZIF0045P001C01CS(CHIPS)':
 'RSVD109': CDS_PINID='RSVD109';
NET_NAME
'TP_FM_WAKE_CPU1_N'
 '@S9S_MB_2U_LIB.S9S_MB_2U(SCH_1):TP_FM_WAKE_CPU1_N':
 C_SIGNAL='@s9s_mb_2u_lib.s9s_mb_2u(sch_1):tp_fm_wake_cpu1_n';
NODE_NAME     U1 AW19
 '@S9S_MB_2U_LIB.S9S_MB_2U(SCH_1):PAGE46_I5@PURE_QUANTA.SOCKET4677_AZIF0045P001C01CS(CHIPS)':
 'RSVD23': CDS_PINID='RSVD23';
NET_NAME
'TP_GPP_L_2'
 '@S9S_MB_2U_LIB.S9S_MB_2U(SCH_1):TP_GPP_L_2':
 C_SIGNAL='@s9s_mb_2u_lib.s9s_mb_2u(sch_1):tp_gpp_l_2';
NODE_NAME     U4 AC10
 '@S9S_MB_2U_LIB.S9S_MB_2U(SCH_1):PAGE176_I22@PURE_QUANTA.EMMITSBURG_REV0P9(CHIPS)':
 'GPP_L_2': CDS_PINID='GPP_L_2';
NET_NAME
'TP_GPP_L_7'
 '@S9S_MB_2U_LIB.S9S_MB_2U(SCH_1):TP_GPP_L_7':
 C_SIGNAL='@s9s_mb_2u_lib.s9s_mb_2u(sch_1):tp_gpp_l_7';
NODE_NAME     U4 AC7
 '@S9S_MB_2U_LIB.S9S_MB_2U(SCH_1):PAGE176_I22@PURE_QUANTA.EMMITSBURG_REV0P9(CHIPS)':
 'GPP_L_7': CDS_PINID='GPP_L_7';
NET_NAME
'TP_GPP_L_8'
 '@S9S_MB_2U_LIB.S9S_MB_2U(SCH_1):TP_GPP_L_8':
 C_SIGNAL='@s9s_mb_2u_lib.s9s_mb_2u(sch_1):tp_gpp_l_8';
NODE_NAME     U4 AE10
 '@S9S_MB_2U_LIB.S9S_MB_2U(SCH_1):PAGE176_I22@PURE_QUANTA.EMMITSBURG_REV0P9(CHIPS)':
 'GPP_L_8': CDS_PINID='GPP_L_8';
NET_NAME
'TP_GPP_M_12'
 '@S9S_MB_2U_LIB.S9S_MB_2U(SCH_1):TP_GPP_M_12':
 C_SIGNAL='@s9s_mb_2u_lib.s9s_mb_2u(sch_1):tp_gpp_m_12';
NODE_NAME     U4 U7
 '@S9S_MB_2U_LIB.S9S_MB_2U(SCH_1):PAGE176_I22@PURE_QUANTA.EMMITSBURG_REV0P9(CHIPS)':
 'GPP_M_12': CDS_PINID='GPP_M_12';
NET_NAME
'TP_HPM_STBY_EN'
 '@S9S_MB_2U_LIB.S9S_MB_2U(SCH_1):TP_HPM_STBY_EN':
 C_SIGNAL='@s9s_mb_2u_lib.s9s_mb_2u(sch_1):tp_hpm_stby_en';
NODE_NAME     J41 A45
 '@S9S_MB_2U_LIB.S9S_MB_2U(SCH_1):PAGE227_I173@PURE_QUANTA.SCONN168_ME1016810202011(CHIPS)':
 'PERP8': CDS_PINID='PERP8';
NET_NAME
'TP_HSC_TYPE_ADC_ALERT'
 '@S9S_MB_2U_LIB.S9S_MB_2U(SCH_1):TP_HSC_TYPE_ADC_ALERT':
 C_SIGNAL='@s9s_mb_2u_lib.s9s_mb_2u(sch_1):tp_hsc_type_adc_alert';
NODE_NAME     R4692 2
 '@S9S_MB_2U_LIB.S9S_MB_2U(SCH_1):PAGE240_I35@PURE_QUANTA.Q_RES(CHIPS)':
 'B': CDS_PINID='B';
NODE_NAME     U331 3
 '@S9S_MB_2U_LIB.S9S_MB_2U(SCH_1):PAGE240_I39@PURE_QUANTA.INA230AIRGTR(CHIPS)':
 'ALERT': CDS_PINID='ALERT';
NET_NAME
'TP_H_CPU1_PMDOWN_PCH_R'
 '@S9S_MB_2U_LIB.S9S_MB_2U(SCH_1):TP_H_CPU1_PMDOWN_PCH_R':
 C_SIGNAL='@s9s_mb_2u_lib.s9s_mb_2u(sch_1):tp_h_cpu1_pmdown_pch_r';
NODE_NAME     U1 CY40
 '@S9S_MB_2U_LIB.S9S_MB_2U(SCH_1):PAGE45_I29@PURE_QUANTA.SOCKET4677_AZIF0045P001C01CS(CHIPS)':
 'PMDOWN_PCH': CDS_PINID='PMDOWN_PCH';
NET_NAME
'TP_H_CPU1_PMSYNC_PCH_INTRP_R'
 '@S9S_MB_2U_LIB.S9S_MB_2U(SCH_1):TP_H_CPU1_PMSYNC_PCH_INTRP_R':
 C_SIGNAL='@s9s_mb_2u_lib.s9s_mb_2u(sch_1):tp_h_cpu1_pmsync_pch_intrp_r';
NODE_NAME     U1 DA39
 '@S9S_MB_2U_LIB.S9S_MB_2U(SCH_1):PAGE45_I29@PURE_QUANTA.SOCKET4677_AZIF0045P001C01CS(CHIPS)':
 'PMSYNC_PCH': CDS_PINID='PMSYNC_PCH';
NET_NAME
'TP_H_SBLINK2_CPU0_PMDOWN'
 '@S9S_MB_2U_LIB.S9S_MB_2U(SCH_1):TP_H_SBLINK2_CPU0_PMDOWN':
 C_SIGNAL='@s9s_mb_2u_lib.s9s_mb_2u(sch_1):tp_h_sblink2_cpu0_pmdown';
NODE_NAME     U2 CP26
 '@S9S_MB_2U_LIB.S9S_MB_2U(SCH_1):PAGE14_I1@PURE_QUANTA.SOCKET4677_AZIF0045P001C01CS(CHIPS)':
 'PMDOWN1': CDS_PINID='PMDOWN1';
NET_NAME
'TP_H_SBLINK2_CPU0_PMSYNC'
 '@S9S_MB_2U_LIB.S9S_MB_2U(SCH_1):TP_H_SBLINK2_CPU0_PMSYNC':
 C_SIGNAL='@s9s_mb_2u_lib.s9s_mb_2u(sch_1):tp_h_sblink2_cpu0_pmsync';
NODE_NAME     U2 CL25
 '@S9S_MB_2U_LIB.S9S_MB_2U(SCH_1):PAGE14_I1@PURE_QUANTA.SOCKET4677_AZIF0045P001C01CS(CHIPS)':
 'PMSYNC1': CDS_PINID='PMSYNC1';
NET_NAME
'TP_H_SBLINK2_CPU1_PMDOWN'
 '@S9S_MB_2U_LIB.S9S_MB_2U(SCH_1):TP_H_SBLINK2_CPU1_PMDOWN':
 C_SIGNAL='@s9s_mb_2u_lib.s9s_mb_2u(sch_1):tp_h_sblink2_cpu1_pmdown';
NODE_NAME     U1 CP26
 '@S9S_MB_2U_LIB.S9S_MB_2U(SCH_1):PAGE45_I29@PURE_QUANTA.SOCKET4677_AZIF0045P001C01CS(CHIPS)':
 'PMDOWN1': CDS_PINID='PMDOWN1';
NET_NAME
'TP_H_SBLINK2_CPU1_PMSYNC'
 '@S9S_MB_2U_LIB.S9S_MB_2U(SCH_1):TP_H_SBLINK2_CPU1_PMSYNC':
 C_SIGNAL='@s9s_mb_2u_lib.s9s_mb_2u(sch_1):tp_h_sblink2_cpu1_pmsync';
NODE_NAME     U1 CL25
 '@S9S_MB_2U_LIB.S9S_MB_2U(SCH_1):PAGE45_I29@PURE_QUANTA.SOCKET4677_AZIF0045P001C01CS(CHIPS)':
 'PMSYNC1': CDS_PINID='PMSYNC1';
NET_NAME
'TP_H_SBLINK3_CPU0_PMDOWN'
 '@S9S_MB_2U_LIB.S9S_MB_2U(SCH_1):TP_H_SBLINK3_CPU0_PMDOWN':
 C_SIGNAL='@s9s_mb_2u_lib.s9s_mb_2u(sch_1):tp_h_sblink3_cpu0_pmdown';
NODE_NAME     U2 CM26
 '@S9S_MB_2U_LIB.S9S_MB_2U(SCH_1):PAGE14_I1@PURE_QUANTA.SOCKET4677_AZIF0045P001C01CS(CHIPS)':
 'PMDOWN2': CDS_PINID='PMDOWN2';
NET_NAME
'TP_H_SBLINK3_CPU0_PMSYNC'
 '@S9S_MB_2U_LIB.S9S_MB_2U(SCH_1):TP_H_SBLINK3_CPU0_PMSYNC':
 C_SIGNAL='@s9s_mb_2u_lib.s9s_mb_2u(sch_1):tp_h_sblink3_cpu0_pmsync';
NODE_NAME     U2 CH26
 '@S9S_MB_2U_LIB.S9S_MB_2U(SCH_1):PAGE14_I1@PURE_QUANTA.SOCKET4677_AZIF0045P001C01CS(CHIPS)':
 'PMSYNC2': CDS_PINID='PMSYNC2';
NET_NAME
'TP_H_SBLINK3_CPU1_PMDOWN'
 '@S9S_MB_2U_LIB.S9S_MB_2U(SCH_1):TP_H_SBLINK3_CPU1_PMDOWN':
 C_SIGNAL='@s9s_mb_2u_lib.s9s_mb_2u(sch_1):tp_h_sblink3_cpu1_pmdown';
NODE_NAME     U1 CM26
 '@S9S_MB_2U_LIB.S9S_MB_2U(SCH_1):PAGE45_I29@PURE_QUANTA.SOCKET4677_AZIF0045P001C01CS(CHIPS)':
 'PMDOWN2': CDS_PINID='PMDOWN2';
NET_NAME
'TP_H_SBLINK3_CPU1_PMSYNC'
 '@S9S_MB_2U_LIB.S9S_MB_2U(SCH_1):TP_H_SBLINK3_CPU1_PMSYNC':
 C_SIGNAL='@s9s_mb_2u_lib.s9s_mb_2u(sch_1):tp_h_sblink3_cpu1_pmsync';
NODE_NAME     U1 CH26
 '@S9S_MB_2U_LIB.S9S_MB_2U(SCH_1):PAGE45_I29@PURE_QUANTA.SOCKET4677_AZIF0045P001C01CS(CHIPS)':
 'PMSYNC2': CDS_PINID='PMSYNC2';
NET_NAME
'TP_H_SBLINK4_CPU0_PMDOWN'
 '@S9S_MB_2U_LIB.S9S_MB_2U(SCH_1):TP_H_SBLINK4_CPU0_PMDOWN':
 C_SIGNAL='@s9s_mb_2u_lib.s9s_mb_2u(sch_1):tp_h_sblink4_cpu0_pmdown';
NODE_NAME     U2 CD24
 '@S9S_MB_2U_LIB.S9S_MB_2U(SCH_1):PAGE14_I1@PURE_QUANTA.SOCKET4677_AZIF0045P001C01CS(CHIPS)':
 'PMDOWN3': CDS_PINID='PMDOWN3';
NET_NAME
'TP_H_SBLINK4_CPU0_PMSYNC'
 '@S9S_MB_2U_LIB.S9S_MB_2U(SCH_1):TP_H_SBLINK4_CPU0_PMSYNC':
 C_SIGNAL='@s9s_mb_2u_lib.s9s_mb_2u(sch_1):tp_h_sblink4_cpu0_pmsync';
NODE_NAME     U2 CE25
 '@S9S_MB_2U_LIB.S9S_MB_2U(SCH_1):PAGE14_I1@PURE_QUANTA.SOCKET4677_AZIF0045P001C01CS(CHIPS)':
 'PMSYNC3': CDS_PINID='PMSYNC3';
NET_NAME
'TP_H_SBLINK4_CPU1_PMDOWN'
 '@S9S_MB_2U_LIB.S9S_MB_2U(SCH_1):TP_H_SBLINK4_CPU1_PMDOWN':
 C_SIGNAL='@s9s_mb_2u_lib.s9s_mb_2u(sch_1):tp_h_sblink4_cpu1_pmdown';
NODE_NAME     U1 CD24
 '@S9S_MB_2U_LIB.S9S_MB_2U(SCH_1):PAGE45_I29@PURE_QUANTA.SOCKET4677_AZIF0045P001C01CS(CHIPS)':
 'PMDOWN3': CDS_PINID='PMDOWN3';
NET_NAME
'TP_H_SBLINK4_CPU1_PMSYNC'
 '@S9S_MB_2U_LIB.S9S_MB_2U(SCH_1):TP_H_SBLINK4_CPU1_PMSYNC':
 C_SIGNAL='@s9s_mb_2u_lib.s9s_mb_2u(sch_1):tp_h_sblink4_cpu1_pmsync';
NODE_NAME     U1 CE25
 '@S9S_MB_2U_LIB.S9S_MB_2U(SCH_1):PAGE45_I29@PURE_QUANTA.SOCKET4677_AZIF0045P001C01CS(CHIPS)':
 'PMSYNC3': CDS_PINID='PMSYNC3';
NET_NAME
'TP_H_SBLINK5_CPU0_PMDOWN'
 '@S9S_MB_2U_LIB.S9S_MB_2U(SCH_1):TP_H_SBLINK5_CPU0_PMDOWN':
 C_SIGNAL='@s9s_mb_2u_lib.s9s_mb_2u(sch_1):tp_h_sblink5_cpu0_pmdown';
NODE_NAME     U2 CV18
 '@S9S_MB_2U_LIB.S9S_MB_2U(SCH_1):PAGE14_I1@PURE_QUANTA.SOCKET4677_AZIF0045P001C01CS(CHIPS)':
 'PMDOWN4': CDS_PINID='PMDOWN4';
NET_NAME
'TP_H_SBLINK5_CPU0_PMSYNC'
 '@S9S_MB_2U_LIB.S9S_MB_2U(SCH_1):TP_H_SBLINK5_CPU0_PMSYNC':
 C_SIGNAL='@s9s_mb_2u_lib.s9s_mb_2u(sch_1):tp_h_sblink5_cpu0_pmsync';
NODE_NAME     U2 CR19
 '@S9S_MB_2U_LIB.S9S_MB_2U(SCH_1):PAGE14_I1@PURE_QUANTA.SOCKET4677_AZIF0045P001C01CS(CHIPS)':
 'PMSYNC4': CDS_PINID='PMSYNC4';
NET_NAME
'TP_H_SBLINK5_CPU1_PMDOWN'
 '@S9S_MB_2U_LIB.S9S_MB_2U(SCH_1):TP_H_SBLINK5_CPU1_PMDOWN':
 C_SIGNAL='@s9s_mb_2u_lib.s9s_mb_2u(sch_1):tp_h_sblink5_cpu1_pmdown';
NODE_NAME     U1 CV18
 '@S9S_MB_2U_LIB.S9S_MB_2U(SCH_1):PAGE45_I29@PURE_QUANTA.SOCKET4677_AZIF0045P001C01CS(CHIPS)':
 'PMDOWN4': CDS_PINID='PMDOWN4';
NET_NAME
'TP_H_SBLINK5_CPU1_PMSYNC'
 '@S9S_MB_2U_LIB.S9S_MB_2U(SCH_1):TP_H_SBLINK5_CPU1_PMSYNC':
 C_SIGNAL='@s9s_mb_2u_lib.s9s_mb_2u(sch_1):tp_h_sblink5_cpu1_pmsync';
NODE_NAME     U1 CR19
 '@S9S_MB_2U_LIB.S9S_MB_2U(SCH_1):PAGE45_I29@PURE_QUANTA.SOCKET4677_AZIF0045P001C01CS(CHIPS)':
 'PMSYNC4': CDS_PINID='PMSYNC4';
NET_NAME
'TP_H_SBLINK6_CPU0_PMDOWN'
 '@S9S_MB_2U_LIB.S9S_MB_2U(SCH_1):TP_H_SBLINK6_CPU0_PMDOWN':
 C_SIGNAL='@s9s_mb_2u_lib.s9s_mb_2u(sch_1):tp_h_sblink6_cpu0_pmdown';
NODE_NAME     U2 CE23
 '@S9S_MB_2U_LIB.S9S_MB_2U(SCH_1):PAGE14_I1@PURE_QUANTA.SOCKET4677_AZIF0045P001C01CS(CHIPS)':
 'PMDOWN5': CDS_PINID='PMDOWN5';
NET_NAME
'TP_H_SBLINK6_CPU0_PMSYNC'
 '@S9S_MB_2U_LIB.S9S_MB_2U(SCH_1):TP_H_SBLINK6_CPU0_PMSYNC':
 C_SIGNAL='@s9s_mb_2u_lib.s9s_mb_2u(sch_1):tp_h_sblink6_cpu0_pmsync';
NODE_NAME     U2 CH24
 '@S9S_MB_2U_LIB.S9S_MB_2U(SCH_1):PAGE14_I1@PURE_QUANTA.SOCKET4677_AZIF0045P001C01CS(CHIPS)':
 'PMSYNC5': CDS_PINID='PMSYNC5';
NET_NAME
'TP_H_SBLINK6_CPU1_PMDOWN'
 '@S9S_MB_2U_LIB.S9S_MB_2U(SCH_1):TP_H_SBLINK6_CPU1_PMDOWN':
 C_SIGNAL='@s9s_mb_2u_lib.s9s_mb_2u(sch_1):tp_h_sblink6_cpu1_pmdown';
NODE_NAME     U1 CE23
 '@S9S_MB_2U_LIB.S9S_MB_2U(SCH_1):PAGE45_I29@PURE_QUANTA.SOCKET4677_AZIF0045P001C01CS(CHIPS)':
 'PMDOWN5': CDS_PINID='PMDOWN5';
NET_NAME
'TP_H_SBLINK6_CPU1_PMSYNC'
 '@S9S_MB_2U_LIB.S9S_MB_2U(SCH_1):TP_H_SBLINK6_CPU1_PMSYNC':
 C_SIGNAL='@s9s_mb_2u_lib.s9s_mb_2u(sch_1):tp_h_sblink6_cpu1_pmsync';
NODE_NAME     U1 CH24
 '@S9S_MB_2U_LIB.S9S_MB_2U(SCH_1):PAGE45_I29@PURE_QUANTA.SOCKET4677_AZIF0045P001C01CS(CHIPS)':
 'PMSYNC5': CDS_PINID='PMSYNC5';
NET_NAME
'TP_H_SBLINK7_CPU0_PMDOWN'
 '@S9S_MB_2U_LIB.S9S_MB_2U(SCH_1):TP_H_SBLINK7_CPU0_PMDOWN':
 C_SIGNAL='@s9s_mb_2u_lib.s9s_mb_2u(sch_1):tp_h_sblink7_cpu0_pmdown';
NODE_NAME     U2 CC25
 '@S9S_MB_2U_LIB.S9S_MB_2U(SCH_1):PAGE14_I1@PURE_QUANTA.SOCKET4677_AZIF0045P001C01CS(CHIPS)':
 'PMDOWN6': CDS_PINID='PMDOWN6';
NET_NAME
'TP_H_SBLINK7_CPU0_PMSYNC'
 '@S9S_MB_2U_LIB.S9S_MB_2U(SCH_1):TP_H_SBLINK7_CPU0_PMSYNC':
 C_SIGNAL='@s9s_mb_2u_lib.s9s_mb_2u(sch_1):tp_h_sblink7_cpu0_pmsync';
NODE_NAME     U2 CF24
 '@S9S_MB_2U_LIB.S9S_MB_2U(SCH_1):PAGE14_I1@PURE_QUANTA.SOCKET4677_AZIF0045P001C01CS(CHIPS)':
 'PMSYNC6': CDS_PINID='PMSYNC6';
NET_NAME
'TP_H_SBLINK7_CPU1_PMDOWN'
 '@S9S_MB_2U_LIB.S9S_MB_2U(SCH_1):TP_H_SBLINK7_CPU1_PMDOWN':
 C_SIGNAL='@s9s_mb_2u_lib.s9s_mb_2u(sch_1):tp_h_sblink7_cpu1_pmdown';
NODE_NAME     U1 CC25
 '@S9S_MB_2U_LIB.S9S_MB_2U(SCH_1):PAGE45_I29@PURE_QUANTA.SOCKET4677_AZIF0045P001C01CS(CHIPS)':
 'PMDOWN6': CDS_PINID='PMDOWN6';
NET_NAME
'TP_H_SBLINK7_CPU1_PMSYNC'
 '@S9S_MB_2U_LIB.S9S_MB_2U(SCH_1):TP_H_SBLINK7_CPU1_PMSYNC':
 C_SIGNAL='@s9s_mb_2u_lib.s9s_mb_2u(sch_1):tp_h_sblink7_cpu1_pmsync';
NODE_NAME     U1 CF24
 '@S9S_MB_2U_LIB.S9S_MB_2U(SCH_1):PAGE45_I29@PURE_QUANTA.SOCKET4677_AZIF0045P001C01CS(CHIPS)':
 'PMSYNC6': CDS_PINID='PMSYNC6';
NET_NAME
'TP_I2C_S3M_RTC_CPU0_ALERT_N'
 '@S9S_MB_2U_LIB.S9S_MB_2U(SCH_1):TP_I2C_S3M_RTC_CPU0_ALERT_N':
 C_SIGNAL='@s9s_mb_2u_lib.s9s_mb_2u(sch_1):tp_i2c_s3m_rtc_cpu0_alert_n';
NODE_NAME     U2 CJ25
 '@S9S_MB_2U_LIB.S9S_MB_2U(SCH_1):PAGE15_I1@PURE_QUANTA.SOCKET4677_AZIF0045P001C01CS(CHIPS)':
 'RSVD103': CDS_PINID='RSVD103';
NET_NAME
'TP_I2C_S3M_RTC_CPU0_SCL'
 '@S9S_MB_2U_LIB.S9S_MB_2U(SCH_1):TP_I2C_S3M_RTC_CPU0_SCL':
 C_SIGNAL='@s9s_mb_2u_lib.s9s_mb_2u(sch_1):tp_i2c_s3m_rtc_cpu0_scl';
NODE_NAME     U2 CL23
 '@S9S_MB_2U_LIB.S9S_MB_2U(SCH_1):PAGE15_I1@PURE_QUANTA.SOCKET4677_AZIF0045P001C01CS(CHIPS)':
 'RSVD114': CDS_PINID='RSVD114';
NET_NAME
'TP_I2C_S3M_RTC_CPU0_SDA'
 '@S9S_MB_2U_LIB.S9S_MB_2U(SCH_1):TP_I2C_S3M_RTC_CPU0_SDA':
 C_SIGNAL='@s9s_mb_2u_lib.s9s_mb_2u(sch_1):tp_i2c_s3m_rtc_cpu0_sda';
NODE_NAME     U2 CJ23
 '@S9S_MB_2U_LIB.S9S_MB_2U(SCH_1):PAGE15_I1@PURE_QUANTA.SOCKET4677_AZIF0045P001C01CS(CHIPS)':
 'RSVD102': CDS_PINID='RSVD102';
NET_NAME
'TP_I2C_S3M_RTC_CPU1_RST_N'
 '@S9S_MB_2U_LIB.S9S_MB_2U(SCH_1):TP_I2C_S3M_RTC_CPU1_RST_N':
 C_SIGNAL='@s9s_mb_2u_lib.s9s_mb_2u(sch_1):tp_i2c_s3m_rtc_cpu1_rst_n';
NODE_NAME     U1 CJ25
 '@S9S_MB_2U_LIB.S9S_MB_2U(SCH_1):PAGE46_I5@PURE_QUANTA.SOCKET4677_AZIF0045P001C01CS(CHIPS)':
 'RSVD103': CDS_PINID='RSVD103';
NET_NAME
'TP_I2C_S3M_RTC_CPU1_SCL'
 '@S9S_MB_2U_LIB.S9S_MB_2U(SCH_1):TP_I2C_S3M_RTC_CPU1_SCL':
 C_SIGNAL='@s9s_mb_2u_lib.s9s_mb_2u(sch_1):tp_i2c_s3m_rtc_cpu1_scl';
NODE_NAME     U1 CL23
 '@S9S_MB_2U_LIB.S9S_MB_2U(SCH_1):PAGE46_I5@PURE_QUANTA.SOCKET4677_AZIF0045P001C01CS(CHIPS)':
 'RSVD114': CDS_PINID='RSVD114';
NET_NAME
'TP_I2C_S3M_RTC_CPU1_SDA'
 '@S9S_MB_2U_LIB.S9S_MB_2U(SCH_1):TP_I2C_S3M_RTC_CPU1_SDA':
 C_SIGNAL='@s9s_mb_2u_lib.s9s_mb_2u(sch_1):tp_i2c_s3m_rtc_cpu1_sda';
NODE_NAME     U1 CJ23
 '@S9S_MB_2U_LIB.S9S_MB_2U(SCH_1):PAGE46_I5@PURE_QUANTA.SOCKET4677_AZIF0045P001C01CS(CHIPS)':
 'RSVD102': CDS_PINID='RSVD102';
NET_NAME
'TP_I3C_MNG2_BMC_SW_SCL'
 '@S9S_MB_2U_LIB.S9S_MB_2U(SCH_1):TP_I3C_MNG2_BMC_SW_SCL':
 C_SIGNAL='@s9s_mb_2u_lib.s9s_mb_2u(sch_1):tp_i3c_mng2_bmc_sw_scl';
NODE_NAME     U2 BE25
 '@S9S_MB_2U_LIB.S9S_MB_2U(SCH_1):PAGE15_I1@PURE_QUANTA.SOCKET4677_AZIF0045P001C01CS(CHIPS)':
 'RSVD47': CDS_PINID='RSVD47';
NET_NAME
'TP_I3C_MNG2_BMC_SW_SDA'
 '@S9S_MB_2U_LIB.S9S_MB_2U(SCH_1):TP_I3C_MNG2_BMC_SW_SDA':
 C_SIGNAL='@s9s_mb_2u_lib.s9s_mb_2u(sch_1):tp_i3c_mng2_bmc_sw_sda';
NODE_NAME     U2 BC25
 '@S9S_MB_2U_LIB.S9S_MB_2U(SCH_1):PAGE15_I1@PURE_QUANTA.SOCKET4677_AZIF0045P001C01CS(CHIPS)':
 'RSVD38': CDS_PINID='RSVD38';
NET_NAME
'TP_I3C_MNG3_BMC_SW_SCL'
 '@S9S_MB_2U_LIB.S9S_MB_2U(SCH_1):TP_I3C_MNG3_BMC_SW_SCL':
 C_SIGNAL='@s9s_mb_2u_lib.s9s_mb_2u(sch_1):tp_i3c_mng3_bmc_sw_scl';
NODE_NAME     U1 BE25
 '@S9S_MB_2U_LIB.S9S_MB_2U(SCH_1):PAGE46_I5@PURE_QUANTA.SOCKET4677_AZIF0045P001C01CS(CHIPS)':
 'RSVD47': CDS_PINID='RSVD47';
NET_NAME
'TP_I3C_MNG3_BMC_SW_SDA'
 '@S9S_MB_2U_LIB.S9S_MB_2U(SCH_1):TP_I3C_MNG3_BMC_SW_SDA':
 C_SIGNAL='@s9s_mb_2u_lib.s9s_mb_2u(sch_1):tp_i3c_mng3_bmc_sw_sda';
NODE_NAME     U1 BC25
 '@S9S_MB_2U_LIB.S9S_MB_2U(SCH_1):PAGE46_I5@PURE_QUANTA.SOCKET4677_AZIF0045P001C01CS(CHIPS)':
 'RSVD38': CDS_PINID='RSVD38';
NET_NAME
'TP_IBL_GRST_WARN_PLD_R_N'
 '@S9S_MB_2U_LIB.S9S_MB_2U(SCH_1):TP_IBL_GRST_WARN_PLD_R_N':
 C_SIGNAL='@s9s_mb_2u_lib.s9s_mb_2u(sch_1):tp_ibl_grst_warn_pld_r_n';
NODE_NAME     U2 CJ21
 '@S9S_MB_2U_LIB.S9S_MB_2U(SCH_1):PAGE15_I1@PURE_QUANTA.SOCKET4677_AZIF0045P001C01CS(CHIPS)':
 'RSVD101': CDS_PINID='RSVD101';
NET_NAME
'TP_IBL_PLT_RST_SYNC_N'
 '@S9S_MB_2U_LIB.S9S_MB_2U(SCH_1):TP_IBL_PLT_RST_SYNC_N':
 C_SIGNAL='@s9s_mb_2u_lib.s9s_mb_2u(sch_1):tp_ibl_plt_rst_sync_n';
NODE_NAME     U2 CL21
 '@S9S_MB_2U_LIB.S9S_MB_2U(SCH_1):PAGE14_I1@PURE_QUANTA.SOCKET4677_AZIF0045P001C01CS(CHIPS)':
 'RSVD113': CDS_PINID='RSVD113';
NET_NAME
'TP_IBL_SLPS3_CPU0_R_N'
 '@S9S_MB_2U_LIB.S9S_MB_2U(SCH_1):TP_IBL_SLPS3_CPU0_R_N':
 C_SIGNAL='@s9s_mb_2u_lib.s9s_mb_2u(sch_1):tp_ibl_slps3_cpu0_r_n';
NODE_NAME     U2 CR21
 '@S9S_MB_2U_LIB.S9S_MB_2U(SCH_1):PAGE15_I1@PURE_QUANTA.SOCKET4677_AZIF0045P001C01CS(CHIPS)':
 'RSVD131': CDS_PINID='RSVD131';
NET_NAME
'TP_IBL_SLPS4_CPU0_R_N'
 '@S9S_MB_2U_LIB.S9S_MB_2U(SCH_1):TP_IBL_SLPS4_CPU0_R_N':
 C_SIGNAL='@s9s_mb_2u_lib.s9s_mb_2u(sch_1):tp_ibl_slps4_cpu0_r_n';
NODE_NAME     U2 CN21
 '@S9S_MB_2U_LIB.S9S_MB_2U(SCH_1):PAGE15_I1@PURE_QUANTA.SOCKET4677_AZIF0045P001C01CS(CHIPS)':
 'RSVD123': CDS_PINID='RSVD123';
NET_NAME
'TP_IBL_SLPS5_CPU0_R_N'
 '@S9S_MB_2U_LIB.S9S_MB_2U(SCH_1):TP_IBL_SLPS5_CPU0_R_N':
 C_SIGNAL='@s9s_mb_2u_lib.s9s_mb_2u(sch_1):tp_ibl_slps5_cpu0_r_n';
NODE_NAME     U2 CW21
 '@S9S_MB_2U_LIB.S9S_MB_2U(SCH_1):PAGE15_I1@PURE_QUANTA.SOCKET4677_AZIF0045P001C01CS(CHIPS)':
 'RSVD144': CDS_PINID='RSVD144';
NET_NAME
'TP_J45_A1'
 '@S9S_MB_2U_LIB.S9S_MB_2U(SCH_1):TP_J45_A1':
 C_SIGNAL='@s9s_mb_2u_lib.s9s_mb_2u(sch_1):tp_j45_a1';
NODE_NAME     J45 A1
 '@S9S_MB_2U_LIB.S9S_MB_2U(SCH_1):PAGE233_I12@PURE_QUANTA.CONN60_101062636003K02LF(CHIPS)':
 'A1': CDS_PINID='A1';
NET_NAME
'TP_JTAG_BMC_1B'
 '@S9S_MB_2U_LIB.S9S_MB_2U(SCH_1):TP_JTAG_BMC_1B':
 C_SIGNAL='@s9s_mb_2u_lib.s9s_mb_2u(sch_1):tp_jtag_bmc_1b';
NODE_NAME     U86 3
 '@S9S_MB_2U_LIB.S9S_MB_2U(SCH_1):PAGE137_I84@PURE_QUANTA.74CBTLV3126PW(CHIPS)':
 '1B': CDS_PINID='\1b\';
NET_NAME
'TP_JTAG_BMC_4B'
 '@S9S_MB_2U_LIB.S9S_MB_2U(SCH_1):TP_JTAG_BMC_4B':
 C_SIGNAL='@s9s_mb_2u_lib.s9s_mb_2u(sch_1):tp_jtag_bmc_4b';
NODE_NAME     U86 11
 '@S9S_MB_2U_LIB.S9S_MB_2U(SCH_1):PAGE137_I84@PURE_QUANTA.74CBTLV3126PW(CHIPS)':
 '4B': CDS_PINID='\4b\';
NET_NAME
'TP_JTAG_BMC_A0'
 '@S9S_MB_2U_LIB.S9S_MB_2U(SCH_1):TP_JTAG_BMC_A0':
 C_SIGNAL='@s9s_mb_2u_lib.s9s_mb_2u(sch_1):tp_jtag_bmc_a0';
NODE_NAME     U83 13
 '@S9S_MB_2U_LIB.S9S_MB_2U(SCH_1):PAGE226_I45@PURE_QUANTA.GTL2014PW(CHIPS)':
 'A0': CDS_PINID='A0';
NET_NAME
'TP_JTAG_BMC_A2'
 '@S9S_MB_2U_LIB.S9S_MB_2U(SCH_1):TP_JTAG_BMC_A2':
 C_SIGNAL='@s9s_mb_2u_lib.s9s_mb_2u(sch_1):tp_jtag_bmc_a2';
NODE_NAME     U83 10
 '@S9S_MB_2U_LIB.S9S_MB_2U(SCH_1):PAGE226_I45@PURE_QUANTA.GTL2014PW(CHIPS)':
 'A2': CDS_PINID='A2';
NET_NAME
'TP_JTAG_CPU0_PLD_TDI'
 '@S9S_MB_2U_LIB.S9S_MB_2U(SCH_1):TP_JTAG_CPU0_PLD_TDI':
 C_SIGNAL='@s9s_mb_2u_lib.s9s_mb_2u(sch_1):tp_jtag_cpu0_pld_tdi';
NODE_NAME     U2 CT22
 '@S9S_MB_2U_LIB.S9S_MB_2U(SCH_1):PAGE15_I1@PURE_QUANTA.SOCKET4677_AZIF0045P001C01CS(CHIPS)':
 'RSVD136': CDS_PINID='RSVD136';
NET_NAME
'TP_JTAG_CPU0_PLD_TDO'
 '@S9S_MB_2U_LIB.S9S_MB_2U(SCH_1):TP_JTAG_CPU0_PLD_TDO':
 C_SIGNAL='@s9s_mb_2u_lib.s9s_mb_2u(sch_1):tp_jtag_cpu0_pld_tdo';
NODE_NAME     U2 CP22
 '@S9S_MB_2U_LIB.S9S_MB_2U(SCH_1):PAGE15_I1@PURE_QUANTA.SOCKET4677_AZIF0045P001C01CS(CHIPS)':
 'RSVD127': CDS_PINID='RSVD127';
NET_NAME
'TP_JTAG_CPU0_PLD_TMS'
 '@S9S_MB_2U_LIB.S9S_MB_2U(SCH_1):TP_JTAG_CPU0_PLD_TMS':
 C_SIGNAL='@s9s_mb_2u_lib.s9s_mb_2u(sch_1):tp_jtag_cpu0_pld_tms';
NODE_NAME     U2 CV22
 '@S9S_MB_2U_LIB.S9S_MB_2U(SCH_1):PAGE15_I1@PURE_QUANTA.SOCKET4677_AZIF0045P001C01CS(CHIPS)':
 'RSVD140': CDS_PINID='RSVD140';
NET_NAME
'TP_JTAG_CPU1_PLD_TDI'
 '@S9S_MB_2U_LIB.S9S_MB_2U(SCH_1):TP_JTAG_CPU1_PLD_TDI':
 C_SIGNAL='@s9s_mb_2u_lib.s9s_mb_2u(sch_1):tp_jtag_cpu1_pld_tdi';
NODE_NAME     U1 CT22
 '@S9S_MB_2U_LIB.S9S_MB_2U(SCH_1):PAGE46_I5@PURE_QUANTA.SOCKET4677_AZIF0045P001C01CS(CHIPS)':
 'RSVD136': CDS_PINID='RSVD136';
NET_NAME
'TP_JTAG_CPU1_PLD_TDO_R'
 '@S9S_MB_2U_LIB.S9S_MB_2U(SCH_1):TP_JTAG_CPU1_PLD_TDO_R':
 C_SIGNAL='@s9s_mb_2u_lib.s9s_mb_2u(sch_1):tp_jtag_cpu1_pld_tdo_r';
NODE_NAME     U1 CP22
 '@S9S_MB_2U_LIB.S9S_MB_2U(SCH_1):PAGE46_I5@PURE_QUANTA.SOCKET4677_AZIF0045P001C01CS(CHIPS)':
 'RSVD127': CDS_PINID='RSVD127';
NET_NAME
'TP_JTAG_CPU1_PLD_TMS'
 '@S9S_MB_2U_LIB.S9S_MB_2U(SCH_1):TP_JTAG_CPU1_PLD_TMS':
 C_SIGNAL='@s9s_mb_2u_lib.s9s_mb_2u(sch_1):tp_jtag_cpu1_pld_tms';
NODE_NAME     U1 CV22
 '@S9S_MB_2U_LIB.S9S_MB_2U(SCH_1):PAGE46_I5@PURE_QUANTA.SOCKET4677_AZIF0045P001C01CS(CHIPS)':
 'RSVD140': CDS_PINID='RSVD140';
NET_NAME
'TP_OCP_SFF_B68'
 '@S9S_MB_2U_LIB.S9S_MB_2U(SCH_1):TP_OCP_SFF_B68':
 C_SIGNAL='@s9s_mb_2u_lib.s9s_mb_2u(sch_1):tp_ocp_sff_b68';
NODE_NAME     J37 B68
 '@S9S_MB_2U_LIB.S9S_MB_2U(SCH_1):PAGE150_I199@PURE_QUANTA.SCONN168_ME1016810202011(CHIPS)':
 'RFU1_NC_B68': CDS_PINID='RFU1_NC_B68';
NET_NAME
'TP_OCP_SFF_B69'
 '@S9S_MB_2U_LIB.S9S_MB_2U(SCH_1):TP_OCP_SFF_B69':
 C_SIGNAL='@s9s_mb_2u_lib.s9s_mb_2u(sch_1):tp_ocp_sff_b69';
NODE_NAME     J37 B69
 '@S9S_MB_2U_LIB.S9S_MB_2U(SCH_1):PAGE150_I199@PURE_QUANTA.SCONN168_ME1016810202011(CHIPS)':
 'RFU1_NC_B69': CDS_PINID='RFU1_NC_B69';
NET_NAME
'TP_OCP_V3_2_B68'
 '@S9S_MB_2U_LIB.S9S_MB_2U(SCH_1):TP_OCP_V3_2_B68':
 C_SIGNAL='@s9s_mb_2u_lib.s9s_mb_2u(sch_1):tp_ocp_v3_2_b68';
NODE_NAME     J35 B68
 '@S9S_MB_2U_LIB.S9S_MB_2U(SCH_1):PAGE146_I303@PURE_QUANTA.SCONN168_ME1016810202011(CHIPS)':
 'RFU1_NC_B68': CDS_PINID='RFU1_NC_B68';
NET_NAME
'TP_OCP_V3_2_B69'
 '@S9S_MB_2U_LIB.S9S_MB_2U(SCH_1):TP_OCP_V3_2_B69':
 C_SIGNAL='@s9s_mb_2u_lib.s9s_mb_2u(sch_1):tp_ocp_v3_2_b69';
NODE_NAME     J35 B69
 '@S9S_MB_2U_LIB.S9S_MB_2U(SCH_1):PAGE146_I303@PURE_QUANTA.SCONN168_ME1016810202011(CHIPS)':
 'RFU1_NC_B69': CDS_PINID='RFU1_NC_B69';
NET_NAME
'TP_P3E_PCH_12_RX_DN'
 '@S9S_MB_2U_LIB.S9S_MB_2U(SCH_1):TP_P3E_PCH_12_RX_DN':
 C_SIGNAL='@s9s_mb_2u_lib.s9s_mb_2u(sch_1):tp_p3e_pch_12_rx_dn';
NODE_NAME     U4 K41
 '@S9S_MB_2U_LIB.S9S_MB_2U(SCH_1):PAGE173_I110@PURE_QUANTA.EMMITSBURG_REV0P9(CHIPS)':
 'SATA_12_PCIE3_12_GBE_1_RXN': CDS_PINID='SATA_12_PCIE3_12_GBE_1_RXN';
NET_NAME
'TP_P3E_PCH_12_RX_DP'
 '@S9S_MB_2U_LIB.S9S_MB_2U(SCH_1):TP_P3E_PCH_12_RX_DP':
 C_SIGNAL='@s9s_mb_2u_lib.s9s_mb_2u(sch_1):tp_p3e_pch_12_rx_dp';
NODE_NAME     U4 K43
 '@S9S_MB_2U_LIB.S9S_MB_2U(SCH_1):PAGE173_I110@PURE_QUANTA.EMMITSBURG_REV0P9(CHIPS)':
 'SATA_12_PCIE3_12_GBE_1_RXP': CDS_PINID='SATA_12_PCIE3_12_GBE_1_RXP';
NET_NAME
'TP_P3E_PCH_12_TX_DN'
 '@S9S_MB_2U_LIB.S9S_MB_2U(SCH_1):TP_P3E_PCH_12_TX_DN':
 C_SIGNAL='@s9s_mb_2u_lib.s9s_mb_2u(sch_1):tp_p3e_pch_12_tx_dn';
NODE_NAME     U4 V34
 '@S9S_MB_2U_LIB.S9S_MB_2U(SCH_1):PAGE173_I110@PURE_QUANTA.EMMITSBURG_REV0P9(CHIPS)':
 'SATA_12_PCIE3_12_GBE_1_TXN': CDS_PINID='SATA_12_PCIE3_12_GBE_1_TXN';
NET_NAME
'TP_P3E_PCH_12_TX_DP'
 '@S9S_MB_2U_LIB.S9S_MB_2U(SCH_1):TP_P3E_PCH_12_TX_DP':
 C_SIGNAL='@s9s_mb_2u_lib.s9s_mb_2u(sch_1):tp_p3e_pch_12_tx_dp';
NODE_NAME     U4 U36
 '@S9S_MB_2U_LIB.S9S_MB_2U(SCH_1):PAGE173_I110@PURE_QUANTA.EMMITSBURG_REV0P9(CHIPS)':
 'SATA_12_PCIE3_12_GBE_1_TXP': CDS_PINID='SATA_12_PCIE3_12_GBE_1_TXP';
NET_NAME
'TP_P3E_PCH_13_RX_DN'
 '@S9S_MB_2U_LIB.S9S_MB_2U(SCH_1):TP_P3E_PCH_13_RX_DN':
 C_SIGNAL='@s9s_mb_2u_lib.s9s_mb_2u(sch_1):tp_p3e_pch_13_rx_dn';
NODE_NAME     U4 J40
 '@S9S_MB_2U_LIB.S9S_MB_2U(SCH_1):PAGE173_I110@PURE_QUANTA.EMMITSBURG_REV0P9(CHIPS)':
 'SATA_13_PCIE3_13_RXN': CDS_PINID='SATA_13_PCIE3_13_RXN';
NET_NAME
'TP_P3E_PCH_13_RX_DP'
 '@S9S_MB_2U_LIB.S9S_MB_2U(SCH_1):TP_P3E_PCH_13_RX_DP':
 C_SIGNAL='@s9s_mb_2u_lib.s9s_mb_2u(sch_1):tp_p3e_pch_13_rx_dp';
NODE_NAME     U4 J42
 '@S9S_MB_2U_LIB.S9S_MB_2U(SCH_1):PAGE173_I110@PURE_QUANTA.EMMITSBURG_REV0P9(CHIPS)':
 'SATA_13_PCIE3_13_RXP': CDS_PINID='SATA_13_PCIE3_13_RXP';
NET_NAME
'TP_P3E_PCH_13_TX_DN'
 '@S9S_MB_2U_LIB.S9S_MB_2U(SCH_1):TP_P3E_PCH_13_TX_DN':
 C_SIGNAL='@s9s_mb_2u_lib.s9s_mb_2u(sch_1):tp_p3e_pch_13_tx_dn';
NODE_NAME     U4 U32
 '@S9S_MB_2U_LIB.S9S_MB_2U(SCH_1):PAGE173_I110@PURE_QUANTA.EMMITSBURG_REV0P9(CHIPS)':
 'SATA_13_PCIE3_13_TXN': CDS_PINID='SATA_13_PCIE3_13_TXN';
NET_NAME
'TP_P3E_PCH_13_TX_DP'
 '@S9S_MB_2U_LIB.S9S_MB_2U(SCH_1):TP_P3E_PCH_13_TX_DP':
 C_SIGNAL='@s9s_mb_2u_lib.s9s_mb_2u(sch_1):tp_p3e_pch_13_tx_dp';
NODE_NAME     U4 W32
 '@S9S_MB_2U_LIB.S9S_MB_2U(SCH_1):PAGE173_I110@PURE_QUANTA.EMMITSBURG_REV0P9(CHIPS)':
 'SATA_13_PCIE3_13_TXP': CDS_PINID='SATA_13_PCIE3_13_TXP';
NET_NAME
'TP_P3E_PCH_14_RX_DN'
 '@S9S_MB_2U_LIB.S9S_MB_2U(SCH_1):TP_P3E_PCH_14_RX_DN':
 C_SIGNAL='@s9s_mb_2u_lib.s9s_mb_2u(sch_1):tp_p3e_pch_14_rx_dn';
NODE_NAME     U4 H41
 '@S9S_MB_2U_LIB.S9S_MB_2U(SCH_1):PAGE173_I110@PURE_QUANTA.EMMITSBURG_REV0P9(CHIPS)':
 'SATA_14_PCIE3_14_GBE_2_RXN': CDS_PINID='SATA_14_PCIE3_14_GBE_2_RXN';
NET_NAME
'TP_P3E_PCH_14_RX_DP'
 '@S9S_MB_2U_LIB.S9S_MB_2U(SCH_1):TP_P3E_PCH_14_RX_DP':
 C_SIGNAL='@s9s_mb_2u_lib.s9s_mb_2u(sch_1):tp_p3e_pch_14_rx_dp';
NODE_NAME     U4 H43
 '@S9S_MB_2U_LIB.S9S_MB_2U(SCH_1):PAGE173_I110@PURE_QUANTA.EMMITSBURG_REV0P9(CHIPS)':
 'SATA_14_PCIE3_14_GBE_2_RXP': CDS_PINID='SATA_14_PCIE3_14_GBE_2_RXP';
NET_NAME
'TP_P3E_PCH_14_TX_DN'
 '@S9S_MB_2U_LIB.S9S_MB_2U(SCH_1):TP_P3E_PCH_14_TX_DN':
 C_SIGNAL='@s9s_mb_2u_lib.s9s_mb_2u(sch_1):tp_p3e_pch_14_tx_dn';
NODE_NAME     U4 R32
 '@S9S_MB_2U_LIB.S9S_MB_2U(SCH_1):PAGE173_I110@PURE_QUANTA.EMMITSBURG_REV0P9(CHIPS)':
 'SATA_14_PCIE3_14_GBE_2_TXN': CDS_PINID='SATA_14_PCIE3_14_GBE_2_TXN';
NET_NAME
'TP_P3E_PCH_14_TX_DP'
 '@S9S_MB_2U_LIB.S9S_MB_2U(SCH_1):TP_P3E_PCH_14_TX_DP':
 C_SIGNAL='@s9s_mb_2u_lib.s9s_mb_2u(sch_1):tp_p3e_pch_14_tx_dp';
NODE_NAME     U4 T34
 '@S9S_MB_2U_LIB.S9S_MB_2U(SCH_1):PAGE173_I110@PURE_QUANTA.EMMITSBURG_REV0P9(CHIPS)':
 'SATA_14_PCIE3_14_GBE_2_TXP': CDS_PINID='SATA_14_PCIE3_14_GBE_2_TXP';
NET_NAME
'TP_P3E_PCH_15_RX_DN'
 '@S9S_MB_2U_LIB.S9S_MB_2U(SCH_1):TP_P3E_PCH_15_RX_DN':
 C_SIGNAL='@s9s_mb_2u_lib.s9s_mb_2u(sch_1):tp_p3e_pch_15_rx_dn';
NODE_NAME     U4 G40
 '@S9S_MB_2U_LIB.S9S_MB_2U(SCH_1):PAGE173_I110@PURE_QUANTA.EMMITSBURG_REV0P9(CHIPS)':
 'SATA_15_PCIE3_15_RXN': CDS_PINID='SATA_15_PCIE3_15_RXN';
NET_NAME
'TP_P3E_PCH_15_RX_DP'
 '@S9S_MB_2U_LIB.S9S_MB_2U(SCH_1):TP_P3E_PCH_15_RX_DP':
 C_SIGNAL='@s9s_mb_2u_lib.s9s_mb_2u(sch_1):tp_p3e_pch_15_rx_dp';
NODE_NAME     U4 G42
 '@S9S_MB_2U_LIB.S9S_MB_2U(SCH_1):PAGE173_I110@PURE_QUANTA.EMMITSBURG_REV0P9(CHIPS)':
 'SATA_15_PCIE3_15_RXP': CDS_PINID='SATA_15_PCIE3_15_RXP';
NET_NAME
'TP_P3E_PCH_15_TX_DN'
 '@S9S_MB_2U_LIB.S9S_MB_2U(SCH_1):TP_P3E_PCH_15_TX_DN':
 C_SIGNAL='@s9s_mb_2u_lib.s9s_mb_2u(sch_1):tp_p3e_pch_15_tx_dn';
NODE_NAME     U4 P34
 '@S9S_MB_2U_LIB.S9S_MB_2U(SCH_1):PAGE173_I110@PURE_QUANTA.EMMITSBURG_REV0P9(CHIPS)':
 'SATA_15_PCIE3_15_TXN': CDS_PINID='SATA_15_PCIE3_15_TXN';
NET_NAME
'TP_P3E_PCH_15_TX_DP'
 '@S9S_MB_2U_LIB.S9S_MB_2U(SCH_1):TP_P3E_PCH_15_TX_DP':
 C_SIGNAL='@s9s_mb_2u_lib.s9s_mb_2u(sch_1):tp_p3e_pch_15_tx_dp';
NODE_NAME     U4 N36
 '@S9S_MB_2U_LIB.S9S_MB_2U(SCH_1):PAGE173_I110@PURE_QUANTA.EMMITSBURG_REV0P9(CHIPS)':
 'SATA_15_PCIE3_15_TXP': CDS_PINID='SATA_15_PCIE3_15_TXP';
NET_NAME
'TP_P3V3_E1S_PWRGD_0'
 '@S9S_MB_2U_LIB.S9S_MB_2U(SCH_1):TP_P3V3_E1S_PWRGD_0':
 C_SIGNAL='@s9s_mb_2u_lib.s9s_mb_2u(sch_1):tp_p3v3_e1s_pwrgd_0';
NODE_NAME     R3973 2
 '@S9S_MB_2U_LIB.S9S_MB_2U(SCH_1):PAGE324_I44@PURE_QUANTA.Q_RES(CHIPS)':
 'B': CDS_PINID='B';
NODE_NAME     R3979 2
 '@S9S_MB_2U_LIB.S9S_MB_2U(SCH_1):PAGE324_I50@PURE_QUANTA.Q_RES(CHIPS)':
 'B': CDS_PINID='B';
NET_NAME
'TP_PCA9555_0_P00'
 '@S9S_MB_2U_LIB.S9S_MB_2U(SCH_1):TP_PCA9555_0_P00':
 C_SIGNAL='@s9s_mb_2u_lib.s9s_mb_2u(sch_1):tp_pca9555_0_p00';
NODE_NAME     U209 4
 '@S9S_MB_2U_LIB.S9S_MB_2U(SCH_1):PAGE154_I206@PURE_QUANTA.PCA9555APW(CHIPS)':
 'P0_0': CDS_PINID='P0_0';
NET_NAME
'TP_PCA9555_0_P01'
 '@S9S_MB_2U_LIB.S9S_MB_2U(SCH_1):TP_PCA9555_0_P01':
 C_SIGNAL='@s9s_mb_2u_lib.s9s_mb_2u(sch_1):tp_pca9555_0_p01';
NODE_NAME     U209 5
 '@S9S_MB_2U_LIB.S9S_MB_2U(SCH_1):PAGE154_I206@PURE_QUANTA.PCA9555APW(CHIPS)':
 'P0_1': CDS_PINID='P0_1';
NET_NAME
'TP_PCA9555_0_P10'
 '@S9S_MB_2U_LIB.S9S_MB_2U(SCH_1):TP_PCA9555_0_P10':
 C_SIGNAL='@s9s_mb_2u_lib.s9s_mb_2u(sch_1):tp_pca9555_0_p10';
NODE_NAME     U209 13
 '@S9S_MB_2U_LIB.S9S_MB_2U(SCH_1):PAGE154_I206@PURE_QUANTA.PCA9555APW(CHIPS)':
 'P1_0': CDS_PINID='P1_0';
NET_NAME
'TP_PCA9555_0_P11'
 '@S9S_MB_2U_LIB.S9S_MB_2U(SCH_1):TP_PCA9555_0_P11':
 C_SIGNAL='@s9s_mb_2u_lib.s9s_mb_2u(sch_1):tp_pca9555_0_p11';
NODE_NAME     U209 14
 '@S9S_MB_2U_LIB.S9S_MB_2U(SCH_1):PAGE154_I206@PURE_QUANTA.PCA9555APW(CHIPS)':
 'P1_1': CDS_PINID='P1_1';
NET_NAME
'TP_PCA9555_0_P12'
 '@S9S_MB_2U_LIB.S9S_MB_2U(SCH_1):TP_PCA9555_0_P12':
 C_SIGNAL='@s9s_mb_2u_lib.s9s_mb_2u(sch_1):tp_pca9555_0_p12';
NODE_NAME     U209 15
 '@S9S_MB_2U_LIB.S9S_MB_2U(SCH_1):PAGE154_I206@PURE_QUANTA.PCA9555APW(CHIPS)':
 'P1_2': CDS_PINID='P1_2';
NET_NAME
'TP_PCA9555_0_P13'
 '@S9S_MB_2U_LIB.S9S_MB_2U(SCH_1):TP_PCA9555_0_P13':
 C_SIGNAL='@s9s_mb_2u_lib.s9s_mb_2u(sch_1):tp_pca9555_0_p13';
NODE_NAME     U209 16
 '@S9S_MB_2U_LIB.S9S_MB_2U(SCH_1):PAGE154_I206@PURE_QUANTA.PCA9555APW(CHIPS)':
 'P1_3': CDS_PINID='P1_3';
NET_NAME
'TP_PCA9555_0_P14'
 '@S9S_MB_2U_LIB.S9S_MB_2U(SCH_1):TP_PCA9555_0_P14':
 C_SIGNAL='@s9s_mb_2u_lib.s9s_mb_2u(sch_1):tp_pca9555_0_p14';
NODE_NAME     U209 17
 '@S9S_MB_2U_LIB.S9S_MB_2U(SCH_1):PAGE154_I206@PURE_QUANTA.PCA9555APW(CHIPS)':
 'P1_4': CDS_PINID='P1_4';
NET_NAME
'TP_PCA9555_0_P15'
 '@S9S_MB_2U_LIB.S9S_MB_2U(SCH_1):TP_PCA9555_0_P15':
 C_SIGNAL='@s9s_mb_2u_lib.s9s_mb_2u(sch_1):tp_pca9555_0_p15';
NODE_NAME     U209 18
 '@S9S_MB_2U_LIB.S9S_MB_2U(SCH_1):PAGE154_I206@PURE_QUANTA.PCA9555APW(CHIPS)':
 'P1_5': CDS_PINID='P1_5';
NET_NAME
'TP_PCA9555_0_P16'
 '@S9S_MB_2U_LIB.S9S_MB_2U(SCH_1):TP_PCA9555_0_P16':
 C_SIGNAL='@s9s_mb_2u_lib.s9s_mb_2u(sch_1):tp_pca9555_0_p16';
NODE_NAME     U209 19
 '@S9S_MB_2U_LIB.S9S_MB_2U(SCH_1):PAGE154_I206@PURE_QUANTA.PCA9555APW(CHIPS)':
 'P1_6': CDS_PINID='P1_6';
NET_NAME
'TP_PCA9555_0_P17'
 '@S9S_MB_2U_LIB.S9S_MB_2U(SCH_1):TP_PCA9555_0_P17':
 C_SIGNAL='@s9s_mb_2u_lib.s9s_mb_2u(sch_1):tp_pca9555_0_p17';
NODE_NAME     U209 20
 '@S9S_MB_2U_LIB.S9S_MB_2U(SCH_1):PAGE154_I206@PURE_QUANTA.PCA9555APW(CHIPS)':
 'P1_7': CDS_PINID='P1_7';
NET_NAME
'TP_PCA9555_0_P5'
 '@S9S_MB_2U_LIB.S9S_MB_2U(SCH_1):TP_PCA9555_0_P5':
 C_SIGNAL='@s9s_mb_2u_lib.s9s_mb_2u(sch_1):tp_pca9555_0_p5';
NODE_NAME     U209 9
 '@S9S_MB_2U_LIB.S9S_MB_2U(SCH_1):PAGE154_I206@PURE_QUANTA.PCA9555APW(CHIPS)':
 'P0_5': CDS_PINID='P0_5';
NET_NAME
'TP_PCA9555_0_P6'
 '@S9S_MB_2U_LIB.S9S_MB_2U(SCH_1):TP_PCA9555_0_P6':
 C_SIGNAL='@s9s_mb_2u_lib.s9s_mb_2u(sch_1):tp_pca9555_0_p6';
NODE_NAME     U209 10
 '@S9S_MB_2U_LIB.S9S_MB_2U(SCH_1):PAGE154_I206@PURE_QUANTA.PCA9555APW(CHIPS)':
 'P0_6': CDS_PINID='P0_6';
NET_NAME
'TP_PCA9555_0_P7'
 '@S9S_MB_2U_LIB.S9S_MB_2U(SCH_1):TP_PCA9555_0_P7':
 C_SIGNAL='@s9s_mb_2u_lib.s9s_mb_2u(sch_1):tp_pca9555_0_p7';
NODE_NAME     U209 11
 '@S9S_MB_2U_LIB.S9S_MB_2U(SCH_1):PAGE154_I206@PURE_QUANTA.PCA9555APW(CHIPS)':
 'P0_7': CDS_PINID='P0_7';
NET_NAME
'TP_PCA9555_U51_P00'
 '@S9S_MB_2U_LIB.S9S_MB_2U(SCH_1):TP_PCA9555_U51_P00':
 C_SIGNAL='@s9s_mb_2u_lib.s9s_mb_2u(sch_1):tp_pca9555_u51_p00';
NODE_NAME     U51 4
 '@S9S_MB_2U_LIB.S9S_MB_2U(SCH_1):PAGE132_I66@PURE_QUANTA.PCA9555APW(CHIPS)':
 'P0_0': CDS_PINID='P0_0';
NET_NAME
'TP_PCA9555_U51_P01'
 '@S9S_MB_2U_LIB.S9S_MB_2U(SCH_1):TP_PCA9555_U51_P01':
 C_SIGNAL='@s9s_mb_2u_lib.s9s_mb_2u(sch_1):tp_pca9555_u51_p01';
NODE_NAME     U51 5
 '@S9S_MB_2U_LIB.S9S_MB_2U(SCH_1):PAGE132_I66@PURE_QUANTA.PCA9555APW(CHIPS)':
 'P0_1': CDS_PINID='P0_1';
NET_NAME
'TP_PCA9555_U51_P05'
 '@S9S_MB_2U_LIB.S9S_MB_2U(SCH_1):TP_PCA9555_U51_P05':
 C_SIGNAL='@s9s_mb_2u_lib.s9s_mb_2u(sch_1):tp_pca9555_u51_p05';
NODE_NAME     U51 9
 '@S9S_MB_2U_LIB.S9S_MB_2U(SCH_1):PAGE132_I66@PURE_QUANTA.PCA9555APW(CHIPS)':
 'P0_5': CDS_PINID='P0_5';
NET_NAME
'TP_PCA9555_U51_P06'
 '@S9S_MB_2U_LIB.S9S_MB_2U(SCH_1):TP_PCA9555_U51_P06':
 C_SIGNAL='@s9s_mb_2u_lib.s9s_mb_2u(sch_1):tp_pca9555_u51_p06';
NODE_NAME     U51 10
 '@S9S_MB_2U_LIB.S9S_MB_2U(SCH_1):PAGE132_I66@PURE_QUANTA.PCA9555APW(CHIPS)':
 'P0_6': CDS_PINID='P0_6';
NET_NAME
'TP_PCA9555_U51_P07'
 '@S9S_MB_2U_LIB.S9S_MB_2U(SCH_1):TP_PCA9555_U51_P07':
 C_SIGNAL='@s9s_mb_2u_lib.s9s_mb_2u(sch_1):tp_pca9555_u51_p07';
NODE_NAME     U51 11
 '@S9S_MB_2U_LIB.S9S_MB_2U(SCH_1):PAGE132_I66@PURE_QUANTA.PCA9555APW(CHIPS)':
 'P0_7': CDS_PINID='P0_7';
NET_NAME
'TP_PCA9555_U51_P10'
 '@S9S_MB_2U_LIB.S9S_MB_2U(SCH_1):TP_PCA9555_U51_P10':
 C_SIGNAL='@s9s_mb_2u_lib.s9s_mb_2u(sch_1):tp_pca9555_u51_p10';
NODE_NAME     U51 13
 '@S9S_MB_2U_LIB.S9S_MB_2U(SCH_1):PAGE132_I66@PURE_QUANTA.PCA9555APW(CHIPS)':
 'P1_0': CDS_PINID='P1_0';
NET_NAME
'TP_PCA9555_U51_P11'
 '@S9S_MB_2U_LIB.S9S_MB_2U(SCH_1):TP_PCA9555_U51_P11':
 C_SIGNAL='@s9s_mb_2u_lib.s9s_mb_2u(sch_1):tp_pca9555_u51_p11';
NODE_NAME     U51 14
 '@S9S_MB_2U_LIB.S9S_MB_2U(SCH_1):PAGE132_I66@PURE_QUANTA.PCA9555APW(CHIPS)':
 'P1_1': CDS_PINID='P1_1';
NET_NAME
'TP_PCA9555_U51_P12'
 '@S9S_MB_2U_LIB.S9S_MB_2U(SCH_1):TP_PCA9555_U51_P12':
 C_SIGNAL='@s9s_mb_2u_lib.s9s_mb_2u(sch_1):tp_pca9555_u51_p12';
NODE_NAME     U51 15
 '@S9S_MB_2U_LIB.S9S_MB_2U(SCH_1):PAGE132_I66@PURE_QUANTA.PCA9555APW(CHIPS)':
 'P1_2': CDS_PINID='P1_2';
NET_NAME
'TP_PCA9555_U51_P13'
 '@S9S_MB_2U_LIB.S9S_MB_2U(SCH_1):TP_PCA9555_U51_P13':
 C_SIGNAL='@s9s_mb_2u_lib.s9s_mb_2u(sch_1):tp_pca9555_u51_p13';
NODE_NAME     U51 16
 '@S9S_MB_2U_LIB.S9S_MB_2U(SCH_1):PAGE132_I66@PURE_QUANTA.PCA9555APW(CHIPS)':
 'P1_3': CDS_PINID='P1_3';
NET_NAME
'TP_PCA9555_U51_P14'
 '@S9S_MB_2U_LIB.S9S_MB_2U(SCH_1):TP_PCA9555_U51_P14':
 C_SIGNAL='@s9s_mb_2u_lib.s9s_mb_2u(sch_1):tp_pca9555_u51_p14';
NODE_NAME     U51 17
 '@S9S_MB_2U_LIB.S9S_MB_2U(SCH_1):PAGE132_I66@PURE_QUANTA.PCA9555APW(CHIPS)':
 'P1_4': CDS_PINID='P1_4';
NET_NAME
'TP_PCA9555_U51_P15'
 '@S9S_MB_2U_LIB.S9S_MB_2U(SCH_1):TP_PCA9555_U51_P15':
 C_SIGNAL='@s9s_mb_2u_lib.s9s_mb_2u(sch_1):tp_pca9555_u51_p15';
NODE_NAME     U51 18
 '@S9S_MB_2U_LIB.S9S_MB_2U(SCH_1):PAGE132_I66@PURE_QUANTA.PCA9555APW(CHIPS)':
 'P1_5': CDS_PINID='P1_5';
NET_NAME
'TP_PCA9555_U51_P16'
 '@S9S_MB_2U_LIB.S9S_MB_2U(SCH_1):TP_PCA9555_U51_P16':
 C_SIGNAL='@s9s_mb_2u_lib.s9s_mb_2u(sch_1):tp_pca9555_u51_p16';
NODE_NAME     U51 19
 '@S9S_MB_2U_LIB.S9S_MB_2U(SCH_1):PAGE132_I66@PURE_QUANTA.PCA9555APW(CHIPS)':
 'P1_6': CDS_PINID='P1_6';
NET_NAME
'TP_PCA9555_U51_P17'
 '@S9S_MB_2U_LIB.S9S_MB_2U(SCH_1):TP_PCA9555_U51_P17':
 C_SIGNAL='@s9s_mb_2u_lib.s9s_mb_2u(sch_1):tp_pca9555_u51_p17';
NODE_NAME     U51 20
 '@S9S_MB_2U_LIB.S9S_MB_2U(SCH_1):PAGE132_I66@PURE_QUANTA.PCA9555APW(CHIPS)':
 'P1_7': CDS_PINID='P1_7';
NET_NAME
'TP_PCH_CGC_DUT_DETECTED'
 '@S9S_MB_2U_LIB.S9S_MB_2U(SCH_1):TP_PCH_CGC_DUT_DETECTED':
 C_SIGNAL='@s9s_mb_2u_lib.s9s_mb_2u(sch_1):tp_pch_cgc_dut_detected';
NODE_NAME     U4 BG3
 '@S9S_MB_2U_LIB.S9S_MB_2U(SCH_1):PAGE177_I27@PURE_QUANTA.EMMITSBURG_REV0P9(CHIPS)':
 'NC_CGC_DUT_DETECT_N': CDS_PINID='NC_CGC_DUT_DETECT_N';
NET_NAME
'TP_PCH_CPU_MEMTRIP_N'
 '@S9S_MB_2U_LIB.S9S_MB_2U(SCH_1):TP_PCH_CPU_MEMTRIP_N':
 C_SIGNAL='@s9s_mb_2u_lib.s9s_mb_2u(sch_1):tp_pch_cpu_memtrip_n';
NODE_NAME     U4 E4
 '@S9S_MB_2U_LIB.S9S_MB_2U(SCH_1):PAGE174_I36@PURE_QUANTA.EMMITSBURG_REV0P9(CHIPS)':
 'CPU_MEMTRIP_N': CDS_PINID='CPU_MEMTRIP_N';
NET_NAME
'TP_PCH_CPU_MSMI_N'
 '@S9S_MB_2U_LIB.S9S_MB_2U(SCH_1):TP_PCH_CPU_MSMI_N':
 C_SIGNAL='@s9s_mb_2u_lib.s9s_mb_2u(sch_1):tp_pch_cpu_msmi_n';
NODE_NAME     U4 F11
 '@S9S_MB_2U_LIB.S9S_MB_2U(SCH_1):PAGE174_I36@PURE_QUANTA.EMMITSBURG_REV0P9(CHIPS)':
 'CPU_MSMI_N': CDS_PINID='CPU_MSMI_N';
NET_NAME
'TP_PCH_GPP_D_2'
 '@S9S_MB_2U_LIB.S9S_MB_2U(SCH_1):TP_PCH_GPP_D_2':
 C_SIGNAL='@s9s_mb_2u_lib.s9s_mb_2u(sch_1):tp_pch_gpp_d_2';
NODE_NAME     U4 AD2
 '@S9S_MB_2U_LIB.S9S_MB_2U(SCH_1):PAGE175_I93@PURE_QUANTA.EMMITSBURG_REV0P9(CHIPS)':
 'GPP_D_2_HS_SMBALERT_N_DMA_SMBALERT_N': CDS_PINID='GPP_D_2_HS_SMBALERT_N_DMA_SMBALERT_N';
NET_NAME
'TP_PCH_GPP_D_20'
 '@S9S_MB_2U_LIB.S9S_MB_2U(SCH_1):TP_PCH_GPP_D_20':
 C_SIGNAL='@s9s_mb_2u_lib.s9s_mb_2u(sch_1):tp_pch_gpp_d_20';
NODE_NAME     U4 AG3
 '@S9S_MB_2U_LIB.S9S_MB_2U(SCH_1):PAGE175_I93@PURE_QUANTA.EMMITSBURG_REV0P9(CHIPS)':
 'GPP_D_20_CATERR_N': CDS_PINID='GPP_D_20_CATERR_N';
NET_NAME
'TP_PCH_GPP_E_0'
 '@S9S_MB_2U_LIB.S9S_MB_2U(SCH_1):TP_PCH_GPP_E_0':
 C_SIGNAL='@s9s_mb_2u_lib.s9s_mb_2u(sch_1):tp_pch_gpp_e_0';
NODE_NAME     U4 BA26
 '@S9S_MB_2U_LIB.S9S_MB_2U(SCH_1):PAGE176_I22@PURE_QUANTA.EMMITSBURG_REV0P9(CHIPS)':
 'GPP_E_0_SATA1_XPCIE_0': CDS_PINID='GPP_E_0_SATA1_XPCIE_0';
NET_NAME
'TP_PCH_GPP_E_1'
 '@S9S_MB_2U_LIB.S9S_MB_2U(SCH_1):TP_PCH_GPP_E_1':
 C_SIGNAL='@s9s_mb_2u_lib.s9s_mb_2u(sch_1):tp_pch_gpp_e_1';
NODE_NAME     U4 BA23
 '@S9S_MB_2U_LIB.S9S_MB_2U(SCH_1):PAGE176_I22@PURE_QUANTA.EMMITSBURG_REV0P9(CHIPS)':
 'GPP_E_1_SATA1_XPCIE_1': CDS_PINID='GPP_E_1_SATA1_XPCIE_1';
NET_NAME
'TP_PCH_GPP_E_2'
 '@S9S_MB_2U_LIB.S9S_MB_2U(SCH_1):TP_PCH_GPP_E_2':
 C_SIGNAL='@s9s_mb_2u_lib.s9s_mb_2u(sch_1):tp_pch_gpp_e_2';
NODE_NAME     U4 AW23
 '@S9S_MB_2U_LIB.S9S_MB_2U(SCH_1):PAGE176_I22@PURE_QUANTA.EMMITSBURG_REV0P9(CHIPS)':
 'GPP_E_2_SATA1_XPCIE_2': CDS_PINID='GPP_E_2_SATA1_XPCIE_2';
NET_NAME
'TP_PCH_GPP_N_1'
 '@S9S_MB_2U_LIB.S9S_MB_2U(SCH_1):TP_PCH_GPP_N_1':
 C_SIGNAL='@s9s_mb_2u_lib.s9s_mb_2u(sch_1):tp_pch_gpp_n_1';
NODE_NAME     U4 T11
 '@S9S_MB_2U_LIB.S9S_MB_2U(SCH_1):PAGE177_I27@PURE_QUANTA.EMMITSBURG_REV0P9(CHIPS)':
 'GPP_N_1': CDS_PINID='GPP_N_1';
NET_NAME
'TP_PCH_GPP_N_4'
 '@S9S_MB_2U_LIB.S9S_MB_2U(SCH_1):TP_PCH_GPP_N_4':
 C_SIGNAL='@s9s_mb_2u_lib.s9s_mb_2u(sch_1):tp_pch_gpp_n_4';
NODE_NAME     U4 V11
 '@S9S_MB_2U_LIB.S9S_MB_2U(SCH_1):PAGE177_I27@PURE_QUANTA.EMMITSBURG_REV0P9(CHIPS)':
 'GPP_N_4': CDS_PINID='GPP_N_4';
NET_NAME
'TP_PCH_GPP_O_11'
 '@S9S_MB_2U_LIB.S9S_MB_2U(SCH_1):TP_PCH_GPP_O_11':
 C_SIGNAL='@s9s_mb_2u_lib.s9s_mb_2u(sch_1):tp_pch_gpp_o_11';
NODE_NAME     U4 AJ7
 '@S9S_MB_2U_LIB.S9S_MB_2U(SCH_1):PAGE174_I36@PURE_QUANTA.EMMITSBURG_REV0P9(CHIPS)':
 'LANPHYPC': CDS_PINID='LANPHYPC';
NET_NAME
'TP_PCH_MGPIO_TEST1'
 '@S9S_MB_2U_LIB.S9S_MB_2U(SCH_1):TP_PCH_MGPIO_TEST1':
 C_SIGNAL='@s9s_mb_2u_lib.s9s_mb_2u(sch_1):tp_pch_mgpio_test1';
NODE_NAME     U4 J2
 '@S9S_MB_2U_LIB.S9S_MB_2U(SCH_1):PAGE176_I22@PURE_QUANTA.EMMITSBURG_REV0P9(CHIPS)':
 'GPPC_H_15_FLEX_CLK_OUT_0': CDS_PINID='GPPC_H_15_FLEX_CLK_OUT_0';
NET_NAME
'TP_PCH_RSVD<0>'
 '@S9S_MB_2U_LIB.S9S_MB_2U(SCH_1):TP_PCH_RSVD'<0>:
 C_SIGNAL='@s9s_mb_2u_lib.s9s_mb_2u(sch_1):tp_pch_rsvd(0)';
NODE_NAME     U4 H1
 '@S9S_MB_2U_LIB.S9S_MB_2U(SCH_1):PAGE179_I4@PURE_QUANTA.EMMITSBURG_REV0P9(CHIPS)':
 'RSVD_H1': CDS_PINID='RSVD_H1';
NET_NAME
'TP_PCH_RSVD<12>'
 '@S9S_MB_2U_LIB.S9S_MB_2U(SCH_1):TP_PCH_RSVD'<12>:
 C_SIGNAL='@s9s_mb_2u_lib.s9s_mb_2u(sch_1):tp_pch_rsvd(12)';
NODE_NAME     U4 N13
 '@S9S_MB_2U_LIB.S9S_MB_2U(SCH_1):PAGE179_I4@PURE_QUANTA.EMMITSBURG_REV0P9(CHIPS)':
 'RSVD_N13': CDS_PINID='RSVD_N13';
NET_NAME
'TP_PCH_RSVD<13>'
 '@S9S_MB_2U_LIB.S9S_MB_2U(SCH_1):TP_PCH_RSVD'<13>:
 C_SIGNAL='@s9s_mb_2u_lib.s9s_mb_2u(sch_1):tp_pch_rsvd(13)';
NODE_NAME     U4 L13
 '@S9S_MB_2U_LIB.S9S_MB_2U(SCH_1):PAGE179_I4@PURE_QUANTA.EMMITSBURG_REV0P9(CHIPS)':
 'RSVD_L13': CDS_PINID='RSVD_L13';
NET_NAME
'TP_PCH_RSVD<15>'
 '@S9S_MB_2U_LIB.S9S_MB_2U(SCH_1):TP_PCH_RSVD'<15>:
 C_SIGNAL='@s9s_mb_2u_lib.s9s_mb_2u(sch_1):tp_pch_rsvd(15)';
NODE_NAME     U4 AN26
 '@S9S_MB_2U_LIB.S9S_MB_2U(SCH_1):PAGE178_I11@PURE_QUANTA.EMMITSBURG_REV0P9(CHIPS)':
 'RSVD_AN26': CDS_PINID='RSVD_AN26';
NET_NAME
'TP_PCH_RSVD<16>'
 '@S9S_MB_2U_LIB.S9S_MB_2U(SCH_1):TP_PCH_RSVD'<16>:
 C_SIGNAL='@s9s_mb_2u_lib.s9s_mb_2u(sch_1):tp_pch_rsvd(16)';
NODE_NAME     U4 AF15
 '@S9S_MB_2U_LIB.S9S_MB_2U(SCH_1):PAGE178_I11@PURE_QUANTA.EMMITSBURG_REV0P9(CHIPS)':
 'RSVD_AF15': CDS_PINID='RSVD_AF15';
NET_NAME
'TP_PCH_RSVD<18>'
 '@S9S_MB_2U_LIB.S9S_MB_2U(SCH_1):TP_PCH_RSVD'<18>:
 C_SIGNAL='@s9s_mb_2u_lib.s9s_mb_2u(sch_1):tp_pch_rsvd(18)';
NODE_NAME     U4 H24
 '@S9S_MB_2U_LIB.S9S_MB_2U(SCH_1):PAGE171_I78@PURE_QUANTA.EMMITSBURG_REV0P9(CHIPS)':
 'RSVD_H24': CDS_PINID='RSVD_H24';
NET_NAME
'TP_PCH_RSVD<19>'
 '@S9S_MB_2U_LIB.S9S_MB_2U(SCH_1):TP_PCH_RSVD'<19>:
 C_SIGNAL='@s9s_mb_2u_lib.s9s_mb_2u(sch_1):tp_pch_rsvd(19)';
NODE_NAME     U4 J23
 '@S9S_MB_2U_LIB.S9S_MB_2U(SCH_1):PAGE171_I78@PURE_QUANTA.EMMITSBURG_REV0P9(CHIPS)':
 'RSVD_J23': CDS_PINID='RSVD_J23';
NET_NAME
'TP_PCH_RSVD<1>'
 '@S9S_MB_2U_LIB.S9S_MB_2U(SCH_1):TP_PCH_RSVD'<1>:
 C_SIGNAL='@s9s_mb_2u_lib.s9s_mb_2u(sch_1):tp_pch_rsvd(1)';
NODE_NAME     U4 F1
 '@S9S_MB_2U_LIB.S9S_MB_2U(SCH_1):PAGE179_I4@PURE_QUANTA.EMMITSBURG_REV0P9(CHIPS)':
 'RSVD_F1': CDS_PINID='RSVD_F1';
NET_NAME
'TP_PCH_RSVD<2>'
 '@S9S_MB_2U_LIB.S9S_MB_2U(SCH_1):TP_PCH_RSVD'<2>:
 C_SIGNAL='@s9s_mb_2u_lib.s9s_mb_2u(sch_1):tp_pch_rsvd(2)';
NODE_NAME     U4 A4
 '@S9S_MB_2U_LIB.S9S_MB_2U(SCH_1):PAGE179_I4@PURE_QUANTA.EMMITSBURG_REV0P9(CHIPS)':
 'RSVD_A4': CDS_PINID='RSVD_A4';
NET_NAME
'TP_PCH_RSVD<6>'
 '@S9S_MB_2U_LIB.S9S_MB_2U(SCH_1):TP_PCH_RSVD'<6>:
 C_SIGNAL='@s9s_mb_2u_lib.s9s_mb_2u(sch_1):tp_pch_rsvd(6)';
NODE_NAME     U4 P18
 '@S9S_MB_2U_LIB.S9S_MB_2U(SCH_1):PAGE179_I4@PURE_QUANTA.EMMITSBURG_REV0P9(CHIPS)':
 'RSVD_P18': CDS_PINID='RSVD_P18';
NET_NAME
'TP_PCH_RSVD<7>'
 '@S9S_MB_2U_LIB.S9S_MB_2U(SCH_1):TP_PCH_RSVD'<7>:
 C_SIGNAL='@s9s_mb_2u_lib.s9s_mb_2u(sch_1):tp_pch_rsvd(7)';
NODE_NAME     U4 BB43
 '@S9S_MB_2U_LIB.S9S_MB_2U(SCH_1):PAGE179_I4@PURE_QUANTA.EMMITSBURG_REV0P9(CHIPS)':
 'RSVD_BB43': CDS_PINID='RSVD_BB43';
NET_NAME
'TP_PCH_SLP_A_N'
 '@S9S_MB_2U_LIB.S9S_MB_2U(SCH_1):TP_PCH_SLP_A_N':
 C_SIGNAL='@s9s_mb_2u_lib.s9s_mb_2u(sch_1):tp_pch_slp_a_n';
NODE_NAME     U4 AM11
 '@S9S_MB_2U_LIB.S9S_MB_2U(SCH_1):PAGE174_I36@PURE_QUANTA.EMMITSBURG_REV0P9(CHIPS)':
 'SLP_A_N': CDS_PINID='SLP_A_N';
NET_NAME
'TP_PCH_SLP_S5_N'
 '@S9S_MB_2U_LIB.S9S_MB_2U(SCH_1):TP_PCH_SLP_S5_N':
 C_SIGNAL='@s9s_mb_2u_lib.s9s_mb_2u(sch_1):tp_pch_slp_s5_n';
NODE_NAME     U4 AJ13
 '@S9S_MB_2U_LIB.S9S_MB_2U(SCH_1):PAGE174_I36@PURE_QUANTA.EMMITSBURG_REV0P9(CHIPS)':
 'SLP_S5_N': CDS_PINID='SLP_S5_N';
NET_NAME
'TP_PCIE_HPM_RXN<1>'
 '@S9S_MB_2U_LIB.S9S_MB_2U(SCH_1):TP_PCIE_HPM_RXN'<1>:
 C_SIGNAL='@s9s_mb_2u_lib.s9s_mb_2u(sch_1):tp_pcie_hpm_rxn(1)';
NODE_NAME     J41 A63
 '@S9S_MB_2U_LIB.S9S_MB_2U(SCH_1):PAGE227_I173@PURE_QUANTA.SCONN168_ME1016810202011(CHIPS)':
 'PERP14': CDS_PINID='PERP14';
NET_NAME
'TP_PCIE_HPM_RXP<1>'
 '@S9S_MB_2U_LIB.S9S_MB_2U(SCH_1):TP_PCIE_HPM_RXP'<1>:
 C_SIGNAL='@s9s_mb_2u_lib.s9s_mb_2u(sch_1):tp_pcie_hpm_rxp(1)';
NODE_NAME     J41 A62
 '@S9S_MB_2U_LIB.S9S_MB_2U(SCH_1):PAGE227_I173@PURE_QUANTA.SCONN168_ME1016810202011(CHIPS)':
 'PERN14': CDS_PINID='PERN14';
NET_NAME
'TP_PCIE_HPM_TXN<1>'
 '@S9S_MB_2U_LIB.S9S_MB_2U(SCH_1):TP_PCIE_HPM_TXN'<1>:
 C_SIGNAL='@s9s_mb_2u_lib.s9s_mb_2u(sch_1):tp_pcie_hpm_txn(1)';
NODE_NAME     J41 B63
 '@S9S_MB_2U_LIB.S9S_MB_2U(SCH_1):PAGE227_I173@PURE_QUANTA.SCONN168_ME1016810202011(CHIPS)':
 'PETP14': CDS_PINID='PETP14';
NET_NAME
'TP_PCIE_HPM_TXN<3>'
 '@S9S_MB_2U_LIB.S9S_MB_2U(SCH_1):TP_PCIE_HPM_TXN'<3>:
 C_SIGNAL='@s9s_mb_2u_lib.s9s_mb_2u(sch_1):tp_pcie_hpm_txn(3)';
NODE_NAME     R3302 1
 '@S9S_MB_2U_LIB.S9S_MB_2U(SCH_1):PAGE227_I48@PURE_QUANTA.Q_RES(CHIPS)':
 'A': CDS_PINID='A';
NODE_NAME     J41 B69
 '@S9S_MB_2U_LIB.S9S_MB_2U(SCH_1):PAGE227_I173@PURE_QUANTA.SCONN168_ME1016810202011(CHIPS)':
 'RFU1_NC_B69': CDS_PINID='RFU1_NC_B69';
NET_NAME
'TP_PCIE_HPM_TXP<1>'
 '@S9S_MB_2U_LIB.S9S_MB_2U(SCH_1):TP_PCIE_HPM_TXP'<1>:
 C_SIGNAL='@s9s_mb_2u_lib.s9s_mb_2u(sch_1):tp_pcie_hpm_txp(1)';
NODE_NAME     J41 B62
 '@S9S_MB_2U_LIB.S9S_MB_2U(SCH_1):PAGE227_I173@PURE_QUANTA.SCONN168_ME1016810202011(CHIPS)':
 'PETN14': CDS_PINID='PETN14';
NET_NAME
'TP_PCIE_HPM_TXP<3>'
 '@S9S_MB_2U_LIB.S9S_MB_2U(SCH_1):TP_PCIE_HPM_TXP'<3>:
 C_SIGNAL='@s9s_mb_2u_lib.s9s_mb_2u(sch_1):tp_pcie_hpm_txp(3)';
NODE_NAME     R3254 1
 '@S9S_MB_2U_LIB.S9S_MB_2U(SCH_1):PAGE227_I49@PURE_QUANTA.Q_RES(CHIPS)':
 'A': CDS_PINID='A';
NODE_NAME     J41 B68
 '@S9S_MB_2U_LIB.S9S_MB_2U(SCH_1):PAGE227_I173@PURE_QUANTA.SCONN168_ME1016810202011(CHIPS)':
 'RFU1_NC_B68': CDS_PINID='RFU1_NC_B68';
NET_NAME
'TP_PLD_CONN_P4'
 '@S9S_MB_2U_LIB.S9S_MB_2U(SCH_1):TP_PLD_CONN_P4':
 C_SIGNAL='@s9s_mb_2u_lib.s9s_mb_2u(sch_1):tp_pld_conn_p4';
NODE_NAME     J43 4
 '@S9S_MB_2U_LIB.S9S_MB_2U(SCH_1):PAGE210_I79@PURE_QUANTA.CONN8_210HP1080BR1(CHIPS)':
 '4': CDS_PINID='\4\';
NET_NAME
'TP_PLD_CONN_P5'
 '@S9S_MB_2U_LIB.S9S_MB_2U(SCH_1):TP_PLD_CONN_P5':
 C_SIGNAL='@s9s_mb_2u_lib.s9s_mb_2u(sch_1):tp_pld_conn_p5';
NODE_NAME     J43 5
 '@S9S_MB_2U_LIB.S9S_MB_2U(SCH_1):PAGE210_I79@PURE_QUANTA.CONN8_210HP1080BR1(CHIPS)':
 '5': CDS_PINID='\5\';
NET_NAME
'TP_PLTRST_N'
 '@S9S_MB_2U_LIB.S9S_MB_2U(SCH_1):TP_PLTRST_N':
 C_SIGNAL='@s9s_mb_2u_lib.s9s_mb_2u(sch_1):tp_pltrst_n';
NODE_NAME     U4 M8
 '@S9S_MB_2U_LIB.S9S_MB_2U(SCH_1):PAGE174_I36@PURE_QUANTA.EMMITSBURG_REV0P9(CHIPS)':
 'PLTRST_CPU_N': CDS_PINID='PLTRST_CPU_N';
NET_NAME
'TP_PWRGD_S0_PWROK_CPU0_LVC1'
 '@S9S_MB_2U_LIB.S9S_MB_2U(SCH_1):TP_PWRGD_S0_PWROK_CPU0_LVC1':
 C_SIGNAL='@s9s_mb_2u_lib.s9s_mb_2u(sch_1):tp_pwrgd_s0_pwrok_cpu0_lvc1';
NODE_NAME     U2 CH71
 '@S9S_MB_2U_LIB.S9S_MB_2U(SCH_1):PAGE15_I1@PURE_QUANTA.SOCKET4677_AZIF0045P001C01CS(CHIPS)':
 'RSVD100': CDS_PINID='RSVD100';
NET_NAME
'TP_PWRGD_S0_PWROK_CPU1_LVC1'
 '@S9S_MB_2U_LIB.S9S_MB_2U(SCH_1):TP_PWRGD_S0_PWROK_CPU1_LVC1':
 C_SIGNAL='@s9s_mb_2u_lib.s9s_mb_2u(sch_1):tp_pwrgd_s0_pwrok_cpu1_lvc1';
NODE_NAME     U1 CH71
 '@S9S_MB_2U_LIB.S9S_MB_2U(SCH_1):PAGE46_I5@PURE_QUANTA.SOCKET4677_AZIF0045P001C01CS(CHIPS)':
 'RSVD100': CDS_PINID='RSVD100';
NET_NAME
'TP_RST_ESPI_IBL_CPU0_LVC1_N'
 '@S9S_MB_2U_LIB.S9S_MB_2U(SCH_1):TP_RST_ESPI_IBL_CPU0_LVC1_N':
 C_SIGNAL='@s9s_mb_2u_lib.s9s_mb_2u(sch_1):tp_rst_espi_ibl_cpu0_lvc1_n';
NODE_NAME     U2 BG64
 '@S9S_MB_2U_LIB.S9S_MB_2U(SCH_1):PAGE15_I1@PURE_QUANTA.SOCKET4677_AZIF0045P001C01CS(CHIPS)':
 'RSVD53': CDS_PINID='RSVD53';
NET_NAME
'TP_SGPIO_S3M_CPU0_GSXCLK_R'
 '@S9S_MB_2U_LIB.S9S_MB_2U(SCH_1):TP_SGPIO_S3M_CPU0_GSXCLK_R':
 C_SIGNAL='@s9s_mb_2u_lib.s9s_mb_2u(sch_1):tp_sgpio_s3m_cpu0_gsxclk_r';
NODE_NAME     U2 CF63
 '@S9S_MB_2U_LIB.S9S_MB_2U(SCH_1):PAGE15_I1@PURE_QUANTA.SOCKET4677_AZIF0045P001C01CS(CHIPS)':
 'RSVD93': CDS_PINID='RSVD93';
NET_NAME
'TP_SGPIO_S3M_CPU0_GSXDIN'
 '@S9S_MB_2U_LIB.S9S_MB_2U(SCH_1):TP_SGPIO_S3M_CPU0_GSXDIN':
 C_SIGNAL='@s9s_mb_2u_lib.s9s_mb_2u(sch_1):tp_sgpio_s3m_cpu0_gsxdin';
NODE_NAME     U2 CH63
 '@S9S_MB_2U_LIB.S9S_MB_2U(SCH_1):PAGE15_I1@PURE_QUANTA.SOCKET4677_AZIF0045P001C01CS(CHIPS)':
 'RSVD98': CDS_PINID='RSVD98';
NET_NAME
'TP_SGPIO_S3M_CPU0_GSXDLOAD_R'
 '@S9S_MB_2U_LIB.S9S_MB_2U(SCH_1):TP_SGPIO_S3M_CPU0_GSXDLOAD_R':
 C_SIGNAL='@s9s_mb_2u_lib.s9s_mb_2u(sch_1):tp_sgpio_s3m_cpu0_gsxdload_r';
NODE_NAME     U2 CJ66
 '@S9S_MB_2U_LIB.S9S_MB_2U(SCH_1):PAGE15_I1@PURE_QUANTA.SOCKET4677_AZIF0045P001C01CS(CHIPS)':
 'RSVD105': CDS_PINID='RSVD105';
NET_NAME
'TP_SGPIO_S3M_CPU0_GSXDOUT_R'
 '@S9S_MB_2U_LIB.S9S_MB_2U(SCH_1):TP_SGPIO_S3M_CPU0_GSXDOUT_R':
 C_SIGNAL='@s9s_mb_2u_lib.s9s_mb_2u(sch_1):tp_sgpio_s3m_cpu0_gsxdout_r';
NODE_NAME     U2 CF65
 '@S9S_MB_2U_LIB.S9S_MB_2U(SCH_1):PAGE15_I1@PURE_QUANTA.SOCKET4677_AZIF0045P001C01CS(CHIPS)':
 'RSVD94': CDS_PINID='RSVD94';
NET_NAME
'TP_SGPIO_S3M_CPU0_RST_R_N'
 '@S9S_MB_2U_LIB.S9S_MB_2U(SCH_1):TP_SGPIO_S3M_CPU0_RST_R_N':
 C_SIGNAL='@s9s_mb_2u_lib.s9s_mb_2u(sch_1):tp_sgpio_s3m_cpu0_rst_r_n';
NODE_NAME     U2 CD65
 '@S9S_MB_2U_LIB.S9S_MB_2U(SCH_1):PAGE15_I1@PURE_QUANTA.SOCKET4677_AZIF0045P001C01CS(CHIPS)':
 'RSVD86': CDS_PINID='RSVD86';
NET_NAME
'TP_SGPIO_S3M_CPU1_GSXCLK'
 '@S9S_MB_2U_LIB.S9S_MB_2U(SCH_1):TP_SGPIO_S3M_CPU1_GSXCLK':
 C_SIGNAL='@s9s_mb_2u_lib.s9s_mb_2u(sch_1):tp_sgpio_s3m_cpu1_gsxclk';
NODE_NAME     U1 CF63
 '@S9S_MB_2U_LIB.S9S_MB_2U(SCH_1):PAGE46_I5@PURE_QUANTA.SOCKET4677_AZIF0045P001C01CS(CHIPS)':
 'RSVD93': CDS_PINID='RSVD93';
NET_NAME
'TP_SGPIO_S3M_CPU1_GSXDIN'
 '@S9S_MB_2U_LIB.S9S_MB_2U(SCH_1):TP_SGPIO_S3M_CPU1_GSXDIN':
 C_SIGNAL='@s9s_mb_2u_lib.s9s_mb_2u(sch_1):tp_sgpio_s3m_cpu1_gsxdin';
NODE_NAME     U1 CH63
 '@S9S_MB_2U_LIB.S9S_MB_2U(SCH_1):PAGE46_I5@PURE_QUANTA.SOCKET4677_AZIF0045P001C01CS(CHIPS)':
 'RSVD98': CDS_PINID='RSVD98';
NET_NAME
'TP_SGPIO_S3M_CPU1_GSXDLOAD'
 '@S9S_MB_2U_LIB.S9S_MB_2U(SCH_1):TP_SGPIO_S3M_CPU1_GSXDLOAD':
 C_SIGNAL='@s9s_mb_2u_lib.s9s_mb_2u(sch_1):tp_sgpio_s3m_cpu1_gsxdload';
NODE_NAME     U1 CJ66
 '@S9S_MB_2U_LIB.S9S_MB_2U(SCH_1):PAGE46_I5@PURE_QUANTA.SOCKET4677_AZIF0045P001C01CS(CHIPS)':
 'RSVD105': CDS_PINID='RSVD105';
NET_NAME
'TP_SGPIO_S3M_CPU1_GSXDOUT'
 '@S9S_MB_2U_LIB.S9S_MB_2U(SCH_1):TP_SGPIO_S3M_CPU1_GSXDOUT':
 C_SIGNAL='@s9s_mb_2u_lib.s9s_mb_2u(sch_1):tp_sgpio_s3m_cpu1_gsxdout';
NODE_NAME     U1 CF65
 '@S9S_MB_2U_LIB.S9S_MB_2U(SCH_1):PAGE46_I5@PURE_QUANTA.SOCKET4677_AZIF0045P001C01CS(CHIPS)':
 'RSVD94': CDS_PINID='RSVD94';
NET_NAME
'TP_SGPIO_S3M_CPU1_GSXRST_N'
 '@S9S_MB_2U_LIB.S9S_MB_2U(SCH_1):TP_SGPIO_S3M_CPU1_GSXRST_N':
 C_SIGNAL='@s9s_mb_2u_lib.s9s_mb_2u(sch_1):tp_sgpio_s3m_cpu1_gsxrst_n';
NODE_NAME     U1 CD65
 '@S9S_MB_2U_LIB.S9S_MB_2U(SCH_1):PAGE46_I5@PURE_QUANTA.SOCKET4677_AZIF0045P001C01CS(CHIPS)':
 'RSVD86': CDS_PINID='RSVD86';
NET_NAME
'TP_SLP_LAN_N'
 '@S9S_MB_2U_LIB.S9S_MB_2U(SCH_1):TP_SLP_LAN_N':
 C_SIGNAL='@s9s_mb_2u_lib.s9s_mb_2u(sch_1):tp_slp_lan_n';
NODE_NAME     U4 AK8
 '@S9S_MB_2U_LIB.S9S_MB_2U(SCH_1):PAGE174_I36@PURE_QUANTA.EMMITSBURG_REV0P9(CHIPS)':
 'SLP_LAN_N': CDS_PINID='SLP_LAN_N';
NET_NAME
'TP_SMB_PEHPCPU0_EN'
 '@S9S_MB_2U_LIB.S9S_MB_2U(SCH_1):TP_SMB_PEHPCPU0_EN':
 C_SIGNAL='@s9s_mb_2u_lib.s9s_mb_2u(sch_1):tp_smb_pehpcpu0_en';
NODE_NAME     U28 5
 '@S9S_MB_2U_LIB.S9S_MB_2U(SCH_1):PAGE223_I39@PURE_QUANTA.PCA9617ADP(CHIPS)':
 'EN': CDS_PINID='EN';
NET_NAME
'TP_SMB_PEHPCPU1_EN'
 '@S9S_MB_2U_LIB.S9S_MB_2U(SCH_1):TP_SMB_PEHPCPU1_EN':
 C_SIGNAL='@s9s_mb_2u_lib.s9s_mb_2u(sch_1):tp_smb_pehpcpu1_en';
NODE_NAME     U29 5
 '@S9S_MB_2U_LIB.S9S_MB_2U(SCH_1):PAGE223_I43@PURE_QUANTA.PCA9617ADP(CHIPS)':
 'EN': CDS_PINID='EN';
NET_NAME
'TP_SMB_S3M_CPU0_EN'
 '@S9S_MB_2U_LIB.S9S_MB_2U(SCH_1):TP_SMB_S3M_CPU0_EN':
 C_SIGNAL='@s9s_mb_2u_lib.s9s_mb_2u(sch_1):tp_smb_s3m_cpu0_en';
NODE_NAME     U30 5
 '@S9S_MB_2U_LIB.S9S_MB_2U(SCH_1):PAGE224_I28@PURE_QUANTA.PCA9517AD(CHIPS)':
 'ENABLE': CDS_PINID='ENABLE';
NET_NAME
'TP_SMB_S3M_CPU1_EN'
 '@S9S_MB_2U_LIB.S9S_MB_2U(SCH_1):TP_SMB_S3M_CPU1_EN':
 C_SIGNAL='@s9s_mb_2u_lib.s9s_mb_2u(sch_1):tp_smb_s3m_cpu1_en';
NODE_NAME     U31 5
 '@S9S_MB_2U_LIB.S9S_MB_2U(SCH_1):PAGE224_I37@PURE_QUANTA.PCA9517AD(CHIPS)':
 'ENABLE': CDS_PINID='ENABLE';
NET_NAME
'TP_SPI_2_PLD_CLK'
 '@S9S_MB_2U_LIB.S9S_MB_2U(SCH_1):TP_SPI_2_PLD_CLK':
 C_SIGNAL='@s9s_mb_2u_lib.s9s_mb_2u(sch_1):tp_spi_2_pld_clk';
NODE_NAME     J41 B43
 '@S9S_MB_2U_LIB.S9S_MB_2U(SCH_1):PAGE227_I173@PURE_QUANTA.SCONN168_ME1016810202011(CHIPS)':
 'GND_B43': CDS_PINID='GND_B43';
NET_NAME
'TP_SPI_2_PLD_CS_N'
 '@S9S_MB_2U_LIB.S9S_MB_2U(SCH_1):TP_SPI_2_PLD_CS_N':
 C_SIGNAL='@s9s_mb_2u_lib.s9s_mb_2u(sch_1):tp_spi_2_pld_cs_n';
NODE_NAME     J41 B44
 '@S9S_MB_2U_LIB.S9S_MB_2U(SCH_1):PAGE227_I173@PURE_QUANTA.SCONN168_ME1016810202011(CHIPS)':
 'PETN8': CDS_PINID='PETN8';
NET_NAME
'TP_SPI_2_PLD_IO0'
 '@S9S_MB_2U_LIB.S9S_MB_2U(SCH_1):TP_SPI_2_PLD_IO0':
 C_SIGNAL='@s9s_mb_2u_lib.s9s_mb_2u(sch_1):tp_spi_2_pld_io0';
NODE_NAME     J41 B45
 '@S9S_MB_2U_LIB.S9S_MB_2U(SCH_1):PAGE227_I173@PURE_QUANTA.SCONN168_ME1016810202011(CHIPS)':
 'PETP8': CDS_PINID='PETP8';
NET_NAME
'TP_SPI_2_PLD_IO1'
 '@S9S_MB_2U_LIB.S9S_MB_2U(SCH_1):TP_SPI_2_PLD_IO1':
 C_SIGNAL='@s9s_mb_2u_lib.s9s_mb_2u(sch_1):tp_spi_2_pld_io1';
NODE_NAME     J41 B46
 '@S9S_MB_2U_LIB.S9S_MB_2U(SCH_1):PAGE227_I173@PURE_QUANTA.SCONN168_ME1016810202011(CHIPS)':
 'GND_B46': CDS_PINID='GND_B46';
NET_NAME
'TP_SPI_2_PLD_IO2'
 '@S9S_MB_2U_LIB.S9S_MB_2U(SCH_1):TP_SPI_2_PLD_IO2':
 C_SIGNAL='@s9s_mb_2u_lib.s9s_mb_2u(sch_1):tp_spi_2_pld_io2';
NODE_NAME     J41 B47
 '@S9S_MB_2U_LIB.S9S_MB_2U(SCH_1):PAGE227_I173@PURE_QUANTA.SCONN168_ME1016810202011(CHIPS)':
 'PETN9': CDS_PINID='PETN9';
NET_NAME
'TP_SPI_2_PLD_IO3'
 '@S9S_MB_2U_LIB.S9S_MB_2U(SCH_1):TP_SPI_2_PLD_IO3':
 C_SIGNAL='@s9s_mb_2u_lib.s9s_mb_2u(sch_1):tp_spi_2_pld_io3';
NODE_NAME     J41 B48
 '@S9S_MB_2U_LIB.S9S_MB_2U(SCH_1):PAGE227_I173@PURE_QUANTA.SCONN168_ME1016810202011(CHIPS)':
 'PETP9': CDS_PINID='PETP9';
NET_NAME
'TP_SPI_IBL_CPU0_TPM_CLK'
 '@S9S_MB_2U_LIB.S9S_MB_2U(SCH_1):TP_SPI_IBL_CPU0_TPM_CLK':
 C_SIGNAL='@s9s_mb_2u_lib.s9s_mb_2u(sch_1):tp_spi_ibl_cpu0_tpm_clk';
NODE_NAME     U2 AU62
 '@S9S_MB_2U_LIB.S9S_MB_2U(SCH_1):PAGE15_I1@PURE_QUANTA.SOCKET4677_AZIF0045P001C01CS(CHIPS)':
 'RSVD11': CDS_PINID='RSVD11';
NET_NAME
'TP_SPI_IBL_CPU0_TPM_CS0_N'
 '@S9S_MB_2U_LIB.S9S_MB_2U(SCH_1):TP_SPI_IBL_CPU0_TPM_CS0_N':
 C_SIGNAL='@s9s_mb_2u_lib.s9s_mb_2u(sch_1):tp_spi_ibl_cpu0_tpm_cs0_n';
NODE_NAME     U2 AY67
 '@S9S_MB_2U_LIB.S9S_MB_2U(SCH_1):PAGE15_I1@PURE_QUANTA.SOCKET4677_AZIF0045P001C01CS(CHIPS)':
 'RSVD30': CDS_PINID='RSVD30';
NET_NAME
'TP_SPI_IBL_CPU0_TPM_IO0'
 '@S9S_MB_2U_LIB.S9S_MB_2U(SCH_1):TP_SPI_IBL_CPU0_TPM_IO0':
 C_SIGNAL='@s9s_mb_2u_lib.s9s_mb_2u(sch_1):tp_spi_ibl_cpu0_tpm_io0';
NODE_NAME     U2 BA66
 '@S9S_MB_2U_LIB.S9S_MB_2U(SCH_1):PAGE15_I1@PURE_QUANTA.SOCKET4677_AZIF0045P001C01CS(CHIPS)':
 'RSVD33': CDS_PINID='RSVD33';
NET_NAME
'TP_SPI_IBL_CPU0_TPM_IO1'
 '@S9S_MB_2U_LIB.S9S_MB_2U(SCH_1):TP_SPI_IBL_CPU0_TPM_IO1':
 C_SIGNAL='@s9s_mb_2u_lib.s9s_mb_2u(sch_1):tp_spi_ibl_cpu0_tpm_io1';
NODE_NAME     U2 AY61
 '@S9S_MB_2U_LIB.S9S_MB_2U(SCH_1):PAGE15_I1@PURE_QUANTA.SOCKET4677_AZIF0045P001C01CS(CHIPS)':
 'RSVD28': CDS_PINID='RSVD28';
NET_NAME
'TP_SPI_IBL_CPU0_TPM_OE_N'
 '@S9S_MB_2U_LIB.S9S_MB_2U(SCH_1):TP_SPI_IBL_CPU0_TPM_OE_N':
 C_SIGNAL='@s9s_mb_2u_lib.s9s_mb_2u(sch_1):tp_spi_ibl_cpu0_tpm_oe_n';
NODE_NAME     U2 BB67
 '@S9S_MB_2U_LIB.S9S_MB_2U(SCH_1):PAGE15_I1@PURE_QUANTA.SOCKET4677_AZIF0045P001C01CS(CHIPS)':
 'RSVD36': CDS_PINID='RSVD36';
NET_NAME
'TP_SPI_PCH_CS1_R_N'
 '@S9S_MB_2U_LIB.S9S_MB_2U(SCH_1):TP_SPI_PCH_CS1_R_N':
 C_SIGNAL='@s9s_mb_2u_lib.s9s_mb_2u(sch_1):tp_spi_pch_cs1_r_n';
NODE_NAME     U4 BA10
 '@S9S_MB_2U_LIB.S9S_MB_2U(SCH_1):PAGE177_I27@PURE_QUANTA.EMMITSBURG_REV0P9(CHIPS)':
 'SPI0_FLASH_1_CS_N': CDS_PINID='SPI0_FLASH_1_CS_N';
NET_NAME
'TP_SPI_S3M_CPU0_CLK_LVC1_R'
 '@S9S_MB_2U_LIB.S9S_MB_2U(SCH_1):TP_SPI_S3M_CPU0_CLK_LVC1_R':
 C_SIGNAL='@s9s_mb_2u_lib.s9s_mb_2u(sch_1):tp_spi_s3m_cpu0_clk_lvc1_r';
NODE_NAME     U2 BC64
 '@S9S_MB_2U_LIB.S9S_MB_2U(SCH_1):PAGE15_I1@PURE_QUANTA.SOCKET4677_AZIF0045P001C01CS(CHIPS)':
 'RSVD39': CDS_PINID='RSVD39';
NET_NAME
'TP_SPI_S3M_CPU0_CS0_LVC1_R_N'
 '@S9S_MB_2U_LIB.S9S_MB_2U(SCH_1):TP_SPI_S3M_CPU0_CS0_LVC1_R_N':
 C_SIGNAL='@s9s_mb_2u_lib.s9s_mb_2u(sch_1):tp_spi_s3m_cpu0_cs0_lvc1_r_n';
NODE_NAME     U2 BB61
 '@S9S_MB_2U_LIB.S9S_MB_2U(SCH_1):PAGE15_I1@PURE_QUANTA.SOCKET4677_AZIF0045P001C01CS(CHIPS)':
 'RSVD35': CDS_PINID='RSVD35';
NET_NAME
'TP_SPI_S3M_CPU0_CS1_LVC1_R_N'
 '@S9S_MB_2U_LIB.S9S_MB_2U(SCH_1):TP_SPI_S3M_CPU0_CS1_LVC1_R_N':
 C_SIGNAL='@s9s_mb_2u_lib.s9s_mb_2u(sch_1):tp_spi_s3m_cpu0_cs1_lvc1_r_n';
NODE_NAME     U2 AV63
 '@S9S_MB_2U_LIB.S9S_MB_2U(SCH_1):PAGE15_I1@PURE_QUANTA.SOCKET4677_AZIF0045P001C01CS(CHIPS)':
 'RSVD20': CDS_PINID='RSVD20';
NET_NAME
'TP_SPI_S3M_CPU0_IO0_LVC1_R'
 '@S9S_MB_2U_LIB.S9S_MB_2U(SCH_1):TP_SPI_S3M_CPU0_IO0_LVC1_R':
 C_SIGNAL='@s9s_mb_2u_lib.s9s_mb_2u(sch_1):tp_spi_s3m_cpu0_io0_lvc1_r';
NODE_NAME     U2 BA62
 '@S9S_MB_2U_LIB.S9S_MB_2U(SCH_1):PAGE15_I1@PURE_QUANTA.SOCKET4677_AZIF0045P001C01CS(CHIPS)':
 'RSVD32': CDS_PINID='RSVD32';
NET_NAME
'TP_SPI_S3M_CPU0_IO1_LVC1_R'
 '@S9S_MB_2U_LIB.S9S_MB_2U(SCH_1):TP_SPI_S3M_CPU0_IO1_LVC1_R':
 C_SIGNAL='@s9s_mb_2u_lib.s9s_mb_2u(sch_1):tp_spi_s3m_cpu0_io1_lvc1_r';
NODE_NAME     U2 AW64
 '@S9S_MB_2U_LIB.S9S_MB_2U(SCH_1):PAGE15_I1@PURE_QUANTA.SOCKET4677_AZIF0045P001C01CS(CHIPS)':
 'RSVD24': CDS_PINID='RSVD24';
NET_NAME
'TP_SPI_S3M_CPU0_IO2_LVC1_R'
 '@S9S_MB_2U_LIB.S9S_MB_2U(SCH_1):TP_SPI_S3M_CPU0_IO2_LVC1_R':
 C_SIGNAL='@s9s_mb_2u_lib.s9s_mb_2u(sch_1):tp_spi_s3m_cpu0_io2_lvc1_r';
NODE_NAME     U2 BD65
 '@S9S_MB_2U_LIB.S9S_MB_2U(SCH_1):PAGE15_I1@PURE_QUANTA.SOCKET4677_AZIF0045P001C01CS(CHIPS)':
 'RSVD42': CDS_PINID='RSVD42';
NET_NAME
'TP_SPI_S3M_CPU0_IO3_LVC1_R'
 '@S9S_MB_2U_LIB.S9S_MB_2U(SCH_1):TP_SPI_S3M_CPU0_IO3_LVC1_R':
 C_SIGNAL='@s9s_mb_2u_lib.s9s_mb_2u(sch_1):tp_spi_s3m_cpu0_io3_lvc1_r';
NODE_NAME     U2 BD61
 '@S9S_MB_2U_LIB.S9S_MB_2U(SCH_1):PAGE15_I1@PURE_QUANTA.SOCKET4677_AZIF0045P001C01CS(CHIPS)':
 'RSVD40': CDS_PINID='RSVD40';
NET_NAME
'TP_SPI_S3M_CPU0_OE_LVC1_R_N'
 '@S9S_MB_2U_LIB.S9S_MB_2U(SCH_1):TP_SPI_S3M_CPU0_OE_LVC1_R_N':
 C_SIGNAL='@s9s_mb_2u_lib.s9s_mb_2u(sch_1):tp_spi_s3m_cpu0_oe_lvc1_r_n';
NODE_NAME     U2 BA68
 '@S9S_MB_2U_LIB.S9S_MB_2U(SCH_1):PAGE15_I1@PURE_QUANTA.SOCKET4677_AZIF0045P001C01CS(CHIPS)':
 'RSVD34': CDS_PINID='RSVD34';
NET_NAME
'TP_TCA9539_0_P0_2'
 '@S9S_MB_2U_LIB.S9S_MB_2U(SCH_1):TP_TCA9539_0_P0_2':
 C_SIGNAL='@s9s_mb_2u_lib.s9s_mb_2u(sch_1):tp_tca9539_0_p0_2';
NODE_NAME     U181 6
 '@S9S_MB_2U_LIB.S9S_MB_2U(SCH_1):PAGE214_I66@PURE_QUANTA.PCA9539RPW(CHIPS)':
 'IO0_2': CDS_PINID='IO0_2';
NET_NAME
'TP_TCA9539_0_P0_3'
 '@S9S_MB_2U_LIB.S9S_MB_2U(SCH_1):TP_TCA9539_0_P0_3':
 C_SIGNAL='@s9s_mb_2u_lib.s9s_mb_2u(sch_1):tp_tca9539_0_p0_3';
NODE_NAME     U181 7
 '@S9S_MB_2U_LIB.S9S_MB_2U(SCH_1):PAGE214_I66@PURE_QUANTA.PCA9539RPW(CHIPS)':
 'IO0_3': CDS_PINID='IO0_3';
NET_NAME
'TP_TP_TRC_CPU0_PTI_MON<0>'
 '@S9S_MB_2U_LIB.S9S_MB_2U(SCH_1):TP_TP_TRC_CPU0_PTI_MON'<0>:
 C_SIGNAL='@s9s_mb_2u_lib.s9s_mb_2u(sch_1):tp_tp_trc_cpu0_pti_mon(0)';
NODE_NAME     U2 CC29
 '@S9S_MB_2U_LIB.S9S_MB_2U(SCH_1):PAGE19_I1@PURE_QUANTA.SOCKET4677_AZIF0045P001C01CS(CHIPS)':
 'PTI_DIE000': CDS_PINID='PTI_DIE000';
NET_NAME
'TP_TRC_CPU0_PTI0_CLK'
 '@S9S_MB_2U_LIB.S9S_MB_2U(SCH_1):TP_TRC_CPU0_PTI0_CLK':
 C_SIGNAL='@s9s_mb_2u_lib.s9s_mb_2u(sch_1):tp_trc_cpu0_pti0_clk';
NODE_NAME     U2 CB30
 '@S9S_MB_2U_LIB.S9S_MB_2U(SCH_1):PAGE19_I1@PURE_QUANTA.SOCKET4677_AZIF0045P001C01CS(CHIPS)':
 'PTI_DIE00_STB_0': CDS_PINID='PTI_DIE00_STB_0';
NET_NAME
'TP_TRC_CPU0_PTI1_CLK'
 '@S9S_MB_2U_LIB.S9S_MB_2U(SCH_1):TP_TRC_CPU0_PTI1_CLK':
 C_SIGNAL='@s9s_mb_2u_lib.s9s_mb_2u(sch_1):tp_trc_cpu0_pti1_clk';
NODE_NAME     U2 BY28
 '@S9S_MB_2U_LIB.S9S_MB_2U(SCH_1):PAGE19_I1@PURE_QUANTA.SOCKET4677_AZIF0045P001C01CS(CHIPS)':
 'PTI_DIE00_STB_1': CDS_PINID='PTI_DIE00_STB_1';
NET_NAME
'TP_TRC_CPU0_PTI2_CLK'
 '@S9S_MB_2U_LIB.S9S_MB_2U(SCH_1):TP_TRC_CPU0_PTI2_CLK':
 C_SIGNAL='@s9s_mb_2u_lib.s9s_mb_2u(sch_1):tp_trc_cpu0_pti2_clk';
NODE_NAME     U2 BF67
 '@S9S_MB_2U_LIB.S9S_MB_2U(SCH_1):PAGE19_I1@PURE_QUANTA.SOCKET4677_AZIF0045P001C01CS(CHIPS)':
 'PTI_DIE01_STB_0': CDS_PINID='PTI_DIE01_STB_0';
NET_NAME
'TP_TRC_CPU0_PTI3_CLK'
 '@S9S_MB_2U_LIB.S9S_MB_2U(SCH_1):TP_TRC_CPU0_PTI3_CLK':
 C_SIGNAL='@s9s_mb_2u_lib.s9s_mb_2u(sch_1):tp_trc_cpu0_pti3_clk';
NODE_NAME     U2 BK67
 '@S9S_MB_2U_LIB.S9S_MB_2U(SCH_1):PAGE19_I1@PURE_QUANTA.SOCKET4677_AZIF0045P001C01CS(CHIPS)':
 'PTI_DIE01_STB_1': CDS_PINID='PTI_DIE01_STB_1';
NET_NAME
'TP_TRC_CPU0_PTI<10>'
 '@S9S_MB_2U_LIB.S9S_MB_2U(SCH_1):TP_TRC_CPU0_PTI'<10>:
 C_SIGNAL='@s9s_mb_2u_lib.s9s_mb_2u(sch_1):tp_trc_cpu0_pti(10)';
NODE_NAME     U2 BU29
 '@S9S_MB_2U_LIB.S9S_MB_2U(SCH_1):PAGE19_I1@PURE_QUANTA.SOCKET4677_AZIF0045P001C01CS(CHIPS)':
 'PTI_DIE0010': CDS_PINID='PTI_DIE0010';
NET_NAME
'TP_TRC_CPU0_PTI<11>'
 '@S9S_MB_2U_LIB.S9S_MB_2U(SCH_1):TP_TRC_CPU0_PTI'<11>:
 C_SIGNAL='@s9s_mb_2u_lib.s9s_mb_2u(sch_1):tp_trc_cpu0_pti(11)';
NODE_NAME     U2 BT30
 '@S9S_MB_2U_LIB.S9S_MB_2U(SCH_1):PAGE19_I1@PURE_QUANTA.SOCKET4677_AZIF0045P001C01CS(CHIPS)':
 'PTI_DIE0011': CDS_PINID='PTI_DIE0011';
NET_NAME
'TP_TRC_CPU0_PTI<12>'
 '@S9S_MB_2U_LIB.S9S_MB_2U(SCH_1):TP_TRC_CPU0_PTI'<12>:
 C_SIGNAL='@s9s_mb_2u_lib.s9s_mb_2u(sch_1):tp_trc_cpu0_pti(12)';
NODE_NAME     U2 BN27
 '@S9S_MB_2U_LIB.S9S_MB_2U(SCH_1):PAGE19_I1@PURE_QUANTA.SOCKET4677_AZIF0045P001C01CS(CHIPS)':
 'PTI_DIE0012': CDS_PINID='PTI_DIE0012';
NET_NAME
'TP_TRC_CPU0_PTI<13>'
 '@S9S_MB_2U_LIB.S9S_MB_2U(SCH_1):TP_TRC_CPU0_PTI'<13>:
 C_SIGNAL='@s9s_mb_2u_lib.s9s_mb_2u(sch_1):tp_trc_cpu0_pti(13)';
NODE_NAME     U2 BP28
 '@S9S_MB_2U_LIB.S9S_MB_2U(SCH_1):PAGE19_I1@PURE_QUANTA.SOCKET4677_AZIF0045P001C01CS(CHIPS)':
 'PTI_DIE0013': CDS_PINID='PTI_DIE0013';
NET_NAME
'TP_TRC_CPU0_PTI<14>'
 '@S9S_MB_2U_LIB.S9S_MB_2U(SCH_1):TP_TRC_CPU0_PTI'<14>:
 C_SIGNAL='@s9s_mb_2u_lib.s9s_mb_2u(sch_1):tp_trc_cpu0_pti(14)';
NODE_NAME     U2 BN29
 '@S9S_MB_2U_LIB.S9S_MB_2U(SCH_1):PAGE19_I1@PURE_QUANTA.SOCKET4677_AZIF0045P001C01CS(CHIPS)':
 'PTI_DIE0014': CDS_PINID='PTI_DIE0014';
NET_NAME
'TP_TRC_CPU0_PTI<15>'
 '@S9S_MB_2U_LIB.S9S_MB_2U(SCH_1):TP_TRC_CPU0_PTI'<15>:
 C_SIGNAL='@s9s_mb_2u_lib.s9s_mb_2u(sch_1):tp_trc_cpu0_pti(15)';
NODE_NAME     U2 BP30
 '@S9S_MB_2U_LIB.S9S_MB_2U(SCH_1):PAGE19_I1@PURE_QUANTA.SOCKET4677_AZIF0045P001C01CS(CHIPS)':
 'PTI_DIE0015': CDS_PINID='PTI_DIE0015';
NET_NAME
'TP_TRC_CPU0_PTI<16>'
 '@S9S_MB_2U_LIB.S9S_MB_2U(SCH_1):TP_TRC_CPU0_PTI'<16>:
 C_SIGNAL='@s9s_mb_2u_lib.s9s_mb_2u(sch_1):tp_trc_cpu0_pti(16)';
NODE_NAME     U2 BC70
 '@S9S_MB_2U_LIB.S9S_MB_2U(SCH_1):PAGE19_I1@PURE_QUANTA.SOCKET4677_AZIF0045P001C01CS(CHIPS)':
 'PTI_DIE010': CDS_PINID='PTI_DIE010';
NET_NAME
'TP_TRC_CPU0_PTI<17>'
 '@S9S_MB_2U_LIB.S9S_MB_2U(SCH_1):TP_TRC_CPU0_PTI'<17>:
 C_SIGNAL='@s9s_mb_2u_lib.s9s_mb_2u(sch_1):tp_trc_cpu0_pti(17)';
NODE_NAME     U2 BE70
 '@S9S_MB_2U_LIB.S9S_MB_2U(SCH_1):PAGE19_I1@PURE_QUANTA.SOCKET4677_AZIF0045P001C01CS(CHIPS)':
 'PTI_DIE011': CDS_PINID='PTI_DIE011';
NET_NAME
'TP_TRC_CPU0_PTI<18>'
 '@S9S_MB_2U_LIB.S9S_MB_2U(SCH_1):TP_TRC_CPU0_PTI'<18>:
 C_SIGNAL='@s9s_mb_2u_lib.s9s_mb_2u(sch_1):tp_trc_cpu0_pti(18)';
NODE_NAME     U2 BD69
 '@S9S_MB_2U_LIB.S9S_MB_2U(SCH_1):PAGE19_I1@PURE_QUANTA.SOCKET4677_AZIF0045P001C01CS(CHIPS)':
 'PTI_DIE012': CDS_PINID='PTI_DIE012';
NET_NAME
'TP_TRC_CPU0_PTI<19>'
 '@S9S_MB_2U_LIB.S9S_MB_2U(SCH_1):TP_TRC_CPU0_PTI'<19>:
 C_SIGNAL='@s9s_mb_2u_lib.s9s_mb_2u(sch_1):tp_trc_cpu0_pti(19)';
NODE_NAME     U2 BF69
 '@S9S_MB_2U_LIB.S9S_MB_2U(SCH_1):PAGE19_I1@PURE_QUANTA.SOCKET4677_AZIF0045P001C01CS(CHIPS)':
 'PTI_DIE013': CDS_PINID='PTI_DIE013';
NET_NAME
'TP_TRC_CPU0_PTI<20>'
 '@S9S_MB_2U_LIB.S9S_MB_2U(SCH_1):TP_TRC_CPU0_PTI'<20>:
 C_SIGNAL='@s9s_mb_2u_lib.s9s_mb_2u(sch_1):tp_trc_cpu0_pti(20)';
NODE_NAME     U2 BH69
 '@S9S_MB_2U_LIB.S9S_MB_2U(SCH_1):PAGE19_I1@PURE_QUANTA.SOCKET4677_AZIF0045P001C01CS(CHIPS)':
 'PTI_DIE014': CDS_PINID='PTI_DIE014';
NET_NAME
'TP_TRC_CPU0_PTI<21>'
 '@S9S_MB_2U_LIB.S9S_MB_2U(SCH_1):TP_TRC_CPU0_PTI'<21>:
 C_SIGNAL='@s9s_mb_2u_lib.s9s_mb_2u(sch_1):tp_trc_cpu0_pti(21)';
NODE_NAME     U2 BC68
 '@S9S_MB_2U_LIB.S9S_MB_2U(SCH_1):PAGE19_I1@PURE_QUANTA.SOCKET4677_AZIF0045P001C01CS(CHIPS)':
 'PTI_DIE015': CDS_PINID='PTI_DIE015';
NET_NAME
'TP_TRC_CPU0_PTI<22>'
 '@S9S_MB_2U_LIB.S9S_MB_2U(SCH_1):TP_TRC_CPU0_PTI'<22>:
 C_SIGNAL='@s9s_mb_2u_lib.s9s_mb_2u(sch_1):tp_trc_cpu0_pti(22)';
NODE_NAME     U2 BG68
 '@S9S_MB_2U_LIB.S9S_MB_2U(SCH_1):PAGE19_I1@PURE_QUANTA.SOCKET4677_AZIF0045P001C01CS(CHIPS)':
 'PTI_DIE016': CDS_PINID='PTI_DIE016';
NET_NAME
'TP_TRC_CPU0_PTI<23>'
 '@S9S_MB_2U_LIB.S9S_MB_2U(SCH_1):TP_TRC_CPU0_PTI'<23>:
 C_SIGNAL='@s9s_mb_2u_lib.s9s_mb_2u(sch_1):tp_trc_cpu0_pti(23)';
NODE_NAME     U2 BD67
 '@S9S_MB_2U_LIB.S9S_MB_2U(SCH_1):PAGE19_I1@PURE_QUANTA.SOCKET4677_AZIF0045P001C01CS(CHIPS)':
 'PTI_DIE017': CDS_PINID='PTI_DIE017';
NET_NAME
'TP_TRC_CPU0_PTI<24>'
 '@S9S_MB_2U_LIB.S9S_MB_2U(SCH_1):TP_TRC_CPU0_PTI'<24>:
 C_SIGNAL='@s9s_mb_2u_lib.s9s_mb_2u(sch_1):tp_trc_cpu0_pti(24)';
NODE_NAME     U2 BK69
 '@S9S_MB_2U_LIB.S9S_MB_2U(SCH_1):PAGE19_I1@PURE_QUANTA.SOCKET4677_AZIF0045P001C01CS(CHIPS)':
 'PTI_DIE018': CDS_PINID='PTI_DIE018';
NET_NAME
'TP_TRC_CPU0_PTI<25>'
 '@S9S_MB_2U_LIB.S9S_MB_2U(SCH_1):TP_TRC_CPU0_PTI'<25>:
 C_SIGNAL='@s9s_mb_2u_lib.s9s_mb_2u(sch_1):tp_trc_cpu0_pti(25)';
NODE_NAME     U2 BM69
 '@S9S_MB_2U_LIB.S9S_MB_2U(SCH_1):PAGE19_I1@PURE_QUANTA.SOCKET4677_AZIF0045P001C01CS(CHIPS)':
 'PTI_DIE019': CDS_PINID='PTI_DIE019';
NET_NAME
'TP_TRC_CPU0_PTI<26>'
 '@S9S_MB_2U_LIB.S9S_MB_2U(SCH_1):TP_TRC_CPU0_PTI'<26>:
 C_SIGNAL='@s9s_mb_2u_lib.s9s_mb_2u(sch_1):tp_trc_cpu0_pti(26)';
NODE_NAME     U2 BN68
 '@S9S_MB_2U_LIB.S9S_MB_2U(SCH_1):PAGE19_I1@PURE_QUANTA.SOCKET4677_AZIF0045P001C01CS(CHIPS)':
 'PTI_DIE0110': CDS_PINID='PTI_DIE0110';
NET_NAME
'TP_TRC_CPU0_PTI<27>'
 '@S9S_MB_2U_LIB.S9S_MB_2U(SCH_1):TP_TRC_CPU0_PTI'<27>:
 C_SIGNAL='@s9s_mb_2u_lib.s9s_mb_2u(sch_1):tp_trc_cpu0_pti(27)';
NODE_NAME     U2 BG66
 '@S9S_MB_2U_LIB.S9S_MB_2U(SCH_1):PAGE19_I1@PURE_QUANTA.SOCKET4677_AZIF0045P001C01CS(CHIPS)':
 'PTI_DIE0111': CDS_PINID='PTI_DIE0111';
NET_NAME
'TP_TRC_CPU0_PTI<28>'
 '@S9S_MB_2U_LIB.S9S_MB_2U(SCH_1):TP_TRC_CPU0_PTI'<28>:
 C_SIGNAL='@s9s_mb_2u_lib.s9s_mb_2u(sch_1):tp_trc_cpu0_pti(28)';
NODE_NAME     U2 BJ66
 '@S9S_MB_2U_LIB.S9S_MB_2U(SCH_1):PAGE19_I1@PURE_QUANTA.SOCKET4677_AZIF0045P001C01CS(CHIPS)':
 'PTI_DIE0112': CDS_PINID='PTI_DIE0112';
NET_NAME
'TP_TRC_CPU0_PTI<29>'
 '@S9S_MB_2U_LIB.S9S_MB_2U(SCH_1):TP_TRC_CPU0_PTI'<29>:
 C_SIGNAL='@s9s_mb_2u_lib.s9s_mb_2u(sch_1):tp_trc_cpu0_pti(29)';
NODE_NAME     U2 BL66
 '@S9S_MB_2U_LIB.S9S_MB_2U(SCH_1):PAGE19_I1@PURE_QUANTA.SOCKET4677_AZIF0045P001C01CS(CHIPS)':
 'PTI_DIE0113': CDS_PINID='PTI_DIE0113';
NET_NAME
'TP_TRC_CPU0_PTI<2>'
 '@S9S_MB_2U_LIB.S9S_MB_2U(SCH_1):TP_TRC_CPU0_PTI'<2>:
 C_SIGNAL='@s9s_mb_2u_lib.s9s_mb_2u(sch_1):tp_trc_cpu0_pti(2)';
NODE_NAME     U2 CC27
 '@S9S_MB_2U_LIB.S9S_MB_2U(SCH_1):PAGE19_I1@PURE_QUANTA.SOCKET4677_AZIF0045P001C01CS(CHIPS)':
 'PTI_DIE002': CDS_PINID='PTI_DIE002';
NET_NAME
'TP_TRC_CPU0_PTI<30>'
 '@S9S_MB_2U_LIB.S9S_MB_2U(SCH_1):TP_TRC_CPU0_PTI'<30>:
 C_SIGNAL='@s9s_mb_2u_lib.s9s_mb_2u(sch_1):tp_trc_cpu0_pti(30)';
NODE_NAME     U2 BM67
 '@S9S_MB_2U_LIB.S9S_MB_2U(SCH_1):PAGE19_I1@PURE_QUANTA.SOCKET4677_AZIF0045P001C01CS(CHIPS)':
 'PTI_DIE0114': CDS_PINID='PTI_DIE0114';
NET_NAME
'TP_TRC_CPU0_PTI<31>'
 '@S9S_MB_2U_LIB.S9S_MB_2U(SCH_1):TP_TRC_CPU0_PTI'<31>:
 C_SIGNAL='@s9s_mb_2u_lib.s9s_mb_2u(sch_1):tp_trc_cpu0_pti(31)';
NODE_NAME     U2 BN66
 '@S9S_MB_2U_LIB.S9S_MB_2U(SCH_1):PAGE19_I1@PURE_QUANTA.SOCKET4677_AZIF0045P001C01CS(CHIPS)':
 'PTI_DIE0115': CDS_PINID='PTI_DIE0115';
NET_NAME
'TP_TRC_CPU0_PTI<3>'
 '@S9S_MB_2U_LIB.S9S_MB_2U(SCH_1):TP_TRC_CPU0_PTI'<3>:
 C_SIGNAL='@s9s_mb_2u_lib.s9s_mb_2u(sch_1):tp_trc_cpu0_pti(3)';
NODE_NAME     U2 BY30
 '@S9S_MB_2U_LIB.S9S_MB_2U(SCH_1):PAGE19_I1@PURE_QUANTA.SOCKET4677_AZIF0045P001C01CS(CHIPS)':
 'PTI_DIE003': CDS_PINID='PTI_DIE003';
NET_NAME
'TP_TRC_CPU0_PTI<4>'
 '@S9S_MB_2U_LIB.S9S_MB_2U(SCH_1):TP_TRC_CPU0_PTI'<4>:
 C_SIGNAL='@s9s_mb_2u_lib.s9s_mb_2u(sch_1):tp_trc_cpu0_pti(4)';
NODE_NAME     U2 CA29
 '@S9S_MB_2U_LIB.S9S_MB_2U(SCH_1):PAGE19_I1@PURE_QUANTA.SOCKET4677_AZIF0045P001C01CS(CHIPS)':
 'PTI_DIE004': CDS_PINID='PTI_DIE004';
NET_NAME
'TP_TRC_CPU0_PTI<5>'
 '@S9S_MB_2U_LIB.S9S_MB_2U(SCH_1):TP_TRC_CPU0_PTI'<5>:
 C_SIGNAL='@s9s_mb_2u_lib.s9s_mb_2u(sch_1):tp_trc_cpu0_pti(5)';
NODE_NAME     U2 BV30
 '@S9S_MB_2U_LIB.S9S_MB_2U(SCH_1):PAGE19_I1@PURE_QUANTA.SOCKET4677_AZIF0045P001C01CS(CHIPS)':
 'PTI_DIE005': CDS_PINID='PTI_DIE005';
NET_NAME
'TP_TRC_CPU0_PTI<6>'
 '@S9S_MB_2U_LIB.S9S_MB_2U(SCH_1):TP_TRC_CPU0_PTI'<6>:
 C_SIGNAL='@s9s_mb_2u_lib.s9s_mb_2u(sch_1):tp_trc_cpu0_pti(6)';
NODE_NAME     U2 CA27
 '@S9S_MB_2U_LIB.S9S_MB_2U(SCH_1):PAGE19_I1@PURE_QUANTA.SOCKET4677_AZIF0045P001C01CS(CHIPS)':
 'PTI_DIE006': CDS_PINID='PTI_DIE006';
NET_NAME
'TP_TRC_CPU0_PTI<7>'
 '@S9S_MB_2U_LIB.S9S_MB_2U(SCH_1):TP_TRC_CPU0_PTI'<7>:
 C_SIGNAL='@s9s_mb_2u_lib.s9s_mb_2u(sch_1):tp_trc_cpu0_pti(7)';
NODE_NAME     U2 BV28
 '@S9S_MB_2U_LIB.S9S_MB_2U(SCH_1):PAGE19_I1@PURE_QUANTA.SOCKET4677_AZIF0045P001C01CS(CHIPS)':
 'PTI_DIE007': CDS_PINID='PTI_DIE007';
NET_NAME
'TP_TRC_CPU0_PTI<8>'
 '@S9S_MB_2U_LIB.S9S_MB_2U(SCH_1):TP_TRC_CPU0_PTI'<8>:
 C_SIGNAL='@s9s_mb_2u_lib.s9s_mb_2u(sch_1):tp_trc_cpu0_pti(8)';
NODE_NAME     U2 BU27
 '@S9S_MB_2U_LIB.S9S_MB_2U(SCH_1):PAGE19_I1@PURE_QUANTA.SOCKET4677_AZIF0045P001C01CS(CHIPS)':
 'PTI_DIE008': CDS_PINID='PTI_DIE008';
NET_NAME
'TP_TRC_CPU0_PTI<9>'
 '@S9S_MB_2U_LIB.S9S_MB_2U(SCH_1):TP_TRC_CPU0_PTI'<9>:
 C_SIGNAL='@s9s_mb_2u_lib.s9s_mb_2u(sch_1):tp_trc_cpu0_pti(9)';
NODE_NAME     U2 BT28
 '@S9S_MB_2U_LIB.S9S_MB_2U(SCH_1):PAGE19_I1@PURE_QUANTA.SOCKET4677_AZIF0045P001C01CS(CHIPS)':
 'PTI_DIE009': CDS_PINID='PTI_DIE009';
NET_NAME
'TP_TRC_CPU0_PTI_MON<1>'
 '@S9S_MB_2U_LIB.S9S_MB_2U(SCH_1):TP_TRC_CPU0_PTI_MON'<1>:
 C_SIGNAL='@s9s_mb_2u_lib.s9s_mb_2u(sch_1):tp_trc_cpu0_pti_mon(1)';
NODE_NAME     U2 CD28
 '@S9S_MB_2U_LIB.S9S_MB_2U(SCH_1):PAGE19_I1@PURE_QUANTA.SOCKET4677_AZIF0045P001C01CS(CHIPS)':
 'PTI_DIE001': CDS_PINID='PTI_DIE001';
NET_NAME
'TP_TRC_CPU1_PTI0_CLK'
 '@S9S_MB_2U_LIB.S9S_MB_2U(SCH_1):TP_TRC_CPU1_PTI0_CLK':
 C_SIGNAL='@s9s_mb_2u_lib.s9s_mb_2u(sch_1):tp_trc_cpu1_pti0_clk';
NODE_NAME     U1 CB30
 '@S9S_MB_2U_LIB.S9S_MB_2U(SCH_1):PAGE50_I23@PURE_QUANTA.SOCKET4677_AZIF0045P001C01CS(CHIPS)':
 'PTI_DIE00_STB_0': CDS_PINID='PTI_DIE00_STB_0';
NET_NAME
'TP_TRC_CPU1_PTI1_CLK'
 '@S9S_MB_2U_LIB.S9S_MB_2U(SCH_1):TP_TRC_CPU1_PTI1_CLK':
 C_SIGNAL='@s9s_mb_2u_lib.s9s_mb_2u(sch_1):tp_trc_cpu1_pti1_clk';
NODE_NAME     U1 BY28
 '@S9S_MB_2U_LIB.S9S_MB_2U(SCH_1):PAGE50_I23@PURE_QUANTA.SOCKET4677_AZIF0045P001C01CS(CHIPS)':
 'PTI_DIE00_STB_1': CDS_PINID='PTI_DIE00_STB_1';
NET_NAME
'TP_TRC_CPU1_PTI2_CLK'
 '@S9S_MB_2U_LIB.S9S_MB_2U(SCH_1):TP_TRC_CPU1_PTI2_CLK':
 C_SIGNAL='@s9s_mb_2u_lib.s9s_mb_2u(sch_1):tp_trc_cpu1_pti2_clk';
NODE_NAME     U1 BF67
 '@S9S_MB_2U_LIB.S9S_MB_2U(SCH_1):PAGE50_I23@PURE_QUANTA.SOCKET4677_AZIF0045P001C01CS(CHIPS)':
 'PTI_DIE01_STB_0': CDS_PINID='PTI_DIE01_STB_0';
NET_NAME
'TP_TRC_CPU1_PTI3_CLK'
 '@S9S_MB_2U_LIB.S9S_MB_2U(SCH_1):TP_TRC_CPU1_PTI3_CLK':
 C_SIGNAL='@s9s_mb_2u_lib.s9s_mb_2u(sch_1):tp_trc_cpu1_pti3_clk';
NODE_NAME     U1 BK67
 '@S9S_MB_2U_LIB.S9S_MB_2U(SCH_1):PAGE50_I23@PURE_QUANTA.SOCKET4677_AZIF0045P001C01CS(CHIPS)':
 'PTI_DIE01_STB_1': CDS_PINID='PTI_DIE01_STB_1';
NET_NAME
'TP_TRC_CPU1_PTI<0>'
 '@S9S_MB_2U_LIB.S9S_MB_2U(SCH_1):TP_TRC_CPU1_PTI'<0>:
 C_SIGNAL='@s9s_mb_2u_lib.s9s_mb_2u(sch_1):tp_trc_cpu1_pti(0)';
NODE_NAME     U1 CC29
 '@S9S_MB_2U_LIB.S9S_MB_2U(SCH_1):PAGE50_I23@PURE_QUANTA.SOCKET4677_AZIF0045P001C01CS(CHIPS)':
 'PTI_DIE000': CDS_PINID='PTI_DIE000';
NET_NAME
'TP_TRC_CPU1_PTI<10>'
 '@S9S_MB_2U_LIB.S9S_MB_2U(SCH_1):TP_TRC_CPU1_PTI'<10>:
 C_SIGNAL='@s9s_mb_2u_lib.s9s_mb_2u(sch_1):tp_trc_cpu1_pti(10)';
NODE_NAME     U1 BU29
 '@S9S_MB_2U_LIB.S9S_MB_2U(SCH_1):PAGE50_I23@PURE_QUANTA.SOCKET4677_AZIF0045P001C01CS(CHIPS)':
 'PTI_DIE0010': CDS_PINID='PTI_DIE0010';
NET_NAME
'TP_TRC_CPU1_PTI<11>'
 '@S9S_MB_2U_LIB.S9S_MB_2U(SCH_1):TP_TRC_CPU1_PTI'<11>:
 C_SIGNAL='@s9s_mb_2u_lib.s9s_mb_2u(sch_1):tp_trc_cpu1_pti(11)';
NODE_NAME     U1 BT30
 '@S9S_MB_2U_LIB.S9S_MB_2U(SCH_1):PAGE50_I23@PURE_QUANTA.SOCKET4677_AZIF0045P001C01CS(CHIPS)':
 'PTI_DIE0011': CDS_PINID='PTI_DIE0011';
NET_NAME
'TP_TRC_CPU1_PTI<12>'
 '@S9S_MB_2U_LIB.S9S_MB_2U(SCH_1):TP_TRC_CPU1_PTI'<12>:
 C_SIGNAL='@s9s_mb_2u_lib.s9s_mb_2u(sch_1):tp_trc_cpu1_pti(12)';
NODE_NAME     U1 BN27
 '@S9S_MB_2U_LIB.S9S_MB_2U(SCH_1):PAGE50_I23@PURE_QUANTA.SOCKET4677_AZIF0045P001C01CS(CHIPS)':
 'PTI_DIE0012': CDS_PINID='PTI_DIE0012';
NET_NAME
'TP_TRC_CPU1_PTI<13>'
 '@S9S_MB_2U_LIB.S9S_MB_2U(SCH_1):TP_TRC_CPU1_PTI'<13>:
 C_SIGNAL='@s9s_mb_2u_lib.s9s_mb_2u(sch_1):tp_trc_cpu1_pti(13)';
NODE_NAME     U1 BP28
 '@S9S_MB_2U_LIB.S9S_MB_2U(SCH_1):PAGE50_I23@PURE_QUANTA.SOCKET4677_AZIF0045P001C01CS(CHIPS)':
 'PTI_DIE0013': CDS_PINID='PTI_DIE0013';
NET_NAME
'TP_TRC_CPU1_PTI<14>'
 '@S9S_MB_2U_LIB.S9S_MB_2U(SCH_1):TP_TRC_CPU1_PTI'<14>:
 C_SIGNAL='@s9s_mb_2u_lib.s9s_mb_2u(sch_1):tp_trc_cpu1_pti(14)';
NODE_NAME     U1 BN29
 '@S9S_MB_2U_LIB.S9S_MB_2U(SCH_1):PAGE50_I23@PURE_QUANTA.SOCKET4677_AZIF0045P001C01CS(CHIPS)':
 'PTI_DIE0014': CDS_PINID='PTI_DIE0014';
NET_NAME
'TP_TRC_CPU1_PTI<15>'
 '@S9S_MB_2U_LIB.S9S_MB_2U(SCH_1):TP_TRC_CPU1_PTI'<15>:
 C_SIGNAL='@s9s_mb_2u_lib.s9s_mb_2u(sch_1):tp_trc_cpu1_pti(15)';
NODE_NAME     U1 BP30
 '@S9S_MB_2U_LIB.S9S_MB_2U(SCH_1):PAGE50_I23@PURE_QUANTA.SOCKET4677_AZIF0045P001C01CS(CHIPS)':
 'PTI_DIE0015': CDS_PINID='PTI_DIE0015';
NET_NAME
'TP_TRC_CPU1_PTI<16>'
 '@S9S_MB_2U_LIB.S9S_MB_2U(SCH_1):TP_TRC_CPU1_PTI'<16>:
 C_SIGNAL='@s9s_mb_2u_lib.s9s_mb_2u(sch_1):tp_trc_cpu1_pti(16)';
NODE_NAME     U1 BC70
 '@S9S_MB_2U_LIB.S9S_MB_2U(SCH_1):PAGE50_I23@PURE_QUANTA.SOCKET4677_AZIF0045P001C01CS(CHIPS)':
 'PTI_DIE010': CDS_PINID='PTI_DIE010';
NET_NAME
'TP_TRC_CPU1_PTI<17>'
 '@S9S_MB_2U_LIB.S9S_MB_2U(SCH_1):TP_TRC_CPU1_PTI'<17>:
 C_SIGNAL='@s9s_mb_2u_lib.s9s_mb_2u(sch_1):tp_trc_cpu1_pti(17)';
NODE_NAME     U1 BE70
 '@S9S_MB_2U_LIB.S9S_MB_2U(SCH_1):PAGE50_I23@PURE_QUANTA.SOCKET4677_AZIF0045P001C01CS(CHIPS)':
 'PTI_DIE011': CDS_PINID='PTI_DIE011';
NET_NAME
'TP_TRC_CPU1_PTI<18>'
 '@S9S_MB_2U_LIB.S9S_MB_2U(SCH_1):TP_TRC_CPU1_PTI'<18>:
 C_SIGNAL='@s9s_mb_2u_lib.s9s_mb_2u(sch_1):tp_trc_cpu1_pti(18)';
NODE_NAME     U1 BD69
 '@S9S_MB_2U_LIB.S9S_MB_2U(SCH_1):PAGE50_I23@PURE_QUANTA.SOCKET4677_AZIF0045P001C01CS(CHIPS)':
 'PTI_DIE012': CDS_PINID='PTI_DIE012';
NET_NAME
'TP_TRC_CPU1_PTI<19>'
 '@S9S_MB_2U_LIB.S9S_MB_2U(SCH_1):TP_TRC_CPU1_PTI'<19>:
 C_SIGNAL='@s9s_mb_2u_lib.s9s_mb_2u(sch_1):tp_trc_cpu1_pti(19)';
NODE_NAME     U1 BF69
 '@S9S_MB_2U_LIB.S9S_MB_2U(SCH_1):PAGE50_I23@PURE_QUANTA.SOCKET4677_AZIF0045P001C01CS(CHIPS)':
 'PTI_DIE013': CDS_PINID='PTI_DIE013';
NET_NAME
'TP_TRC_CPU1_PTI<1>'
 '@S9S_MB_2U_LIB.S9S_MB_2U(SCH_1):TP_TRC_CPU1_PTI'<1>:
 C_SIGNAL='@s9s_mb_2u_lib.s9s_mb_2u(sch_1):tp_trc_cpu1_pti(1)';
NODE_NAME     U1 CD28
 '@S9S_MB_2U_LIB.S9S_MB_2U(SCH_1):PAGE50_I23@PURE_QUANTA.SOCKET4677_AZIF0045P001C01CS(CHIPS)':
 'PTI_DIE001': CDS_PINID='PTI_DIE001';
NET_NAME
'TP_TRC_CPU1_PTI<20>'
 '@S9S_MB_2U_LIB.S9S_MB_2U(SCH_1):TP_TRC_CPU1_PTI'<20>:
 C_SIGNAL='@s9s_mb_2u_lib.s9s_mb_2u(sch_1):tp_trc_cpu1_pti(20)';
NODE_NAME     U1 BH69
 '@S9S_MB_2U_LIB.S9S_MB_2U(SCH_1):PAGE50_I23@PURE_QUANTA.SOCKET4677_AZIF0045P001C01CS(CHIPS)':
 'PTI_DIE014': CDS_PINID='PTI_DIE014';
NET_NAME
'TP_TRC_CPU1_PTI<21>'
 '@S9S_MB_2U_LIB.S9S_MB_2U(SCH_1):TP_TRC_CPU1_PTI'<21>:
 C_SIGNAL='@s9s_mb_2u_lib.s9s_mb_2u(sch_1):tp_trc_cpu1_pti(21)';
NODE_NAME     U1 BC68
 '@S9S_MB_2U_LIB.S9S_MB_2U(SCH_1):PAGE50_I23@PURE_QUANTA.SOCKET4677_AZIF0045P001C01CS(CHIPS)':
 'PTI_DIE015': CDS_PINID='PTI_DIE015';
NET_NAME
'TP_TRC_CPU1_PTI<22>'
 '@S9S_MB_2U_LIB.S9S_MB_2U(SCH_1):TP_TRC_CPU1_PTI'<22>:
 C_SIGNAL='@s9s_mb_2u_lib.s9s_mb_2u(sch_1):tp_trc_cpu1_pti(22)';
NODE_NAME     U1 BG68
 '@S9S_MB_2U_LIB.S9S_MB_2U(SCH_1):PAGE50_I23@PURE_QUANTA.SOCKET4677_AZIF0045P001C01CS(CHIPS)':
 'PTI_DIE016': CDS_PINID='PTI_DIE016';
NET_NAME
'TP_TRC_CPU1_PTI<23>'
 '@S9S_MB_2U_LIB.S9S_MB_2U(SCH_1):TP_TRC_CPU1_PTI'<23>:
 C_SIGNAL='@s9s_mb_2u_lib.s9s_mb_2u(sch_1):tp_trc_cpu1_pti(23)';
NODE_NAME     U1 BD67
 '@S9S_MB_2U_LIB.S9S_MB_2U(SCH_1):PAGE50_I23@PURE_QUANTA.SOCKET4677_AZIF0045P001C01CS(CHIPS)':
 'PTI_DIE017': CDS_PINID='PTI_DIE017';
NET_NAME
'TP_TRC_CPU1_PTI<24>'
 '@S9S_MB_2U_LIB.S9S_MB_2U(SCH_1):TP_TRC_CPU1_PTI'<24>:
 C_SIGNAL='@s9s_mb_2u_lib.s9s_mb_2u(sch_1):tp_trc_cpu1_pti(24)';
NODE_NAME     U1 BK69
 '@S9S_MB_2U_LIB.S9S_MB_2U(SCH_1):PAGE50_I23@PURE_QUANTA.SOCKET4677_AZIF0045P001C01CS(CHIPS)':
 'PTI_DIE018': CDS_PINID='PTI_DIE018';
NET_NAME
'TP_TRC_CPU1_PTI<25>'
 '@S9S_MB_2U_LIB.S9S_MB_2U(SCH_1):TP_TRC_CPU1_PTI'<25>:
 C_SIGNAL='@s9s_mb_2u_lib.s9s_mb_2u(sch_1):tp_trc_cpu1_pti(25)';
NODE_NAME     U1 BM69
 '@S9S_MB_2U_LIB.S9S_MB_2U(SCH_1):PAGE50_I23@PURE_QUANTA.SOCKET4677_AZIF0045P001C01CS(CHIPS)':
 'PTI_DIE019': CDS_PINID='PTI_DIE019';
NET_NAME
'TP_TRC_CPU1_PTI<26>'
 '@S9S_MB_2U_LIB.S9S_MB_2U(SCH_1):TP_TRC_CPU1_PTI'<26>:
 C_SIGNAL='@s9s_mb_2u_lib.s9s_mb_2u(sch_1):tp_trc_cpu1_pti(26)';
NODE_NAME     U1 BN68
 '@S9S_MB_2U_LIB.S9S_MB_2U(SCH_1):PAGE50_I23@PURE_QUANTA.SOCKET4677_AZIF0045P001C01CS(CHIPS)':
 'PTI_DIE0110': CDS_PINID='PTI_DIE0110';
NET_NAME
'TP_TRC_CPU1_PTI<27>'
 '@S9S_MB_2U_LIB.S9S_MB_2U(SCH_1):TP_TRC_CPU1_PTI'<27>:
 C_SIGNAL='@s9s_mb_2u_lib.s9s_mb_2u(sch_1):tp_trc_cpu1_pti(27)';
NODE_NAME     U1 BG66
 '@S9S_MB_2U_LIB.S9S_MB_2U(SCH_1):PAGE50_I23@PURE_QUANTA.SOCKET4677_AZIF0045P001C01CS(CHIPS)':
 'PTI_DIE0111': CDS_PINID='PTI_DIE0111';
NET_NAME
'TP_TRC_CPU1_PTI<28>'
 '@S9S_MB_2U_LIB.S9S_MB_2U(SCH_1):TP_TRC_CPU1_PTI'<28>:
 C_SIGNAL='@s9s_mb_2u_lib.s9s_mb_2u(sch_1):tp_trc_cpu1_pti(28)';
NODE_NAME     U1 BJ66
 '@S9S_MB_2U_LIB.S9S_MB_2U(SCH_1):PAGE50_I23@PURE_QUANTA.SOCKET4677_AZIF0045P001C01CS(CHIPS)':
 'PTI_DIE0112': CDS_PINID='PTI_DIE0112';
NET_NAME
'TP_TRC_CPU1_PTI<29>'
 '@S9S_MB_2U_LIB.S9S_MB_2U(SCH_1):TP_TRC_CPU1_PTI'<29>:
 C_SIGNAL='@s9s_mb_2u_lib.s9s_mb_2u(sch_1):tp_trc_cpu1_pti(29)';
NODE_NAME     U1 BL66
 '@S9S_MB_2U_LIB.S9S_MB_2U(SCH_1):PAGE50_I23@PURE_QUANTA.SOCKET4677_AZIF0045P001C01CS(CHIPS)':
 'PTI_DIE0113': CDS_PINID='PTI_DIE0113';
NET_NAME
'TP_TRC_CPU1_PTI<2>'
 '@S9S_MB_2U_LIB.S9S_MB_2U(SCH_1):TP_TRC_CPU1_PTI'<2>:
 C_SIGNAL='@s9s_mb_2u_lib.s9s_mb_2u(sch_1):tp_trc_cpu1_pti(2)';
NODE_NAME     U1 CC27
 '@S9S_MB_2U_LIB.S9S_MB_2U(SCH_1):PAGE50_I23@PURE_QUANTA.SOCKET4677_AZIF0045P001C01CS(CHIPS)':
 'PTI_DIE002': CDS_PINID='PTI_DIE002';
NET_NAME
'TP_TRC_CPU1_PTI<30>'
 '@S9S_MB_2U_LIB.S9S_MB_2U(SCH_1):TP_TRC_CPU1_PTI'<30>:
 C_SIGNAL='@s9s_mb_2u_lib.s9s_mb_2u(sch_1):tp_trc_cpu1_pti(30)';
NODE_NAME     U1 BM67
 '@S9S_MB_2U_LIB.S9S_MB_2U(SCH_1):PAGE50_I23@PURE_QUANTA.SOCKET4677_AZIF0045P001C01CS(CHIPS)':
 'PTI_DIE0114': CDS_PINID='PTI_DIE0114';
NET_NAME
'TP_TRC_CPU1_PTI<31>'
 '@S9S_MB_2U_LIB.S9S_MB_2U(SCH_1):TP_TRC_CPU1_PTI'<31>:
 C_SIGNAL='@s9s_mb_2u_lib.s9s_mb_2u(sch_1):tp_trc_cpu1_pti(31)';
NODE_NAME     U1 BN66
 '@S9S_MB_2U_LIB.S9S_MB_2U(SCH_1):PAGE50_I23@PURE_QUANTA.SOCKET4677_AZIF0045P001C01CS(CHIPS)':
 'PTI_DIE0115': CDS_PINID='PTI_DIE0115';
NET_NAME
'TP_TRC_CPU1_PTI<3>'
 '@S9S_MB_2U_LIB.S9S_MB_2U(SCH_1):TP_TRC_CPU1_PTI'<3>:
 C_SIGNAL='@s9s_mb_2u_lib.s9s_mb_2u(sch_1):tp_trc_cpu1_pti(3)';
NODE_NAME     U1 BY30
 '@S9S_MB_2U_LIB.S9S_MB_2U(SCH_1):PAGE50_I23@PURE_QUANTA.SOCKET4677_AZIF0045P001C01CS(CHIPS)':
 'PTI_DIE003': CDS_PINID='PTI_DIE003';
NET_NAME
'TP_TRC_CPU1_PTI<4>'
 '@S9S_MB_2U_LIB.S9S_MB_2U(SCH_1):TP_TRC_CPU1_PTI'<4>:
 C_SIGNAL='@s9s_mb_2u_lib.s9s_mb_2u(sch_1):tp_trc_cpu1_pti(4)';
NODE_NAME     U1 CA29
 '@S9S_MB_2U_LIB.S9S_MB_2U(SCH_1):PAGE50_I23@PURE_QUANTA.SOCKET4677_AZIF0045P001C01CS(CHIPS)':
 'PTI_DIE004': CDS_PINID='PTI_DIE004';
NET_NAME
'TP_TRC_CPU1_PTI<5>'
 '@S9S_MB_2U_LIB.S9S_MB_2U(SCH_1):TP_TRC_CPU1_PTI'<5>:
 C_SIGNAL='@s9s_mb_2u_lib.s9s_mb_2u(sch_1):tp_trc_cpu1_pti(5)';
NODE_NAME     U1 BV30
 '@S9S_MB_2U_LIB.S9S_MB_2U(SCH_1):PAGE50_I23@PURE_QUANTA.SOCKET4677_AZIF0045P001C01CS(CHIPS)':
 'PTI_DIE005': CDS_PINID='PTI_DIE005';
NET_NAME
'TP_TRC_CPU1_PTI<6>'
 '@S9S_MB_2U_LIB.S9S_MB_2U(SCH_1):TP_TRC_CPU1_PTI'<6>:
 C_SIGNAL='@s9s_mb_2u_lib.s9s_mb_2u(sch_1):tp_trc_cpu1_pti(6)';
NODE_NAME     U1 CA27
 '@S9S_MB_2U_LIB.S9S_MB_2U(SCH_1):PAGE50_I23@PURE_QUANTA.SOCKET4677_AZIF0045P001C01CS(CHIPS)':
 'PTI_DIE006': CDS_PINID='PTI_DIE006';
NET_NAME
'TP_TRC_CPU1_PTI<7>'
 '@S9S_MB_2U_LIB.S9S_MB_2U(SCH_1):TP_TRC_CPU1_PTI'<7>:
 C_SIGNAL='@s9s_mb_2u_lib.s9s_mb_2u(sch_1):tp_trc_cpu1_pti(7)';
NODE_NAME     U1 BV28
 '@S9S_MB_2U_LIB.S9S_MB_2U(SCH_1):PAGE50_I23@PURE_QUANTA.SOCKET4677_AZIF0045P001C01CS(CHIPS)':
 'PTI_DIE007': CDS_PINID='PTI_DIE007';
NET_NAME
'TP_TRC_CPU1_PTI<8>'
 '@S9S_MB_2U_LIB.S9S_MB_2U(SCH_1):TP_TRC_CPU1_PTI'<8>:
 C_SIGNAL='@s9s_mb_2u_lib.s9s_mb_2u(sch_1):tp_trc_cpu1_pti(8)';
NODE_NAME     U1 BU27
 '@S9S_MB_2U_LIB.S9S_MB_2U(SCH_1):PAGE50_I23@PURE_QUANTA.SOCKET4677_AZIF0045P001C01CS(CHIPS)':
 'PTI_DIE008': CDS_PINID='PTI_DIE008';
NET_NAME
'TP_TRC_CPU1_PTI<9>'
 '@S9S_MB_2U_LIB.S9S_MB_2U(SCH_1):TP_TRC_CPU1_PTI'<9>:
 C_SIGNAL='@s9s_mb_2u_lib.s9s_mb_2u(sch_1):tp_trc_cpu1_pti(9)';
NODE_NAME     U1 BT28
 '@S9S_MB_2U_LIB.S9S_MB_2U(SCH_1):PAGE50_I23@PURE_QUANTA.SOCKET4677_AZIF0045P001C01CS(CHIPS)':
 'PTI_DIE009': CDS_PINID='PTI_DIE009';
NET_NAME
'TP_USB2_10_DN'
 '@S9S_MB_2U_LIB.S9S_MB_2U(SCH_1):TP_USB2_10_DN':
 C_SIGNAL='@s9s_mb_2u_lib.s9s_mb_2u(sch_1):tp_usb2_10_dn';
NODE_NAME     U4 AY43
 '@S9S_MB_2U_LIB.S9S_MB_2U(SCH_1):PAGE172_I11@PURE_QUANTA.EMMITSBURG_REV0P9(CHIPS)':
 'USB2N_10': CDS_PINID='USB2N_10';
NET_NAME
'TP_USB2_10_DP'
 '@S9S_MB_2U_LIB.S9S_MB_2U(SCH_1):TP_USB2_10_DP':
 C_SIGNAL='@s9s_mb_2u_lib.s9s_mb_2u(sch_1):tp_usb2_10_dp';
NODE_NAME     U4 AY41
 '@S9S_MB_2U_LIB.S9S_MB_2U(SCH_1):PAGE172_I11@PURE_QUANTA.EMMITSBURG_REV0P9(CHIPS)':
 'USB2P_10': CDS_PINID='USB2P_10';
NET_NAME
'TP_USB2_11_DN'
 '@S9S_MB_2U_LIB.S9S_MB_2U(SCH_1):TP_USB2_11_DN':
 C_SIGNAL='@s9s_mb_2u_lib.s9s_mb_2u(sch_1):tp_usb2_11_dn';
NODE_NAME     U4 AH42
 '@S9S_MB_2U_LIB.S9S_MB_2U(SCH_1):PAGE172_I11@PURE_QUANTA.EMMITSBURG_REV0P9(CHIPS)':
 'USB2N_11': CDS_PINID='USB2N_11';
NET_NAME
'TP_USB2_11_DP'
 '@S9S_MB_2U_LIB.S9S_MB_2U(SCH_1):TP_USB2_11_DP':
 C_SIGNAL='@s9s_mb_2u_lib.s9s_mb_2u(sch_1):tp_usb2_11_dp';
NODE_NAME     U4 AH40
 '@S9S_MB_2U_LIB.S9S_MB_2U(SCH_1):PAGE172_I11@PURE_QUANTA.EMMITSBURG_REV0P9(CHIPS)':
 'USB2P_11': CDS_PINID='USB2P_11';
NET_NAME
'TP_USB2_12_DN'
 '@S9S_MB_2U_LIB.S9S_MB_2U(SCH_1):TP_USB2_12_DN':
 C_SIGNAL='@s9s_mb_2u_lib.s9s_mb_2u(sch_1):tp_usb2_12_dn';
NODE_NAME     U4 BA42
 '@S9S_MB_2U_LIB.S9S_MB_2U(SCH_1):PAGE172_I11@PURE_QUANTA.EMMITSBURG_REV0P9(CHIPS)':
 'USB2N_12': CDS_PINID='USB2N_12';
NET_NAME
'TP_USB2_12_DP'
 '@S9S_MB_2U_LIB.S9S_MB_2U(SCH_1):TP_USB2_12_DP':
 C_SIGNAL='@s9s_mb_2u_lib.s9s_mb_2u(sch_1):tp_usb2_12_dp';
NODE_NAME     U4 BA40
 '@S9S_MB_2U_LIB.S9S_MB_2U(SCH_1):PAGE172_I11@PURE_QUANTA.EMMITSBURG_REV0P9(CHIPS)':
 'USB2P_12': CDS_PINID='USB2P_12';
NET_NAME
'TP_USB2_13_DN'
 '@S9S_MB_2U_LIB.S9S_MB_2U(SCH_1):TP_USB2_13_DN':
 C_SIGNAL='@s9s_mb_2u_lib.s9s_mb_2u(sch_1):tp_usb2_13_dn';
NODE_NAME     U4 AG43
 '@S9S_MB_2U_LIB.S9S_MB_2U(SCH_1):PAGE172_I11@PURE_QUANTA.EMMITSBURG_REV0P9(CHIPS)':
 'USB2N_13': CDS_PINID='USB2N_13';
NET_NAME
'TP_USB2_13_DP'
 '@S9S_MB_2U_LIB.S9S_MB_2U(SCH_1):TP_USB2_13_DP':
 C_SIGNAL='@s9s_mb_2u_lib.s9s_mb_2u(sch_1):tp_usb2_13_dp';
NODE_NAME     U4 AG41
 '@S9S_MB_2U_LIB.S9S_MB_2U(SCH_1):PAGE172_I11@PURE_QUANTA.EMMITSBURG_REV0P9(CHIPS)':
 'USB2P_13': CDS_PINID='USB2P_13';
NET_NAME
'TP_USB2_1_DN'
 '@S9S_MB_2U_LIB.S9S_MB_2U(SCH_1):TP_USB2_1_DN':
 C_SIGNAL='@s9s_mb_2u_lib.s9s_mb_2u(sch_1):tp_usb2_1_dn';
NODE_NAME     U4 AP43
 '@S9S_MB_2U_LIB.S9S_MB_2U(SCH_1):PAGE172_I11@PURE_QUANTA.EMMITSBURG_REV0P9(CHIPS)':
 'USB2N_1': CDS_PINID='USB2N_1';
NET_NAME
'TP_USB2_1_DP'
 '@S9S_MB_2U_LIB.S9S_MB_2U(SCH_1):TP_USB2_1_DP':
 C_SIGNAL='@s9s_mb_2u_lib.s9s_mb_2u(sch_1):tp_usb2_1_dp';
NODE_NAME     U4 AP41
 '@S9S_MB_2U_LIB.S9S_MB_2U(SCH_1):PAGE172_I11@PURE_QUANTA.EMMITSBURG_REV0P9(CHIPS)':
 'USB2P_1': CDS_PINID='USB2P_1';
NET_NAME
'TP_USB2_2_DN'
 '@S9S_MB_2U_LIB.S9S_MB_2U(SCH_1):TP_USB2_2_DN':
 C_SIGNAL='@s9s_mb_2u_lib.s9s_mb_2u(sch_1):tp_usb2_2_dn';
NODE_NAME     U4 AT43
 '@S9S_MB_2U_LIB.S9S_MB_2U(SCH_1):PAGE172_I11@PURE_QUANTA.EMMITSBURG_REV0P9(CHIPS)':
 'USB2N_2': CDS_PINID='USB2N_2';
NET_NAME
'TP_USB2_2_DP'
 '@S9S_MB_2U_LIB.S9S_MB_2U(SCH_1):TP_USB2_2_DP':
 C_SIGNAL='@s9s_mb_2u_lib.s9s_mb_2u(sch_1):tp_usb2_2_dp';
NODE_NAME     U4 AT41
 '@S9S_MB_2U_LIB.S9S_MB_2U(SCH_1):PAGE172_I11@PURE_QUANTA.EMMITSBURG_REV0P9(CHIPS)':
 'USB2P_2': CDS_PINID='USB2P_2';
NET_NAME
'TP_USB2_4_DN'
 '@S9S_MB_2U_LIB.S9S_MB_2U(SCH_1):TP_USB2_4_DN':
 C_SIGNAL='@s9s_mb_2u_lib.s9s_mb_2u(sch_1):tp_usb2_4_dn';
NODE_NAME     U4 AU42
 '@S9S_MB_2U_LIB.S9S_MB_2U(SCH_1):PAGE172_I11@PURE_QUANTA.EMMITSBURG_REV0P9(CHIPS)':
 'USB2N_4': CDS_PINID='USB2N_4';
NET_NAME
'TP_USB2_4_DP'
 '@S9S_MB_2U_LIB.S9S_MB_2U(SCH_1):TP_USB2_4_DP':
 C_SIGNAL='@s9s_mb_2u_lib.s9s_mb_2u(sch_1):tp_usb2_4_dp';
NODE_NAME     U4 AU40
 '@S9S_MB_2U_LIB.S9S_MB_2U(SCH_1):PAGE172_I11@PURE_QUANTA.EMMITSBURG_REV0P9(CHIPS)':
 'USB2P_4': CDS_PINID='USB2P_4';
NET_NAME
'TP_USB2_6_DN'
 '@S9S_MB_2U_LIB.S9S_MB_2U(SCH_1):TP_USB2_6_DN':
 C_SIGNAL='@s9s_mb_2u_lib.s9s_mb_2u(sch_1):tp_usb2_6_dn';
NODE_NAME     U4 AV43
 '@S9S_MB_2U_LIB.S9S_MB_2U(SCH_1):PAGE172_I11@PURE_QUANTA.EMMITSBURG_REV0P9(CHIPS)':
 'USB2N_6': CDS_PINID='USB2N_6';
NET_NAME
'TP_USB2_6_DP'
 '@S9S_MB_2U_LIB.S9S_MB_2U(SCH_1):TP_USB2_6_DP':
 C_SIGNAL='@s9s_mb_2u_lib.s9s_mb_2u(sch_1):tp_usb2_6_dp';
NODE_NAME     U4 AV41
 '@S9S_MB_2U_LIB.S9S_MB_2U(SCH_1):PAGE172_I11@PURE_QUANTA.EMMITSBURG_REV0P9(CHIPS)':
 'USB2P_6': CDS_PINID='USB2P_6';
NET_NAME
'TP_USB2_9_DN'
 '@S9S_MB_2U_LIB.S9S_MB_2U(SCH_1):TP_USB2_9_DN':
 C_SIGNAL='@s9s_mb_2u_lib.s9s_mb_2u(sch_1):tp_usb2_9_dn';
NODE_NAME     U4 AJ43
 '@S9S_MB_2U_LIB.S9S_MB_2U(SCH_1):PAGE172_I11@PURE_QUANTA.EMMITSBURG_REV0P9(CHIPS)':
 'USB2N_9': CDS_PINID='USB2N_9';
NET_NAME
'TP_USB2_9_DP'
 '@S9S_MB_2U_LIB.S9S_MB_2U(SCH_1):TP_USB2_9_DP':
 C_SIGNAL='@s9s_mb_2u_lib.s9s_mb_2u(sch_1):tp_usb2_9_dp';
NODE_NAME     U4 AJ41
 '@S9S_MB_2U_LIB.S9S_MB_2U(SCH_1):PAGE172_I11@PURE_QUANTA.EMMITSBURG_REV0P9(CHIPS)':
 'USB2P_9': CDS_PINID='USB2P_9';
NET_NAME
'TP_USB2_CD'
 '@S9S_MB_2U_LIB.S9S_MB_2U(SCH_1):TP_USB2_CD':
 C_SIGNAL='@s9s_mb_2u_lib.s9s_mb_2u(sch_1):tp_usb2_cd';
NODE_NAME     U5201 4
 '@S9S_MB_2U_LIB.S9S_MB_2U(SCH_1):PAGE155_I84@PURE_QUANTA.TUSB211IRWBR(CHIPS)':
 'CD': CDS_PINID='CD';
NET_NAME
'TP_USB2_ENA_HS'
 '@S9S_MB_2U_LIB.S9S_MB_2U(SCH_1):TP_USB2_ENA_HS':
 C_SIGNAL='@s9s_mb_2u_lib.s9s_mb_2u(sch_1):tp_usb2_ena_hs';
NODE_NAME     U5201 9
 '@S9S_MB_2U_LIB.S9S_MB_2U(SCH_1):PAGE155_I84@PURE_QUANTA.TUSB211IRWBR(CHIPS)':
 'ENA_HS': CDS_PINID='ENA_HS';
NET_NAME
'TP_USB2_TEST'
 '@S9S_MB_2U_LIB.S9S_MB_2U(SCH_1):TP_USB2_TEST':
 C_SIGNAL='@s9s_mb_2u_lib.s9s_mb_2u(sch_1):tp_usb2_test';
NODE_NAME     U5201 3
 '@S9S_MB_2U_LIB.S9S_MB_2U(SCH_1):PAGE155_I84@PURE_QUANTA.TUSB211IRWBR(CHIPS)':
 'TEST': CDS_PINID='TEST';
NET_NAME
'TP_USB_HUB_2_CD'
 '@S9S_MB_2U_LIB.S9S_MB_2U(SCH_1):TP_USB_HUB_2_CD':
 C_SIGNAL='@s9s_mb_2u_lib.s9s_mb_2u(sch_1):tp_usb_hub_2_cd';
NODE_NAME     U312 4
 '@S9S_MB_2U_LIB.S9S_MB_2U(SCH_1):PAGE194_I20@PURE_QUANTA.TUSB211IRWBR(CHIPS)':
 'CD': CDS_PINID='CD';
NET_NAME
'TP_USB_HUB_2_ENA_HS'
 '@S9S_MB_2U_LIB.S9S_MB_2U(SCH_1):TP_USB_HUB_2_ENA_HS':
 C_SIGNAL='@s9s_mb_2u_lib.s9s_mb_2u(sch_1):tp_usb_hub_2_ena_hs';
NODE_NAME     U312 9
 '@S9S_MB_2U_LIB.S9S_MB_2U(SCH_1):PAGE194_I20@PURE_QUANTA.TUSB211IRWBR(CHIPS)':
 'ENA_HS': CDS_PINID='ENA_HS';
NET_NAME
'TP_USB_HUB_2_TEST'
 '@S9S_MB_2U_LIB.S9S_MB_2U(SCH_1):TP_USB_HUB_2_TEST':
 C_SIGNAL='@s9s_mb_2u_lib.s9s_mb_2u(sch_1):tp_usb_hub_2_test';
NODE_NAME     U312 3
 '@S9S_MB_2U_LIB.S9S_MB_2U(SCH_1):PAGE194_I20@PURE_QUANTA.TUSB211IRWBR(CHIPS)':
 'TEST': CDS_PINID='TEST';
NET_NAME
'U205_VDD'
 '@S9S_MB_2U_LIB.S9S_MB_2U(SCH_1):U205_VDD':
 C_SIGNAL='@s9s_mb_2u_lib.s9s_mb_2u(sch_1):u205_vdd';
NODE_NAME     U205 5
 '@S9S_MB_2U_LIB.S9S_MB_2U(SCH_1):PAGE326_I5@PURE_QUANTA.TPS3700DDCR(CHIPS)':
 'VDD': CDS_PINID='VDD';
NODE_NAME     C1562 1
 '@S9S_MB_2U_LIB.S9S_MB_2U(SCH_1):PAGE326_I89@PURE_QUANTA.Q_CAP(CHIPS)':
 'A': CDS_PINID='A';
NODE_NAME     C2392 1
 '@S9S_MB_2U_LIB.S9S_MB_2U(SCH_1):PAGE326_I95@PURE_QUANTA.Q_CAP(CHIPS)':
 'A': CDS_PINID='A';
NODE_NAME     R4804 2
 '@S9S_MB_2U_LIB.S9S_MB_2U(SCH_1):PAGE326_I97@PURE_QUANTA.Q_RES(CHIPS)':
 'B': CDS_PINID='B';
NET_NAME
'U206_VDD'
 '@S9S_MB_2U_LIB.S9S_MB_2U(SCH_1):U206_VDD':
 C_SIGNAL='@s9s_mb_2u_lib.s9s_mb_2u(sch_1):u206_vdd';
NODE_NAME     C1561 1
 '@S9S_MB_2U_LIB.S9S_MB_2U(SCH_1):PAGE326_I90@PURE_QUANTA.Q_CAP(CHIPS)':
 'A': CDS_PINID='A';
NODE_NAME     C2394 1
 '@S9S_MB_2U_LIB.S9S_MB_2U(SCH_1):PAGE326_I93@PURE_QUANTA.Q_CAP(CHIPS)':
 'A': CDS_PINID='A';
NODE_NAME     R4806 2
 '@S9S_MB_2U_LIB.S9S_MB_2U(SCH_1):PAGE326_I98@PURE_QUANTA.Q_RES(CHIPS)':
 'B': CDS_PINID='B';
NODE_NAME     U206 5
 '@S9S_MB_2U_LIB.S9S_MB_2U(SCH_1):PAGE326_I102@PURE_QUANTA.LT6700CS61TRPBF(CHIPS)':
 'VS': CDS_PINID='VS';
NET_NAME
'U270_0_ADD0'
 '@S9S_MB_2U_LIB.S9S_MB_2U(SCH_1):U270_0_ADD0':
 C_SIGNAL='@s9s_mb_2u_lib.s9s_mb_2u(sch_1):u270_0_add0';
NODE_NAME     R4207 1
 '@S9S_MB_2U_LIB.S9S_MB_2U(SCH_1):PAGE161_I85@PURE_QUANTA.Q_RES(CHIPS)':
 'A': CDS_PINID='A';
NODE_NAME     R4206 2
 '@S9S_MB_2U_LIB.S9S_MB_2U(SCH_1):PAGE161_I86@PURE_QUANTA.Q_RES(CHIPS)':
 'B': CDS_PINID='B';
NODE_NAME     U270 7
 '@S9S_MB_2U_LIB.S9S_MB_2U(SCH_1):PAGE161_I164@PURE_QUANTA.LM75BD(CHIPS)':
 'A0': CDS_PINID='A0';
NET_NAME
'U270_0_ADD1'
 '@S9S_MB_2U_LIB.S9S_MB_2U(SCH_1):U270_0_ADD1':
 C_SIGNAL='@s9s_mb_2u_lib.s9s_mb_2u(sch_1):u270_0_add1';
NODE_NAME     R4199 1
 '@S9S_MB_2U_LIB.S9S_MB_2U(SCH_1):PAGE161_I81@PURE_QUANTA.Q_RES(CHIPS)':
 'A': CDS_PINID='A';
NODE_NAME     R4198 2
 '@S9S_MB_2U_LIB.S9S_MB_2U(SCH_1):PAGE161_I82@PURE_QUANTA.Q_RES(CHIPS)':
 'B': CDS_PINID='B';
NODE_NAME     U270 6
 '@S9S_MB_2U_LIB.S9S_MB_2U(SCH_1):PAGE161_I164@PURE_QUANTA.LM75BD(CHIPS)':
 'A1': CDS_PINID='A1';
NET_NAME
'U270_0_ADD2'
 '@S9S_MB_2U_LIB.S9S_MB_2U(SCH_1):U270_0_ADD2':
 C_SIGNAL='@s9s_mb_2u_lib.s9s_mb_2u(sch_1):u270_0_add2';
NODE_NAME     R4191 1
 '@S9S_MB_2U_LIB.S9S_MB_2U(SCH_1):PAGE161_I89@PURE_QUANTA.Q_RES(CHIPS)':
 'A': CDS_PINID='A';
NODE_NAME     R4190 2
 '@S9S_MB_2U_LIB.S9S_MB_2U(SCH_1):PAGE161_I91@PURE_QUANTA.Q_RES(CHIPS)':
 'B': CDS_PINID='B';
NODE_NAME     U270 5
 '@S9S_MB_2U_LIB.S9S_MB_2U(SCH_1):PAGE161_I164@PURE_QUANTA.LM75BD(CHIPS)':
 'A2': CDS_PINID='A2';
NET_NAME
'U271_1_ADD0'
 '@S9S_MB_2U_LIB.S9S_MB_2U(SCH_1):U271_1_ADD0':
 C_SIGNAL='@s9s_mb_2u_lib.s9s_mb_2u(sch_1):u271_1_add0';
NODE_NAME     R4204 2
 '@S9S_MB_2U_LIB.S9S_MB_2U(SCH_1):PAGE161_I94@PURE_QUANTA.Q_RES(CHIPS)':
 'B': CDS_PINID='B';
NODE_NAME     R4205 1
 '@S9S_MB_2U_LIB.S9S_MB_2U(SCH_1):PAGE161_I96@PURE_QUANTA.Q_RES(CHIPS)':
 'A': CDS_PINID='A';
NODE_NAME     U271 7
 '@S9S_MB_2U_LIB.S9S_MB_2U(SCH_1):PAGE161_I165@PURE_QUANTA.LM75BD(CHIPS)':
 'A0': CDS_PINID='A0';
NET_NAME
'U271_1_ADD1'
 '@S9S_MB_2U_LIB.S9S_MB_2U(SCH_1):U271_1_ADD1':
 C_SIGNAL='@s9s_mb_2u_lib.s9s_mb_2u(sch_1):u271_1_add1';
NODE_NAME     R4196 2
 '@S9S_MB_2U_LIB.S9S_MB_2U(SCH_1):PAGE161_I95@PURE_QUANTA.Q_RES(CHIPS)':
 'B': CDS_PINID='B';
NODE_NAME     R4197 1
 '@S9S_MB_2U_LIB.S9S_MB_2U(SCH_1):PAGE161_I98@PURE_QUANTA.Q_RES(CHIPS)':
 'A': CDS_PINID='A';
NODE_NAME     U271 6
 '@S9S_MB_2U_LIB.S9S_MB_2U(SCH_1):PAGE161_I165@PURE_QUANTA.LM75BD(CHIPS)':
 'A1': CDS_PINID='A1';
NET_NAME
'U271_1_ADD2'
 '@S9S_MB_2U_LIB.S9S_MB_2U(SCH_1):U271_1_ADD2':
 C_SIGNAL='@s9s_mb_2u_lib.s9s_mb_2u(sch_1):u271_1_add2';
NODE_NAME     R4188 2
 '@S9S_MB_2U_LIB.S9S_MB_2U(SCH_1):PAGE161_I101@PURE_QUANTA.Q_RES(CHIPS)':
 'B': CDS_PINID='B';
NODE_NAME     R4189 1
 '@S9S_MB_2U_LIB.S9S_MB_2U(SCH_1):PAGE161_I102@PURE_QUANTA.Q_RES(CHIPS)':
 'A': CDS_PINID='A';
NODE_NAME     U271 5
 '@S9S_MB_2U_LIB.S9S_MB_2U(SCH_1):PAGE161_I165@PURE_QUANTA.LM75BD(CHIPS)':
 'A2': CDS_PINID='A2';
NET_NAME
'U272_2_ADD0'
 '@S9S_MB_2U_LIB.S9S_MB_2U(SCH_1):U272_2_ADD0':
 C_SIGNAL='@s9s_mb_2u_lib.s9s_mb_2u(sch_1):u272_2_add0';
NODE_NAME     R4203 1
 '@S9S_MB_2U_LIB.S9S_MB_2U(SCH_1):PAGE161_I127@PURE_QUANTA.Q_RES(CHIPS)':
 'A': CDS_PINID='A';
NODE_NAME     R4202 2
 '@S9S_MB_2U_LIB.S9S_MB_2U(SCH_1):PAGE161_I129@PURE_QUANTA.Q_RES(CHIPS)':
 'B': CDS_PINID='B';
NODE_NAME     U272 7
 '@S9S_MB_2U_LIB.S9S_MB_2U(SCH_1):PAGE161_I166@PURE_QUANTA.LM75BD(CHIPS)':
 'A0': CDS_PINID='A0';
NET_NAME
'U272_2_ADD1'
 '@S9S_MB_2U_LIB.S9S_MB_2U(SCH_1):U272_2_ADD1':
 C_SIGNAL='@s9s_mb_2u_lib.s9s_mb_2u(sch_1):u272_2_add1';
NODE_NAME     R4195 1
 '@S9S_MB_2U_LIB.S9S_MB_2U(SCH_1):PAGE161_I125@PURE_QUANTA.Q_RES(CHIPS)':
 'A': CDS_PINID='A';
NODE_NAME     R4194 2
 '@S9S_MB_2U_LIB.S9S_MB_2U(SCH_1):PAGE161_I128@PURE_QUANTA.Q_RES(CHIPS)':
 'B': CDS_PINID='B';
NODE_NAME     U272 6
 '@S9S_MB_2U_LIB.S9S_MB_2U(SCH_1):PAGE161_I166@PURE_QUANTA.LM75BD(CHIPS)':
 'A1': CDS_PINID='A1';
NET_NAME
'U272_2_ADD2'
 '@S9S_MB_2U_LIB.S9S_MB_2U(SCH_1):U272_2_ADD2':
 C_SIGNAL='@s9s_mb_2u_lib.s9s_mb_2u(sch_1):u272_2_add2';
NODE_NAME     R4187 1
 '@S9S_MB_2U_LIB.S9S_MB_2U(SCH_1):PAGE161_I121@PURE_QUANTA.Q_RES(CHIPS)':
 'A': CDS_PINID='A';
NODE_NAME     R4186 2
 '@S9S_MB_2U_LIB.S9S_MB_2U(SCH_1):PAGE161_I122@PURE_QUANTA.Q_RES(CHIPS)':
 'B': CDS_PINID='B';
NODE_NAME     U272 5
 '@S9S_MB_2U_LIB.S9S_MB_2U(SCH_1):PAGE161_I166@PURE_QUANTA.LM75BD(CHIPS)':
 'A2': CDS_PINID='A2';
NET_NAME
'U273_3_ADD0'
 '@S9S_MB_2U_LIB.S9S_MB_2U(SCH_1):U273_3_ADD0':
 C_SIGNAL='@s9s_mb_2u_lib.s9s_mb_2u(sch_1):u273_3_add0';
NODE_NAME     R4201 1
 '@S9S_MB_2U_LIB.S9S_MB_2U(SCH_1):PAGE161_I147@PURE_QUANTA.Q_RES(CHIPS)':
 'A': CDS_PINID='A';
NODE_NAME     R4200 2
 '@S9S_MB_2U_LIB.S9S_MB_2U(SCH_1):PAGE161_I149@PURE_QUANTA.Q_RES(CHIPS)':
 'B': CDS_PINID='B';
NODE_NAME     U273 7
 '@S9S_MB_2U_LIB.S9S_MB_2U(SCH_1):PAGE161_I167@PURE_QUANTA.LM75BD(CHIPS)':
 'A0': CDS_PINID='A0';
NET_NAME
'U273_3_ADD1'
 '@S9S_MB_2U_LIB.S9S_MB_2U(SCH_1):U273_3_ADD1':
 C_SIGNAL='@s9s_mb_2u_lib.s9s_mb_2u(sch_1):u273_3_add1';
NODE_NAME     R4193 1
 '@S9S_MB_2U_LIB.S9S_MB_2U(SCH_1):PAGE161_I145@PURE_QUANTA.Q_RES(CHIPS)':
 'A': CDS_PINID='A';
NODE_NAME     R4192 2
 '@S9S_MB_2U_LIB.S9S_MB_2U(SCH_1):PAGE161_I148@PURE_QUANTA.Q_RES(CHIPS)':
 'B': CDS_PINID='B';
NODE_NAME     U273 6
 '@S9S_MB_2U_LIB.S9S_MB_2U(SCH_1):PAGE161_I167@PURE_QUANTA.LM75BD(CHIPS)':
 'A1': CDS_PINID='A1';
NET_NAME
'U273_3_ADD2'
 '@S9S_MB_2U_LIB.S9S_MB_2U(SCH_1):U273_3_ADD2':
 C_SIGNAL='@s9s_mb_2u_lib.s9s_mb_2u(sch_1):u273_3_add2';
NODE_NAME     R4185 1
 '@S9S_MB_2U_LIB.S9S_MB_2U(SCH_1):PAGE161_I141@PURE_QUANTA.Q_RES(CHIPS)':
 'A': CDS_PINID='A';
NODE_NAME     R4184 2
 '@S9S_MB_2U_LIB.S9S_MB_2U(SCH_1):PAGE161_I142@PURE_QUANTA.Q_RES(CHIPS)':
 'B': CDS_PINID='B';
NODE_NAME     U273 5
 '@S9S_MB_2U_LIB.S9S_MB_2U(SCH_1):PAGE161_I167@PURE_QUANTA.LM75BD(CHIPS)':
 'A2': CDS_PINID='A2';
NET_NAME
'U369_VDD'
 '@S9S_MB_2U_LIB.S9S_MB_2U(SCH_1):U369_VDD':
 C_SIGNAL='@s9s_mb_2u_lib.s9s_mb_2u(sch_1):u369_vdd';
NODE_NAME     U369 5
 '@S9S_MB_2U_LIB.S9S_MB_2U(SCH_1):PAGE326_I30@PURE_QUANTA.TPS3700DDCR(CHIPS)':
 'VDD': CDS_PINID='VDD';
NODE_NAME     C4562 1
 '@S9S_MB_2U_LIB.S9S_MB_2U(SCH_1):PAGE326_I91@PURE_QUANTA.Q_CAP(CHIPS)':
 'A': CDS_PINID='A';
NODE_NAME     C2393 1
 '@S9S_MB_2U_LIB.S9S_MB_2U(SCH_1):PAGE326_I92@PURE_QUANTA.Q_CAP(CHIPS)':
 'A': CDS_PINID='A';
NODE_NAME     R4805 2
 '@S9S_MB_2U_LIB.S9S_MB_2U(SCH_1):PAGE326_I99@PURE_QUANTA.Q_RES(CHIPS)':
 'B': CDS_PINID='B';
NET_NAME
'UART_BMC_BIC_BUF_RX'
 '@S9S_MB_2U_LIB.S9S_MB_2U(SCH_1):UART_BMC_BIC_BUF_RX':
 C_SIGNAL='@s9s_mb_2u_lib.s9s_mb_2u(sch_1):uart_bmc_bic_buf_rx';
NODE_NAME     R3036 2
 '@S9S_MB_2U_LIB.S9S_MB_2U(SCH_1):PAGE140_I197@PURE_QUANTA.Q_RES(CHIPS)':
 'B': CDS_PINID='B';
NODE_NAME     J41 OB6
 '@S9S_MB_2U_LIB.S9S_MB_2U(SCH_1):PAGE227_I173@PURE_QUANTA.SCONN168_ME1016810202011(CHIPS)':
 'CLK': CDS_PINID='CLK';
NET_NAME
'UART_BMC_BIC_RX'
 '@S9S_MB_2U_LIB.S9S_MB_2U(SCH_1):UART_BMC_BIC_RX':
 C_SIGNAL='@s9s_mb_2u_lib.s9s_mb_2u(sch_1):uart_bmc_bic_rx';
NODE_NAME     J106 N6
 '@S9S_MB_2U_LIB.S9S_MB_2U(SCH_1):PAGE144_I68@PURE_QUANTA.CONN112_10137002101LF(CHIPS)':
 'N6': CDS_PINID='N6';
NODE_NAME     R3033 1
 '@S9S_MB_2U_LIB.S9S_MB_2U(SCH_1):PAGE140_I170@PURE_QUANTA.Q_RES(CHIPS)':
 'A': CDS_PINID='A';
NODE_NAME     R4515 2
 '@S9S_MB_2U_LIB.S9S_MB_2U(SCH_1):PAGE140_I200@PURE_QUANTA.Q_RES(CHIPS)':
 'B': CDS_PINID='B';
NET_NAME
'UART_BMC_BIC_R_BUF_RX'
 '@S9S_MB_2U_LIB.S9S_MB_2U(SCH_1):UART_BMC_BIC_R_BUF_RX':
 C_SIGNAL='@s9s_mb_2u_lib.s9s_mb_2u(sch_1):uart_bmc_bic_r_buf_rx';
NODE_NAME     U204 4
 '@S9S_MB_2U_LIB.S9S_MB_2U(SCH_1):PAGE140_I195@PURE_QUANTA.74LVC1G126SE7(CHIPS)':
 'Y': CDS_PINID='Y';
NODE_NAME     R3036 1
 '@S9S_MB_2U_LIB.S9S_MB_2U(SCH_1):PAGE140_I197@PURE_QUANTA.Q_RES(CHIPS)':
 'A': CDS_PINID='A';
NODE_NAME     R4173 2
 '@S9S_MB_2U_LIB.S9S_MB_2U(SCH_1):PAGE140_I202@PURE_QUANTA.Q_RES(CHIPS)':
 'B': CDS_PINID='B';
NET_NAME
'UART_BMC_BIC_R_RX'
 '@S9S_MB_2U_LIB.S9S_MB_2U(SCH_1):UART_BMC_BIC_R_RX':
 C_SIGNAL='@s9s_mb_2u_lib.s9s_mb_2u(sch_1):uart_bmc_bic_r_rx';
NODE_NAME     R3033 2
 '@S9S_MB_2U_LIB.S9S_MB_2U(SCH_1):PAGE140_I170@PURE_QUANTA.Q_RES(CHIPS)':
 'B': CDS_PINID='B';
NODE_NAME     U204 2
 '@S9S_MB_2U_LIB.S9S_MB_2U(SCH_1):PAGE140_I195@PURE_QUANTA.74LVC1G126SE7(CHIPS)':
 'A': CDS_PINID='A';
NET_NAME
'UART_BMC_BIC_TX'
 '@S9S_MB_2U_LIB.S9S_MB_2U(SCH_1):UART_BMC_BIC_TX':
 C_SIGNAL='@s9s_mb_2u_lib.s9s_mb_2u(sch_1):uart_bmc_bic_tx';
NODE_NAME     J106 N8
 '@S9S_MB_2U_LIB.S9S_MB_2U(SCH_1):PAGE144_I68@PURE_QUANTA.CONN112_10137002101LF(CHIPS)':
 'N8': CDS_PINID='N8';
NODE_NAME     J41 OB5
 '@S9S_MB_2U_LIB.S9S_MB_2U(SCH_1):PAGE227_I173@PURE_QUANTA.SCONN168_ME1016810202011(CHIPS)':
 'DATA_OUT': CDS_PINID='DATA_OUT';
NET_NAME
'UNNAMED_310_TPTDR4PFTS_I10_S1'
 '@S9S_MB_2U_LIB.S9S_MB_2U(SCH_1):UNNAMED_310_TPTDR4PFTS_I10_S1':
 C_SIGNAL='@s9s_mb_2u_lib.s9s_mb_2u(sch_1):unnamed_310_tptdr4pfts_i10_s1';
NODE_NAME     X36 4
 '@S9S_MB_2U_LIB.S9S_MB_2U(SCH_1):PAGE310_I8@PURE_QUANTA.TP_TDR_4P_FTS(CHIPS)':
 'S2': CDS_PINID='S2';
NODE_NAME     X42 1
 '@S9S_MB_2U_LIB.S9S_MB_2U(SCH_1):PAGE310_I10@PURE_QUANTA.TP_TDR_4P_FTS(CHIPS)':
 'S1': CDS_PINID='S1';
NET_NAME
'UNNAMED_310_TPTDR4PFTS_I10_S2'
 '@S9S_MB_2U_LIB.S9S_MB_2U(SCH_1):UNNAMED_310_TPTDR4PFTS_I10_S2':
 C_SIGNAL='@s9s_mb_2u_lib.s9s_mb_2u(sch_1):unnamed_310_tptdr4pfts_i10_s2';
NODE_NAME     X36 1
 '@S9S_MB_2U_LIB.S9S_MB_2U(SCH_1):PAGE310_I8@PURE_QUANTA.TP_TDR_4P_FTS(CHIPS)':
 'S1': CDS_PINID='S1';
NODE_NAME     X42 4
 '@S9S_MB_2U_LIB.S9S_MB_2U(SCH_1):PAGE310_I10@PURE_QUANTA.TP_TDR_4P_FTS(CHIPS)':
 'S2': CDS_PINID='S2';
NET_NAME
'UNNAMED_310_TPTDR4PFTS_I15_S1'
 '@S9S_MB_2U_LIB.S9S_MB_2U(SCH_1):UNNAMED_310_TPTDR4PFTS_I15_S1':
 C_SIGNAL='@s9s_mb_2u_lib.s9s_mb_2u(sch_1):unnamed_310_tptdr4pfts_i15_s1';
NODE_NAME     X41 1
 '@S9S_MB_2U_LIB.S9S_MB_2U(SCH_1):PAGE310_I15@PURE_QUANTA.TP_TDR_4P_FTS(CHIPS)':
 'S1': CDS_PINID='S1';
NODE_NAME     X35 4
 '@S9S_MB_2U_LIB.S9S_MB_2U(SCH_1):PAGE310_I16@PURE_QUANTA.TP_TDR_4P_FTS(CHIPS)':
 'S2': CDS_PINID='S2';
NET_NAME
'UNNAMED_310_TPTDR4PFTS_I15_S2'
 '@S9S_MB_2U_LIB.S9S_MB_2U(SCH_1):UNNAMED_310_TPTDR4PFTS_I15_S2':
 C_SIGNAL='@s9s_mb_2u_lib.s9s_mb_2u(sch_1):unnamed_310_tptdr4pfts_i15_s2';
NODE_NAME     X41 4
 '@S9S_MB_2U_LIB.S9S_MB_2U(SCH_1):PAGE310_I15@PURE_QUANTA.TP_TDR_4P_FTS(CHIPS)':
 'S2': CDS_PINID='S2';
NODE_NAME     X35 1
 '@S9S_MB_2U_LIB.S9S_MB_2U(SCH_1):PAGE310_I16@PURE_QUANTA.TP_TDR_4P_FTS(CHIPS)':
 'S1': CDS_PINID='S1';
NET_NAME
'UNNAMED_310_TPTDR4PFTS_I19_S1'
 '@S9S_MB_2U_LIB.S9S_MB_2U(SCH_1):UNNAMED_310_TPTDR4PFTS_I19_S1':
 C_SIGNAL='@s9s_mb_2u_lib.s9s_mb_2u(sch_1):unnamed_310_tptdr4pfts_i19_s1';
NODE_NAME     X34 1
 '@S9S_MB_2U_LIB.S9S_MB_2U(SCH_1):PAGE310_I19@PURE_QUANTA.TP_TDR_4P_FTS(CHIPS)':
 'S1': CDS_PINID='S1';
NODE_NAME     X40 4
 '@S9S_MB_2U_LIB.S9S_MB_2U(SCH_1):PAGE310_I21@PURE_QUANTA.TP_TDR_4P_FTS(CHIPS)':
 'S2': CDS_PINID='S2';
NET_NAME
'UNNAMED_310_TPTDR4PFTS_I19_S2'
 '@S9S_MB_2U_LIB.S9S_MB_2U(SCH_1):UNNAMED_310_TPTDR4PFTS_I19_S2':
 C_SIGNAL='@s9s_mb_2u_lib.s9s_mb_2u(sch_1):unnamed_310_tptdr4pfts_i19_s2';
NODE_NAME     X34 4
 '@S9S_MB_2U_LIB.S9S_MB_2U(SCH_1):PAGE310_I19@PURE_QUANTA.TP_TDR_4P_FTS(CHIPS)':
 'S2': CDS_PINID='S2';
NODE_NAME     X40 1
 '@S9S_MB_2U_LIB.S9S_MB_2U(SCH_1):PAGE310_I21@PURE_QUANTA.TP_TDR_4P_FTS(CHIPS)':
 'S1': CDS_PINID='S1';
NET_NAME
'UNNAMED_310_TPTDR4PFTS_I20_S1'
 '@S9S_MB_2U_LIB.S9S_MB_2U(SCH_1):UNNAMED_310_TPTDR4PFTS_I20_S1':
 C_SIGNAL='@s9s_mb_2u_lib.s9s_mb_2u(sch_1):unnamed_310_tptdr4pfts_i20_s1';
NODE_NAME     X33 1
 '@S9S_MB_2U_LIB.S9S_MB_2U(SCH_1):PAGE310_I20@PURE_QUANTA.TP_TDR_4P_FTS(CHIPS)':
 'S1': CDS_PINID='S1';
NODE_NAME     X39 4
 '@S9S_MB_2U_LIB.S9S_MB_2U(SCH_1):PAGE310_I22@PURE_QUANTA.TP_TDR_4P_FTS(CHIPS)':
 'S2': CDS_PINID='S2';
NET_NAME
'UNNAMED_310_TPTDR4PFTS_I20_S2'
 '@S9S_MB_2U_LIB.S9S_MB_2U(SCH_1):UNNAMED_310_TPTDR4PFTS_I20_S2':
 C_SIGNAL='@s9s_mb_2u_lib.s9s_mb_2u(sch_1):unnamed_310_tptdr4pfts_i20_s2';
NODE_NAME     X33 4
 '@S9S_MB_2U_LIB.S9S_MB_2U(SCH_1):PAGE310_I20@PURE_QUANTA.TP_TDR_4P_FTS(CHIPS)':
 'S2': CDS_PINID='S2';
NODE_NAME     X39 1
 '@S9S_MB_2U_LIB.S9S_MB_2U(SCH_1):PAGE310_I22@PURE_QUANTA.TP_TDR_4P_FTS(CHIPS)':
 'S1': CDS_PINID='S1';
NET_NAME
'UNNAMED_310_TPTDR4PFTS_I5_S1'
 '@S9S_MB_2U_LIB.S9S_MB_2U(SCH_1):UNNAMED_310_TPTDR4PFTS_I5_S1':
 C_SIGNAL='@s9s_mb_2u_lib.s9s_mb_2u(sch_1):unnamed_310_tptdr4pfts_i5_s1';
NODE_NAME     X38 1
 '@S9S_MB_2U_LIB.S9S_MB_2U(SCH_1):PAGE310_I5@PURE_QUANTA.TP_TDR_4P_FTS(CHIPS)':
 'S1': CDS_PINID='S1';
NODE_NAME     X44 4
 '@S9S_MB_2U_LIB.S9S_MB_2U(SCH_1):PAGE310_I6@PURE_QUANTA.TP_TDR_4P_FTS(CHIPS)':
 'S2': CDS_PINID='S2';
NET_NAME
'UNNAMED_310_TPTDR4PFTS_I5_S2'
 '@S9S_MB_2U_LIB.S9S_MB_2U(SCH_1):UNNAMED_310_TPTDR4PFTS_I5_S2':
 C_SIGNAL='@s9s_mb_2u_lib.s9s_mb_2u(sch_1):unnamed_310_tptdr4pfts_i5_s2';
NODE_NAME     X38 4
 '@S9S_MB_2U_LIB.S9S_MB_2U(SCH_1):PAGE310_I5@PURE_QUANTA.TP_TDR_4P_FTS(CHIPS)':
 'S2': CDS_PINID='S2';
NODE_NAME     X44 1
 '@S9S_MB_2U_LIB.S9S_MB_2U(SCH_1):PAGE310_I6@PURE_QUANTA.TP_TDR_4P_FTS(CHIPS)':
 'S1': CDS_PINID='S1';
NET_NAME
'UNNAMED_310_TPTDR4PFTS_I7_S1'
 '@S9S_MB_2U_LIB.S9S_MB_2U(SCH_1):UNNAMED_310_TPTDR4PFTS_I7_S1':
 C_SIGNAL='@s9s_mb_2u_lib.s9s_mb_2u(sch_1):unnamed_310_tptdr4pfts_i7_s1';
NODE_NAME     X37 1
 '@S9S_MB_2U_LIB.S9S_MB_2U(SCH_1):PAGE310_I7@PURE_QUANTA.TP_TDR_4P_FTS(CHIPS)':
 'S1': CDS_PINID='S1';
NODE_NAME     X43 4
 '@S9S_MB_2U_LIB.S9S_MB_2U(SCH_1):PAGE310_I9@PURE_QUANTA.TP_TDR_4P_FTS(CHIPS)':
 'S2': CDS_PINID='S2';
NET_NAME
'UNNAMED_310_TPTDR4PFTS_I7_S2'
 '@S9S_MB_2U_LIB.S9S_MB_2U(SCH_1):UNNAMED_310_TPTDR4PFTS_I7_S2':
 C_SIGNAL='@s9s_mb_2u_lib.s9s_mb_2u(sch_1):unnamed_310_tptdr4pfts_i7_s2';
NODE_NAME     X37 4
 '@S9S_MB_2U_LIB.S9S_MB_2U(SCH_1):PAGE310_I7@PURE_QUANTA.TP_TDR_4P_FTS(CHIPS)':
 'S2': CDS_PINID='S2';
NODE_NAME     X43 1
 '@S9S_MB_2U_LIB.S9S_MB_2U(SCH_1):PAGE310_I9@PURE_QUANTA.TP_TDR_4P_FTS(CHIPS)':
 'S1': CDS_PINID='S1';
NET_NAME
'UPI_CPU0_CPU1_P0P1_DN<0>'
 '@S9S_MB_2U_LIB.S9S_MB_2U(SCH_1):UPI_CPU0_CPU1_P0P1_DN'<0>:
 C_SIGNAL='@s9s_mb_2u_lib.s9s_mb_2u(sch_1):upi_cpu0_cpu1_p0p1_dn(0)';
NODE_NAME     U2 K4
 '@S9S_MB_2U_LIB.S9S_MB_2U(SCH_1):PAGE32_I70@PURE_QUANTA.SOCKET4677_AZIF0045P001C01CS(CHIPS)':
 'UPI0_TX_DN0': CDS_PINID='UPI0_TX_DN0';
NODE_NAME     U1 EH2
 '@S9S_MB_2U_LIB.S9S_MB_2U(SCH_1):PAGE64_I21@PURE_QUANTA.SOCKET4677_AZIF0045P001C01CS(CHIPS)':
 'UPI1_RX_DN0': CDS_PINID='UPI1_RX_DN0';
NET_NAME
'UPI_CPU0_CPU1_P0P1_DN<10>'
 '@S9S_MB_2U_LIB.S9S_MB_2U(SCH_1):UPI_CPU0_CPU1_P0P1_DN'<10>:
 C_SIGNAL='@s9s_mb_2u_lib.s9s_mb_2u(sch_1):upi_cpu0_cpu1_p0p1_dn(10)';
NODE_NAME     U2 AK2
 '@S9S_MB_2U_LIB.S9S_MB_2U(SCH_1):PAGE32_I70@PURE_QUANTA.SOCKET4677_AZIF0045P001C01CS(CHIPS)':
 'UPI0_TX_DN10': CDS_PINID='UPI0_TX_DN10';
NODE_NAME     U1 DG3
 '@S9S_MB_2U_LIB.S9S_MB_2U(SCH_1):PAGE64_I21@PURE_QUANTA.SOCKET4677_AZIF0045P001C01CS(CHIPS)':
 'UPI1_RX_DN10': CDS_PINID='UPI1_RX_DN10';
NET_NAME
'UPI_CPU0_CPU1_P0P1_DN<11>'
 '@S9S_MB_2U_LIB.S9S_MB_2U(SCH_1):UPI_CPU0_CPU1_P0P1_DN'<11>:
 C_SIGNAL='@s9s_mb_2u_lib.s9s_mb_2u(sch_1):upi_cpu0_cpu1_p0p1_dn(11)';
NODE_NAME     U2 AM2
 '@S9S_MB_2U_LIB.S9S_MB_2U(SCH_1):PAGE32_I70@PURE_QUANTA.SOCKET4677_AZIF0045P001C01CS(CHIPS)':
 'UPI0_TX_DN11': CDS_PINID='UPI0_TX_DN11';
NODE_NAME     U1 DE1
 '@S9S_MB_2U_LIB.S9S_MB_2U(SCH_1):PAGE64_I21@PURE_QUANTA.SOCKET4677_AZIF0045P001C01CS(CHIPS)':
 'UPI1_RX_DN11': CDS_PINID='UPI1_RX_DN11';
NET_NAME
'UPI_CPU0_CPU1_P0P1_DN<12>'
 '@S9S_MB_2U_LIB.S9S_MB_2U(SCH_1):UPI_CPU0_CPU1_P0P1_DN'<12>:
 C_SIGNAL='@s9s_mb_2u_lib.s9s_mb_2u(sch_1):upi_cpu0_cpu1_p0p1_dn(12)';
NODE_NAME     U2 AN1
 '@S9S_MB_2U_LIB.S9S_MB_2U(SCH_1):PAGE32_I70@PURE_QUANTA.SOCKET4677_AZIF0045P001C01CS(CHIPS)':
 'UPI0_TX_DP12': CDS_PINID='UPI0_TX_DP12';
NODE_NAME     U1 DD2
 '@S9S_MB_2U_LIB.S9S_MB_2U(SCH_1):PAGE64_I21@PURE_QUANTA.SOCKET4677_AZIF0045P001C01CS(CHIPS)':
 'UPI1_RX_DN12': CDS_PINID='UPI1_RX_DN12';
NET_NAME
'UPI_CPU0_CPU1_P0P1_DN<13>'
 '@S9S_MB_2U_LIB.S9S_MB_2U(SCH_1):UPI_CPU0_CPU1_P0P1_DN'<13>:
 C_SIGNAL='@s9s_mb_2u_lib.s9s_mb_2u(sch_1):upi_cpu0_cpu1_p0p1_dn(13)';
NODE_NAME     U2 AR3
 '@S9S_MB_2U_LIB.S9S_MB_2U(SCH_1):PAGE32_I70@PURE_QUANTA.SOCKET4677_AZIF0045P001C01CS(CHIPS)':
 'UPI0_TX_DP13': CDS_PINID='UPI0_TX_DP13';
NODE_NAME     U1 DB2
 '@S9S_MB_2U_LIB.S9S_MB_2U(SCH_1):PAGE64_I21@PURE_QUANTA.SOCKET4677_AZIF0045P001C01CS(CHIPS)':
 'UPI1_RX_DN13': CDS_PINID='UPI1_RX_DN13';
NET_NAME
'UPI_CPU0_CPU1_P0P1_DN<14>'
 '@S9S_MB_2U_LIB.S9S_MB_2U(SCH_1):UPI_CPU0_CPU1_P0P1_DN'<14>:
 C_SIGNAL='@s9s_mb_2u_lib.s9s_mb_2u(sch_1):upi_cpu0_cpu1_p0p1_dn(14)';
NODE_NAME     U2 AU1
 '@S9S_MB_2U_LIB.S9S_MB_2U(SCH_1):PAGE32_I70@PURE_QUANTA.SOCKET4677_AZIF0045P001C01CS(CHIPS)':
 'UPI0_TX_DN14': CDS_PINID='UPI0_TX_DN14';
NODE_NAME     U1 CY2
 '@S9S_MB_2U_LIB.S9S_MB_2U(SCH_1):PAGE64_I21@PURE_QUANTA.SOCKET4677_AZIF0045P001C01CS(CHIPS)':
 'UPI1_RX_DN14': CDS_PINID='UPI1_RX_DN14';
NET_NAME
'UPI_CPU0_CPU1_P0P1_DN<15>'
 '@S9S_MB_2U_LIB.S9S_MB_2U(SCH_1):UPI_CPU0_CPU1_P0P1_DN'<15>:
 C_SIGNAL='@s9s_mb_2u_lib.s9s_mb_2u(sch_1):upi_cpu0_cpu1_p0p1_dn(15)';
NODE_NAME     U2 AW3
 '@S9S_MB_2U_LIB.S9S_MB_2U(SCH_1):PAGE32_I70@PURE_QUANTA.SOCKET4677_AZIF0045P001C01CS(CHIPS)':
 'UPI0_TX_DP15': CDS_PINID='UPI0_TX_DP15';
NODE_NAME     U1 CV2
 '@S9S_MB_2U_LIB.S9S_MB_2U(SCH_1):PAGE64_I21@PURE_QUANTA.SOCKET4677_AZIF0045P001C01CS(CHIPS)':
 'UPI1_RX_DN15': CDS_PINID='UPI1_RX_DN15';
NET_NAME
'UPI_CPU0_CPU1_P0P1_DN<16>'
 '@S9S_MB_2U_LIB.S9S_MB_2U(SCH_1):UPI_CPU0_CPU1_P0P1_DN'<16>:
 C_SIGNAL='@s9s_mb_2u_lib.s9s_mb_2u(sch_1):upi_cpu0_cpu1_p0p1_dn(16)';
NODE_NAME     U2 BB2
 '@S9S_MB_2U_LIB.S9S_MB_2U(SCH_1):PAGE32_I70@PURE_QUANTA.SOCKET4677_AZIF0045P001C01CS(CHIPS)':
 'UPI0_TX_DN16': CDS_PINID='UPI0_TX_DN16';
NODE_NAME     U1 CR3
 '@S9S_MB_2U_LIB.S9S_MB_2U(SCH_1):PAGE64_I21@PURE_QUANTA.SOCKET4677_AZIF0045P001C01CS(CHIPS)':
 'UPI1_RX_DN16': CDS_PINID='UPI1_RX_DN16';
NET_NAME
'UPI_CPU0_CPU1_P0P1_DN<17>'
 '@S9S_MB_2U_LIB.S9S_MB_2U(SCH_1):UPI_CPU0_CPU1_P0P1_DN'<17>:
 C_SIGNAL='@s9s_mb_2u_lib.s9s_mb_2u(sch_1):upi_cpu0_cpu1_p0p1_dn(17)';
NODE_NAME     U2 BD2
 '@S9S_MB_2U_LIB.S9S_MB_2U(SCH_1):PAGE32_I70@PURE_QUANTA.SOCKET4677_AZIF0045P001C01CS(CHIPS)':
 'UPI0_TX_DN17': CDS_PINID='UPI0_TX_DN17';
NODE_NAME     U1 CN1
 '@S9S_MB_2U_LIB.S9S_MB_2U(SCH_1):PAGE64_I21@PURE_QUANTA.SOCKET4677_AZIF0045P001C01CS(CHIPS)':
 'UPI1_RX_DN17': CDS_PINID='UPI1_RX_DN17';
NET_NAME
'UPI_CPU0_CPU1_P0P1_DN<18>'
 '@S9S_MB_2U_LIB.S9S_MB_2U(SCH_1):UPI_CPU0_CPU1_P0P1_DN'<18>:
 C_SIGNAL='@s9s_mb_2u_lib.s9s_mb_2u(sch_1):upi_cpu0_cpu1_p0p1_dn(18)';
NODE_NAME     U2 BF2
 '@S9S_MB_2U_LIB.S9S_MB_2U(SCH_1):PAGE32_I70@PURE_QUANTA.SOCKET4677_AZIF0045P001C01CS(CHIPS)':
 'UPI0_TX_DN18': CDS_PINID='UPI0_TX_DN18';
NODE_NAME     U1 CL3
 '@S9S_MB_2U_LIB.S9S_MB_2U(SCH_1):PAGE64_I21@PURE_QUANTA.SOCKET4677_AZIF0045P001C01CS(CHIPS)':
 'UPI1_RX_DN18': CDS_PINID='UPI1_RX_DN18';
NET_NAME
'UPI_CPU0_CPU1_P0P1_DN<19>'
 '@S9S_MB_2U_LIB.S9S_MB_2U(SCH_1):UPI_CPU0_CPU1_P0P1_DN'<19>:
 C_SIGNAL='@s9s_mb_2u_lib.s9s_mb_2u(sch_1):upi_cpu0_cpu1_p0p1_dn(19)';
NODE_NAME     U2 BH2
 '@S9S_MB_2U_LIB.S9S_MB_2U(SCH_1):PAGE32_I70@PURE_QUANTA.SOCKET4677_AZIF0045P001C01CS(CHIPS)':
 'UPI0_TX_DN19': CDS_PINID='UPI0_TX_DN19';
NODE_NAME     U1 CJ1
 '@S9S_MB_2U_LIB.S9S_MB_2U(SCH_1):PAGE64_I21@PURE_QUANTA.SOCKET4677_AZIF0045P001C01CS(CHIPS)':
 'UPI1_RX_DN19': CDS_PINID='UPI1_RX_DN19';
NET_NAME
'UPI_CPU0_CPU1_P0P1_DN<1>'
 '@S9S_MB_2U_LIB.S9S_MB_2U(SCH_1):UPI_CPU0_CPU1_P0P1_DN'<1>:
 C_SIGNAL='@s9s_mb_2u_lib.s9s_mb_2u(sch_1):upi_cpu0_cpu1_p0p1_dn(1)';
NODE_NAME     U2 M2
 '@S9S_MB_2U_LIB.S9S_MB_2U(SCH_1):PAGE32_I70@PURE_QUANTA.SOCKET4677_AZIF0045P001C01CS(CHIPS)':
 'UPI0_TX_DN1': CDS_PINID='UPI0_TX_DN1';
NODE_NAME     U1 EE3
 '@S9S_MB_2U_LIB.S9S_MB_2U(SCH_1):PAGE64_I21@PURE_QUANTA.SOCKET4677_AZIF0045P001C01CS(CHIPS)':
 'UPI1_RX_DN1': CDS_PINID='UPI1_RX_DN1';
NET_NAME
'UPI_CPU0_CPU1_P0P1_DN<20>'
 '@S9S_MB_2U_LIB.S9S_MB_2U(SCH_1):UPI_CPU0_CPU1_P0P1_DN'<20>:
 C_SIGNAL='@s9s_mb_2u_lib.s9s_mb_2u(sch_1):upi_cpu0_cpu1_p0p1_dn(20)';
NODE_NAME     U2 BJ1
 '@S9S_MB_2U_LIB.S9S_MB_2U(SCH_1):PAGE32_I70@PURE_QUANTA.SOCKET4677_AZIF0045P001C01CS(CHIPS)':
 'UPI0_TX_DP20': CDS_PINID='UPI0_TX_DP20';
NODE_NAME     U1 CH2
 '@S9S_MB_2U_LIB.S9S_MB_2U(SCH_1):PAGE64_I21@PURE_QUANTA.SOCKET4677_AZIF0045P001C01CS(CHIPS)':
 'UPI1_RX_DN20': CDS_PINID='UPI1_RX_DN20';
NET_NAME
'UPI_CPU0_CPU1_P0P1_DN<21>'
 '@S9S_MB_2U_LIB.S9S_MB_2U(SCH_1):UPI_CPU0_CPU1_P0P1_DN'<21>:
 C_SIGNAL='@s9s_mb_2u_lib.s9s_mb_2u(sch_1):upi_cpu0_cpu1_p0p1_dn(21)';
NODE_NAME     U2 BL3
 '@S9S_MB_2U_LIB.S9S_MB_2U(SCH_1):PAGE32_I70@PURE_QUANTA.SOCKET4677_AZIF0045P001C01CS(CHIPS)':
 'UPI0_TX_DP21': CDS_PINID='UPI0_TX_DP21';
NODE_NAME     U1 CF2
 '@S9S_MB_2U_LIB.S9S_MB_2U(SCH_1):PAGE64_I21@PURE_QUANTA.SOCKET4677_AZIF0045P001C01CS(CHIPS)':
 'UPI1_RX_DN21': CDS_PINID='UPI1_RX_DN21';
NET_NAME
'UPI_CPU0_CPU1_P0P1_DN<22>'
 '@S9S_MB_2U_LIB.S9S_MB_2U(SCH_1):UPI_CPU0_CPU1_P0P1_DN'<22>:
 C_SIGNAL='@s9s_mb_2u_lib.s9s_mb_2u(sch_1):upi_cpu0_cpu1_p0p1_dn(22)';
NODE_NAME     U2 BN3
 '@S9S_MB_2U_LIB.S9S_MB_2U(SCH_1):PAGE32_I70@PURE_QUANTA.SOCKET4677_AZIF0045P001C01CS(CHIPS)':
 'UPI0_TX_DP22': CDS_PINID='UPI0_TX_DP22';
NODE_NAME     U1 CD2
 '@S9S_MB_2U_LIB.S9S_MB_2U(SCH_1):PAGE64_I21@PURE_QUANTA.SOCKET4677_AZIF0045P001C01CS(CHIPS)':
 'UPI1_RX_DN22': CDS_PINID='UPI1_RX_DN22';
NET_NAME
'UPI_CPU0_CPU1_P0P1_DN<23>'
 '@S9S_MB_2U_LIB.S9S_MB_2U(SCH_1):UPI_CPU0_CPU1_P0P1_DN'<23>:
 C_SIGNAL='@s9s_mb_2u_lib.s9s_mb_2u(sch_1):upi_cpu0_cpu1_p0p1_dn(23)';
NODE_NAME     U2 BT2
 '@S9S_MB_2U_LIB.S9S_MB_2U(SCH_1):PAGE32_I70@PURE_QUANTA.SOCKET4677_AZIF0045P001C01CS(CHIPS)':
 'UPI0_TX_DN23': CDS_PINID='UPI0_TX_DN23';
NODE_NAME     U1 CB2
 '@S9S_MB_2U_LIB.S9S_MB_2U(SCH_1):PAGE64_I21@PURE_QUANTA.SOCKET4677_AZIF0045P001C01CS(CHIPS)':
 'UPI1_RX_DN23': CDS_PINID='UPI1_RX_DN23';
NET_NAME
'UPI_CPU0_CPU1_P0P1_DN<2>'
 '@S9S_MB_2U_LIB.S9S_MB_2U(SCH_1):UPI_CPU0_CPU1_P0P1_DN'<2>:
 C_SIGNAL='@s9s_mb_2u_lib.s9s_mb_2u(sch_1):upi_cpu0_cpu1_p0p1_dn(2)';
NODE_NAME     U2 N1
 '@S9S_MB_2U_LIB.S9S_MB_2U(SCH_1):PAGE32_I70@PURE_QUANTA.SOCKET4677_AZIF0045P001C01CS(CHIPS)':
 'UPI0_TX_DN2': CDS_PINID='UPI0_TX_DN2';
NODE_NAME     U1 ED2
 '@S9S_MB_2U_LIB.S9S_MB_2U(SCH_1):PAGE64_I21@PURE_QUANTA.SOCKET4677_AZIF0045P001C01CS(CHIPS)':
 'UPI1_RX_DN2': CDS_PINID='UPI1_RX_DN2';
NET_NAME
'UPI_CPU0_CPU1_P0P1_DN<3>'
 '@S9S_MB_2U_LIB.S9S_MB_2U(SCH_1):UPI_CPU0_CPU1_P0P1_DN'<3>:
 C_SIGNAL='@s9s_mb_2u_lib.s9s_mb_2u(sch_1):upi_cpu0_cpu1_p0p1_dn(3)';
NODE_NAME     U2 T2
 '@S9S_MB_2U_LIB.S9S_MB_2U(SCH_1):PAGE32_I70@PURE_QUANTA.SOCKET4677_AZIF0045P001C01CS(CHIPS)':
 'UPI0_TX_DN3': CDS_PINID='UPI0_TX_DN3';
NODE_NAME     U1 EA1
 '@S9S_MB_2U_LIB.S9S_MB_2U(SCH_1):PAGE64_I21@PURE_QUANTA.SOCKET4677_AZIF0045P001C01CS(CHIPS)':
 'UPI1_RX_DN3': CDS_PINID='UPI1_RX_DN3';
NET_NAME
'UPI_CPU0_CPU1_P0P1_DN<4>'
 '@S9S_MB_2U_LIB.S9S_MB_2U(SCH_1):UPI_CPU0_CPU1_P0P1_DN'<4>:
 C_SIGNAL='@s9s_mb_2u_lib.s9s_mb_2u(sch_1):upi_cpu0_cpu1_p0p1_dn(4)';
NODE_NAME     U2 U1
 '@S9S_MB_2U_LIB.S9S_MB_2U(SCH_1):PAGE32_I70@PURE_QUANTA.SOCKET4677_AZIF0045P001C01CS(CHIPS)':
 'UPI0_TX_DN4': CDS_PINID='UPI0_TX_DN4';
NODE_NAME     U1 DY2
 '@S9S_MB_2U_LIB.S9S_MB_2U(SCH_1):PAGE64_I21@PURE_QUANTA.SOCKET4677_AZIF0045P001C01CS(CHIPS)':
 'UPI1_RX_DN4': CDS_PINID='UPI1_RX_DN4';
NET_NAME
'UPI_CPU0_CPU1_P0P1_DN<5>'
 '@S9S_MB_2U_LIB.S9S_MB_2U(SCH_1):UPI_CPU0_CPU1_P0P1_DN'<5>:
 C_SIGNAL='@s9s_mb_2u_lib.s9s_mb_2u(sch_1):upi_cpu0_cpu1_p0p1_dn(5)';
NODE_NAME     U2 Y2
 '@S9S_MB_2U_LIB.S9S_MB_2U(SCH_1):PAGE32_I70@PURE_QUANTA.SOCKET4677_AZIF0045P001C01CS(CHIPS)':
 'UPI0_TX_DN5': CDS_PINID='UPI0_TX_DN5';
NODE_NAME     U1 DU1
 '@S9S_MB_2U_LIB.S9S_MB_2U(SCH_1):PAGE64_I21@PURE_QUANTA.SOCKET4677_AZIF0045P001C01CS(CHIPS)':
 'UPI1_RX_DN5': CDS_PINID='UPI1_RX_DN5';
NET_NAME
'UPI_CPU0_CPU1_P0P1_DN<6>'
 '@S9S_MB_2U_LIB.S9S_MB_2U(SCH_1):UPI_CPU0_CPU1_P0P1_DN'<6>:
 C_SIGNAL='@s9s_mb_2u_lib.s9s_mb_2u(sch_1):upi_cpu0_cpu1_p0p1_dn(6)';
NODE_NAME     U2 AA1
 '@S9S_MB_2U_LIB.S9S_MB_2U(SCH_1):PAGE32_I70@PURE_QUANTA.SOCKET4677_AZIF0045P001C01CS(CHIPS)':
 'UPI0_TX_DN6': CDS_PINID='UPI0_TX_DN6';
NODE_NAME     U1 DT2
 '@S9S_MB_2U_LIB.S9S_MB_2U(SCH_1):PAGE64_I21@PURE_QUANTA.SOCKET4677_AZIF0045P001C01CS(CHIPS)':
 'UPI1_RX_DN6': CDS_PINID='UPI1_RX_DN6';
NET_NAME
'UPI_CPU0_CPU1_P0P1_DN<7>'
 '@S9S_MB_2U_LIB.S9S_MB_2U(SCH_1):UPI_CPU0_CPU1_P0P1_DN'<7>:
 C_SIGNAL='@s9s_mb_2u_lib.s9s_mb_2u(sch_1):upi_cpu0_cpu1_p0p1_dn(7)';
NODE_NAME     U2 AD2
 '@S9S_MB_2U_LIB.S9S_MB_2U(SCH_1):PAGE32_I70@PURE_QUANTA.SOCKET4677_AZIF0045P001C01CS(CHIPS)':
 'UPI0_TX_DN7': CDS_PINID='UPI0_TX_DN7';
NODE_NAME     U1 DN1
 '@S9S_MB_2U_LIB.S9S_MB_2U(SCH_1):PAGE64_I21@PURE_QUANTA.SOCKET4677_AZIF0045P001C01CS(CHIPS)':
 'UPI1_RX_DN7': CDS_PINID='UPI1_RX_DN7';
NET_NAME
'UPI_CPU0_CPU1_P0P1_DN<8>'
 '@S9S_MB_2U_LIB.S9S_MB_2U(SCH_1):UPI_CPU0_CPU1_P0P1_DN'<8>:
 C_SIGNAL='@s9s_mb_2u_lib.s9s_mb_2u(sch_1):upi_cpu0_cpu1_p0p1_dn(8)';
NODE_NAME     U2 AF2
 '@S9S_MB_2U_LIB.S9S_MB_2U(SCH_1):PAGE32_I70@PURE_QUANTA.SOCKET4677_AZIF0045P001C01CS(CHIPS)':
 'UPI0_TX_DN8': CDS_PINID='UPI0_TX_DN8';
NODE_NAME     U1 DL3
 '@S9S_MB_2U_LIB.S9S_MB_2U(SCH_1):PAGE64_I21@PURE_QUANTA.SOCKET4677_AZIF0045P001C01CS(CHIPS)':
 'UPI1_RX_DN8': CDS_PINID='UPI1_RX_DN8';
NET_NAME
'UPI_CPU0_CPU1_P0P1_DN<9>'
 '@S9S_MB_2U_LIB.S9S_MB_2U(SCH_1):UPI_CPU0_CPU1_P0P1_DN'<9>:
 C_SIGNAL='@s9s_mb_2u_lib.s9s_mb_2u(sch_1):upi_cpu0_cpu1_p0p1_dn(9)';
NODE_NAME     U2 AH2
 '@S9S_MB_2U_LIB.S9S_MB_2U(SCH_1):PAGE32_I70@PURE_QUANTA.SOCKET4677_AZIF0045P001C01CS(CHIPS)':
 'UPI0_TX_DN9': CDS_PINID='UPI0_TX_DN9';
NODE_NAME     U1 DJ1
 '@S9S_MB_2U_LIB.S9S_MB_2U(SCH_1):PAGE64_I21@PURE_QUANTA.SOCKET4677_AZIF0045P001C01CS(CHIPS)':
 'UPI1_RX_DN9': CDS_PINID='UPI1_RX_DN9';
NET_NAME
'UPI_CPU0_CPU1_P0P1_DP<0>'
 '@S9S_MB_2U_LIB.S9S_MB_2U(SCH_1):UPI_CPU0_CPU1_P0P1_DP'<0>:
 C_SIGNAL='@s9s_mb_2u_lib.s9s_mb_2u(sch_1):upi_cpu0_cpu1_p0p1_dp(0)';
NODE_NAME     U2 J3
 '@S9S_MB_2U_LIB.S9S_MB_2U(SCH_1):PAGE32_I70@PURE_QUANTA.SOCKET4677_AZIF0045P001C01CS(CHIPS)':
 'UPI0_TX_DP0': CDS_PINID='UPI0_TX_DP0';
NODE_NAME     U1 EJ3
 '@S9S_MB_2U_LIB.S9S_MB_2U(SCH_1):PAGE64_I21@PURE_QUANTA.SOCKET4677_AZIF0045P001C01CS(CHIPS)':
 'UPI1_RX_DP0': CDS_PINID='UPI1_RX_DP0';
NET_NAME
'UPI_CPU0_CPU1_P0P1_DP<10>'
 '@S9S_MB_2U_LIB.S9S_MB_2U(SCH_1):UPI_CPU0_CPU1_P0P1_DP'<10>:
 C_SIGNAL='@s9s_mb_2u_lib.s9s_mb_2u(sch_1):upi_cpu0_cpu1_p0p1_dp(10)';
NODE_NAME     U2 AJ1
 '@S9S_MB_2U_LIB.S9S_MB_2U(SCH_1):PAGE32_I70@PURE_QUANTA.SOCKET4677_AZIF0045P001C01CS(CHIPS)':
 'UPI0_TX_DP10': CDS_PINID='UPI0_TX_DP10';
NODE_NAME     U1 DH2
 '@S9S_MB_2U_LIB.S9S_MB_2U(SCH_1):PAGE64_I21@PURE_QUANTA.SOCKET4677_AZIF0045P001C01CS(CHIPS)':
 'UPI1_RX_DP10': CDS_PINID='UPI1_RX_DP10';
NET_NAME
'UPI_CPU0_CPU1_P0P1_DP<11>'
 '@S9S_MB_2U_LIB.S9S_MB_2U(SCH_1):UPI_CPU0_CPU1_P0P1_DP'<11>:
 C_SIGNAL='@s9s_mb_2u_lib.s9s_mb_2u(sch_1):upi_cpu0_cpu1_p0p1_dp(11)';
NODE_NAME     U2 AL3
 '@S9S_MB_2U_LIB.S9S_MB_2U(SCH_1):PAGE32_I70@PURE_QUANTA.SOCKET4677_AZIF0045P001C01CS(CHIPS)':
 'UPI0_TX_DP11': CDS_PINID='UPI0_TX_DP11';
NODE_NAME     U1 DF2
 '@S9S_MB_2U_LIB.S9S_MB_2U(SCH_1):PAGE64_I21@PURE_QUANTA.SOCKET4677_AZIF0045P001C01CS(CHIPS)':
 'UPI1_RX_DP11': CDS_PINID='UPI1_RX_DP11';
NET_NAME
'UPI_CPU0_CPU1_P0P1_DP<12>'
 '@S9S_MB_2U_LIB.S9S_MB_2U(SCH_1):UPI_CPU0_CPU1_P0P1_DP'<12>:
 C_SIGNAL='@s9s_mb_2u_lib.s9s_mb_2u(sch_1):upi_cpu0_cpu1_p0p1_dp(12)';
NODE_NAME     U2 AP2
 '@S9S_MB_2U_LIB.S9S_MB_2U(SCH_1):PAGE32_I70@PURE_QUANTA.SOCKET4677_AZIF0045P001C01CS(CHIPS)':
 'UPI0_TX_DN12': CDS_PINID='UPI0_TX_DN12';
NODE_NAME     U1 DC3
 '@S9S_MB_2U_LIB.S9S_MB_2U(SCH_1):PAGE64_I21@PURE_QUANTA.SOCKET4677_AZIF0045P001C01CS(CHIPS)':
 'UPI1_RX_DP12': CDS_PINID='UPI1_RX_DP12';
NET_NAME
'UPI_CPU0_CPU1_P0P1_DP<13>'
 '@S9S_MB_2U_LIB.S9S_MB_2U(SCH_1):UPI_CPU0_CPU1_P0P1_DP'<13>:
 C_SIGNAL='@s9s_mb_2u_lib.s9s_mb_2u(sch_1):upi_cpu0_cpu1_p0p1_dp(13)';
NODE_NAME     U2 AT2
 '@S9S_MB_2U_LIB.S9S_MB_2U(SCH_1):PAGE32_I70@PURE_QUANTA.SOCKET4677_AZIF0045P001C01CS(CHIPS)':
 'UPI0_TX_DN13': CDS_PINID='UPI0_TX_DN13';
NODE_NAME     U1 DA1
 '@S9S_MB_2U_LIB.S9S_MB_2U(SCH_1):PAGE64_I21@PURE_QUANTA.SOCKET4677_AZIF0045P001C01CS(CHIPS)':
 'UPI1_RX_DP13': CDS_PINID='UPI1_RX_DP13';
NET_NAME
'UPI_CPU0_CPU1_P0P1_DP<14>'
 '@S9S_MB_2U_LIB.S9S_MB_2U(SCH_1):UPI_CPU0_CPU1_P0P1_DP'<14>:
 C_SIGNAL='@s9s_mb_2u_lib.s9s_mb_2u(sch_1):upi_cpu0_cpu1_p0p1_dp(14)';
NODE_NAME     U2 AV2
 '@S9S_MB_2U_LIB.S9S_MB_2U(SCH_1):PAGE32_I70@PURE_QUANTA.SOCKET4677_AZIF0045P001C01CS(CHIPS)':
 'UPI0_TX_DP14': CDS_PINID='UPI0_TX_DP14';
NODE_NAME     U1 CW3
 '@S9S_MB_2U_LIB.S9S_MB_2U(SCH_1):PAGE64_I21@PURE_QUANTA.SOCKET4677_AZIF0045P001C01CS(CHIPS)':
 'UPI1_RX_DP14': CDS_PINID='UPI1_RX_DP14';
NET_NAME
'UPI_CPU0_CPU1_P0P1_DP<15>'
 '@S9S_MB_2U_LIB.S9S_MB_2U(SCH_1):UPI_CPU0_CPU1_P0P1_DP'<15>:
 C_SIGNAL='@s9s_mb_2u_lib.s9s_mb_2u(sch_1):upi_cpu0_cpu1_p0p1_dp(15)';
NODE_NAME     U2 AY2
 '@S9S_MB_2U_LIB.S9S_MB_2U(SCH_1):PAGE32_I70@PURE_QUANTA.SOCKET4677_AZIF0045P001C01CS(CHIPS)':
 'UPI0_TX_DN15': CDS_PINID='UPI0_TX_DN15';
NODE_NAME     U1 CU1
 '@S9S_MB_2U_LIB.S9S_MB_2U(SCH_1):PAGE64_I21@PURE_QUANTA.SOCKET4677_AZIF0045P001C01CS(CHIPS)':
 'UPI1_RX_DP15': CDS_PINID='UPI1_RX_DP15';
NET_NAME
'UPI_CPU0_CPU1_P0P1_DP<16>'
 '@S9S_MB_2U_LIB.S9S_MB_2U(SCH_1):UPI_CPU0_CPU1_P0P1_DP'<16>:
 C_SIGNAL='@s9s_mb_2u_lib.s9s_mb_2u(sch_1):upi_cpu0_cpu1_p0p1_dp(16)';
NODE_NAME     U2 BA1
 '@S9S_MB_2U_LIB.S9S_MB_2U(SCH_1):PAGE32_I70@PURE_QUANTA.SOCKET4677_AZIF0045P001C01CS(CHIPS)':
 'UPI0_TX_DP16': CDS_PINID='UPI0_TX_DP16';
NODE_NAME     U1 CT2
 '@S9S_MB_2U_LIB.S9S_MB_2U(SCH_1):PAGE64_I21@PURE_QUANTA.SOCKET4677_AZIF0045P001C01CS(CHIPS)':
 'UPI1_RX_DP16': CDS_PINID='UPI1_RX_DP16';
NET_NAME
'UPI_CPU0_CPU1_P0P1_DP<17>'
 '@S9S_MB_2U_LIB.S9S_MB_2U(SCH_1):UPI_CPU0_CPU1_P0P1_DP'<17>:
 C_SIGNAL='@s9s_mb_2u_lib.s9s_mb_2u(sch_1):upi_cpu0_cpu1_p0p1_dp(17)';
NODE_NAME     U2 BC3
 '@S9S_MB_2U_LIB.S9S_MB_2U(SCH_1):PAGE32_I70@PURE_QUANTA.SOCKET4677_AZIF0045P001C01CS(CHIPS)':
 'UPI0_TX_DP17': CDS_PINID='UPI0_TX_DP17';
NODE_NAME     U1 CP2
 '@S9S_MB_2U_LIB.S9S_MB_2U(SCH_1):PAGE64_I21@PURE_QUANTA.SOCKET4677_AZIF0045P001C01CS(CHIPS)':
 'UPI1_RX_DP17': CDS_PINID='UPI1_RX_DP17';
NET_NAME
'UPI_CPU0_CPU1_P0P1_DP<18>'
 '@S9S_MB_2U_LIB.S9S_MB_2U(SCH_1):UPI_CPU0_CPU1_P0P1_DP'<18>:
 C_SIGNAL='@s9s_mb_2u_lib.s9s_mb_2u(sch_1):upi_cpu0_cpu1_p0p1_dp(18)';
NODE_NAME     U2 BE1
 '@S9S_MB_2U_LIB.S9S_MB_2U(SCH_1):PAGE32_I70@PURE_QUANTA.SOCKET4677_AZIF0045P001C01CS(CHIPS)':
 'UPI0_TX_DP18': CDS_PINID='UPI0_TX_DP18';
NODE_NAME     U1 CM2
 '@S9S_MB_2U_LIB.S9S_MB_2U(SCH_1):PAGE64_I21@PURE_QUANTA.SOCKET4677_AZIF0045P001C01CS(CHIPS)':
 'UPI1_RX_DP18': CDS_PINID='UPI1_RX_DP18';
NET_NAME
'UPI_CPU0_CPU1_P0P1_DP<19>'
 '@S9S_MB_2U_LIB.S9S_MB_2U(SCH_1):UPI_CPU0_CPU1_P0P1_DP'<19>:
 C_SIGNAL='@s9s_mb_2u_lib.s9s_mb_2u(sch_1):upi_cpu0_cpu1_p0p1_dp(19)';
NODE_NAME     U2 BG3
 '@S9S_MB_2U_LIB.S9S_MB_2U(SCH_1):PAGE32_I70@PURE_QUANTA.SOCKET4677_AZIF0045P001C01CS(CHIPS)':
 'UPI0_TX_DP19': CDS_PINID='UPI0_TX_DP19';
NODE_NAME     U1 CK2
 '@S9S_MB_2U_LIB.S9S_MB_2U(SCH_1):PAGE64_I21@PURE_QUANTA.SOCKET4677_AZIF0045P001C01CS(CHIPS)':
 'UPI1_RX_DP19': CDS_PINID='UPI1_RX_DP19';
NET_NAME
'UPI_CPU0_CPU1_P0P1_DP<1>'
 '@S9S_MB_2U_LIB.S9S_MB_2U(SCH_1):UPI_CPU0_CPU1_P0P1_DP'<1>:
 C_SIGNAL='@s9s_mb_2u_lib.s9s_mb_2u(sch_1):upi_cpu0_cpu1_p0p1_dp(1)';
NODE_NAME     U2 L3
 '@S9S_MB_2U_LIB.S9S_MB_2U(SCH_1):PAGE32_I70@PURE_QUANTA.SOCKET4677_AZIF0045P001C01CS(CHIPS)':
 'UPI0_TX_DP1': CDS_PINID='UPI0_TX_DP1';
NODE_NAME     U1 EG3
 '@S9S_MB_2U_LIB.S9S_MB_2U(SCH_1):PAGE64_I21@PURE_QUANTA.SOCKET4677_AZIF0045P001C01CS(CHIPS)':
 'UPI1_RX_DP1': CDS_PINID='UPI1_RX_DP1';
NET_NAME
'UPI_CPU0_CPU1_P0P1_DP<20>'
 '@S9S_MB_2U_LIB.S9S_MB_2U(SCH_1):UPI_CPU0_CPU1_P0P1_DP'<20>:
 C_SIGNAL='@s9s_mb_2u_lib.s9s_mb_2u(sch_1):upi_cpu0_cpu1_p0p1_dp(20)';
NODE_NAME     U2 BK2
 '@S9S_MB_2U_LIB.S9S_MB_2U(SCH_1):PAGE32_I70@PURE_QUANTA.SOCKET4677_AZIF0045P001C01CS(CHIPS)':
 'UPI0_TX_DN20': CDS_PINID='UPI0_TX_DN20';
NODE_NAME     U1 CG3
 '@S9S_MB_2U_LIB.S9S_MB_2U(SCH_1):PAGE64_I21@PURE_QUANTA.SOCKET4677_AZIF0045P001C01CS(CHIPS)':
 'UPI1_RX_DP20': CDS_PINID='UPI1_RX_DP20';
NET_NAME
'UPI_CPU0_CPU1_P0P1_DP<21>'
 '@S9S_MB_2U_LIB.S9S_MB_2U(SCH_1):UPI_CPU0_CPU1_P0P1_DP'<21>:
 C_SIGNAL='@s9s_mb_2u_lib.s9s_mb_2u(sch_1):upi_cpu0_cpu1_p0p1_dp(21)';
NODE_NAME     U2 BM2
 '@S9S_MB_2U_LIB.S9S_MB_2U(SCH_1):PAGE32_I70@PURE_QUANTA.SOCKET4677_AZIF0045P001C01CS(CHIPS)':
 'UPI0_TX_DN21': CDS_PINID='UPI0_TX_DN21';
NODE_NAME     U1 CE1
 '@S9S_MB_2U_LIB.S9S_MB_2U(SCH_1):PAGE64_I21@PURE_QUANTA.SOCKET4677_AZIF0045P001C01CS(CHIPS)':
 'UPI1_RX_DP21': CDS_PINID='UPI1_RX_DP21';
NET_NAME
'UPI_CPU0_CPU1_P0P1_DP<22>'
 '@S9S_MB_2U_LIB.S9S_MB_2U(SCH_1):UPI_CPU0_CPU1_P0P1_DP'<22>:
 C_SIGNAL='@s9s_mb_2u_lib.s9s_mb_2u(sch_1):upi_cpu0_cpu1_p0p1_dp(22)';
NODE_NAME     U2 BR3
 '@S9S_MB_2U_LIB.S9S_MB_2U(SCH_1):PAGE32_I70@PURE_QUANTA.SOCKET4677_AZIF0045P001C01CS(CHIPS)':
 'UPI0_TX_DN22': CDS_PINID='UPI0_TX_DN22';
NODE_NAME     U1 CC3
 '@S9S_MB_2U_LIB.S9S_MB_2U(SCH_1):PAGE64_I21@PURE_QUANTA.SOCKET4677_AZIF0045P001C01CS(CHIPS)':
 'UPI1_RX_DP22': CDS_PINID='UPI1_RX_DP22';
NET_NAME
'UPI_CPU0_CPU1_P0P1_DP<23>'
 '@S9S_MB_2U_LIB.S9S_MB_2U(SCH_1):UPI_CPU0_CPU1_P0P1_DP'<23>:
 C_SIGNAL='@s9s_mb_2u_lib.s9s_mb_2u(sch_1):upi_cpu0_cpu1_p0p1_dp(23)';
NODE_NAME     U2 BU3
 '@S9S_MB_2U_LIB.S9S_MB_2U(SCH_1):PAGE32_I70@PURE_QUANTA.SOCKET4677_AZIF0045P001C01CS(CHIPS)':
 'UPI0_TX_DP23': CDS_PINID='UPI0_TX_DP23';
NODE_NAME     U1 BY2
 '@S9S_MB_2U_LIB.S9S_MB_2U(SCH_1):PAGE64_I21@PURE_QUANTA.SOCKET4677_AZIF0045P001C01CS(CHIPS)':
 'UPI1_RX_DP23': CDS_PINID='UPI1_RX_DP23';
NET_NAME
'UPI_CPU0_CPU1_P0P1_DP<2>'
 '@S9S_MB_2U_LIB.S9S_MB_2U(SCH_1):UPI_CPU0_CPU1_P0P1_DP'<2>:
 C_SIGNAL='@s9s_mb_2u_lib.s9s_mb_2u(sch_1):upi_cpu0_cpu1_p0p1_dp(2)';
NODE_NAME     U2 P2
 '@S9S_MB_2U_LIB.S9S_MB_2U(SCH_1):PAGE32_I70@PURE_QUANTA.SOCKET4677_AZIF0045P001C01CS(CHIPS)':
 'UPI0_TX_DP2': CDS_PINID='UPI0_TX_DP2';
NODE_NAME     U1 EC3
 '@S9S_MB_2U_LIB.S9S_MB_2U(SCH_1):PAGE64_I21@PURE_QUANTA.SOCKET4677_AZIF0045P001C01CS(CHIPS)':
 'UPI1_RX_DP2': CDS_PINID='UPI1_RX_DP2';
NET_NAME
'UPI_CPU0_CPU1_P0P1_DP<3>'
 '@S9S_MB_2U_LIB.S9S_MB_2U(SCH_1):UPI_CPU0_CPU1_P0P1_DP'<3>:
 C_SIGNAL='@s9s_mb_2u_lib.s9s_mb_2u(sch_1):upi_cpu0_cpu1_p0p1_dp(3)';
NODE_NAME     U2 R3
 '@S9S_MB_2U_LIB.S9S_MB_2U(SCH_1):PAGE32_I70@PURE_QUANTA.SOCKET4677_AZIF0045P001C01CS(CHIPS)':
 'UPI0_TX_DP3': CDS_PINID='UPI0_TX_DP3';
NODE_NAME     U1 EB2
 '@S9S_MB_2U_LIB.S9S_MB_2U(SCH_1):PAGE64_I21@PURE_QUANTA.SOCKET4677_AZIF0045P001C01CS(CHIPS)':
 'UPI1_RX_DP3': CDS_PINID='UPI1_RX_DP3';
NET_NAME
'UPI_CPU0_CPU1_P0P1_DP<4>'
 '@S9S_MB_2U_LIB.S9S_MB_2U(SCH_1):UPI_CPU0_CPU1_P0P1_DP'<4>:
 C_SIGNAL='@s9s_mb_2u_lib.s9s_mb_2u(sch_1):upi_cpu0_cpu1_p0p1_dp(4)';
NODE_NAME     U2 V2
 '@S9S_MB_2U_LIB.S9S_MB_2U(SCH_1):PAGE32_I70@PURE_QUANTA.SOCKET4677_AZIF0045P001C01CS(CHIPS)':
 'UPI0_TX_DP4': CDS_PINID='UPI0_TX_DP4';
NODE_NAME     U1 DW3
 '@S9S_MB_2U_LIB.S9S_MB_2U(SCH_1):PAGE64_I21@PURE_QUANTA.SOCKET4677_AZIF0045P001C01CS(CHIPS)':
 'UPI1_RX_DP4': CDS_PINID='UPI1_RX_DP4';
NET_NAME
'UPI_CPU0_CPU1_P0P1_DP<5>'
 '@S9S_MB_2U_LIB.S9S_MB_2U(SCH_1):UPI_CPU0_CPU1_P0P1_DP'<5>:
 C_SIGNAL='@s9s_mb_2u_lib.s9s_mb_2u(sch_1):upi_cpu0_cpu1_p0p1_dp(5)';
NODE_NAME     U2 W3
 '@S9S_MB_2U_LIB.S9S_MB_2U(SCH_1):PAGE32_I70@PURE_QUANTA.SOCKET4677_AZIF0045P001C01CS(CHIPS)':
 'UPI0_TX_DP5': CDS_PINID='UPI0_TX_DP5';
NODE_NAME     U1 DV2
 '@S9S_MB_2U_LIB.S9S_MB_2U(SCH_1):PAGE64_I21@PURE_QUANTA.SOCKET4677_AZIF0045P001C01CS(CHIPS)':
 'UPI1_RX_DP5': CDS_PINID='UPI1_RX_DP5';
NET_NAME
'UPI_CPU0_CPU1_P0P1_DP<6>'
 '@S9S_MB_2U_LIB.S9S_MB_2U(SCH_1):UPI_CPU0_CPU1_P0P1_DP'<6>:
 C_SIGNAL='@s9s_mb_2u_lib.s9s_mb_2u(sch_1):upi_cpu0_cpu1_p0p1_dp(6)';
NODE_NAME     U2 AB2
 '@S9S_MB_2U_LIB.S9S_MB_2U(SCH_1):PAGE32_I70@PURE_QUANTA.SOCKET4677_AZIF0045P001C01CS(CHIPS)':
 'UPI0_TX_DP6': CDS_PINID='UPI0_TX_DP6';
NODE_NAME     U1 DR3
 '@S9S_MB_2U_LIB.S9S_MB_2U(SCH_1):PAGE64_I21@PURE_QUANTA.SOCKET4677_AZIF0045P001C01CS(CHIPS)':
 'UPI1_RX_DP6': CDS_PINID='UPI1_RX_DP6';
NET_NAME
'UPI_CPU0_CPU1_P0P1_DP<7>'
 '@S9S_MB_2U_LIB.S9S_MB_2U(SCH_1):UPI_CPU0_CPU1_P0P1_DP'<7>:
 C_SIGNAL='@s9s_mb_2u_lib.s9s_mb_2u(sch_1):upi_cpu0_cpu1_p0p1_dp(7)';
NODE_NAME     U2 AC3
 '@S9S_MB_2U_LIB.S9S_MB_2U(SCH_1):PAGE32_I70@PURE_QUANTA.SOCKET4677_AZIF0045P001C01CS(CHIPS)':
 'UPI0_TX_DP7': CDS_PINID='UPI0_TX_DP7';
NODE_NAME     U1 DP2
 '@S9S_MB_2U_LIB.S9S_MB_2U(SCH_1):PAGE64_I21@PURE_QUANTA.SOCKET4677_AZIF0045P001C01CS(CHIPS)':
 'UPI1_RX_DP7': CDS_PINID='UPI1_RX_DP7';
NET_NAME
'UPI_CPU0_CPU1_P0P1_DP<8>'
 '@S9S_MB_2U_LIB.S9S_MB_2U(SCH_1):UPI_CPU0_CPU1_P0P1_DP'<8>:
 C_SIGNAL='@s9s_mb_2u_lib.s9s_mb_2u(sch_1):upi_cpu0_cpu1_p0p1_dp(8)';
NODE_NAME     U2 AE1
 '@S9S_MB_2U_LIB.S9S_MB_2U(SCH_1):PAGE32_I70@PURE_QUANTA.SOCKET4677_AZIF0045P001C01CS(CHIPS)':
 'UPI0_TX_DP8': CDS_PINID='UPI0_TX_DP8';
NODE_NAME     U1 DM2
 '@S9S_MB_2U_LIB.S9S_MB_2U(SCH_1):PAGE64_I21@PURE_QUANTA.SOCKET4677_AZIF0045P001C01CS(CHIPS)':
 'UPI1_RX_DP8': CDS_PINID='UPI1_RX_DP8';
NET_NAME
'UPI_CPU0_CPU1_P0P1_DP<9>'
 '@S9S_MB_2U_LIB.S9S_MB_2U(SCH_1):UPI_CPU0_CPU1_P0P1_DP'<9>:
 C_SIGNAL='@s9s_mb_2u_lib.s9s_mb_2u(sch_1):upi_cpu0_cpu1_p0p1_dp(9)';
NODE_NAME     U2 AG3
 '@S9S_MB_2U_LIB.S9S_MB_2U(SCH_1):PAGE32_I70@PURE_QUANTA.SOCKET4677_AZIF0045P001C01CS(CHIPS)':
 'UPI0_TX_DP9': CDS_PINID='UPI0_TX_DP9';
NODE_NAME     U1 DK2
 '@S9S_MB_2U_LIB.S9S_MB_2U(SCH_1):PAGE64_I21@PURE_QUANTA.SOCKET4677_AZIF0045P001C01CS(CHIPS)':
 'UPI1_RX_DP9': CDS_PINID='UPI1_RX_DP9';
NET_NAME
'UPI_CPU0_CPU1_P1P0_DN<0>'
 '@S9S_MB_2U_LIB.S9S_MB_2U(SCH_1):UPI_CPU0_CPU1_P1P0_DN'<0>:
 C_SIGNAL='@s9s_mb_2u_lib.s9s_mb_2u(sch_1):upi_cpu0_cpu1_p1p0_dn(0)';
NODE_NAME     U2 EF6
 '@S9S_MB_2U_LIB.S9S_MB_2U(SCH_1):PAGE33_I102@PURE_QUANTA.SOCKET4677_AZIF0045P001C01CS(CHIPS)':
 'UPI1_TX_DN0': CDS_PINID='UPI1_TX_DN0';
NODE_NAME     U1 K6
 '@S9S_MB_2U_LIB.S9S_MB_2U(SCH_1):PAGE63_I51@PURE_QUANTA.SOCKET4677_AZIF0045P001C01CS(CHIPS)':
 'UPI0_RX_DN0': CDS_PINID='UPI0_RX_DN0';
NET_NAME
'UPI_CPU0_CPU1_P1P0_DN<10>'
 '@S9S_MB_2U_LIB.S9S_MB_2U(SCH_1):UPI_CPU0_CPU1_P1P0_DN'<10>:
 C_SIGNAL='@s9s_mb_2u_lib.s9s_mb_2u(sch_1):upi_cpu0_cpu1_p1p0_dn(10)';
NODE_NAME     U2 DF6
 '@S9S_MB_2U_LIB.S9S_MB_2U(SCH_1):PAGE33_I102@PURE_QUANTA.SOCKET4677_AZIF0045P001C01CS(CHIPS)':
 'UPI1_TX_DP10': CDS_PINID='UPI1_TX_DP10';
NODE_NAME     U1 AK6
 '@S9S_MB_2U_LIB.S9S_MB_2U(SCH_1):PAGE63_I51@PURE_QUANTA.SOCKET4677_AZIF0045P001C01CS(CHIPS)':
 'UPI0_RX_DN10': CDS_PINID='UPI0_RX_DN10';
NET_NAME
'UPI_CPU0_CPU1_P1P0_DN<11>'
 '@S9S_MB_2U_LIB.S9S_MB_2U(SCH_1):UPI_CPU0_CPU1_P1P0_DN'<11>:
 C_SIGNAL='@s9s_mb_2u_lib.s9s_mb_2u(sch_1):upi_cpu0_cpu1_p1p0_dn(11)';
NODE_NAME     U2 DC7
 '@S9S_MB_2U_LIB.S9S_MB_2U(SCH_1):PAGE33_I102@PURE_QUANTA.SOCKET4677_AZIF0045P001C01CS(CHIPS)':
 'UPI1_TX_DP11': CDS_PINID='UPI1_TX_DP11';
NODE_NAME     U1 AN5
 '@S9S_MB_2U_LIB.S9S_MB_2U(SCH_1):PAGE63_I51@PURE_QUANTA.SOCKET4677_AZIF0045P001C01CS(CHIPS)':
 'UPI0_RX_DN11': CDS_PINID='UPI0_RX_DN11';
NET_NAME
'UPI_CPU0_CPU1_P1P0_DN<12>'
 '@S9S_MB_2U_LIB.S9S_MB_2U(SCH_1):UPI_CPU0_CPU1_P1P0_DN'<12>:
 C_SIGNAL='@s9s_mb_2u_lib.s9s_mb_2u(sch_1):upi_cpu0_cpu1_p1p0_dn(12)';
NODE_NAME     U2 DB6
 '@S9S_MB_2U_LIB.S9S_MB_2U(SCH_1):PAGE33_I102@PURE_QUANTA.SOCKET4677_AZIF0045P001C01CS(CHIPS)':
 'UPI1_TX_DP12': CDS_PINID='UPI1_TX_DP12';
NODE_NAME     U1 AP6
 '@S9S_MB_2U_LIB.S9S_MB_2U(SCH_1):PAGE63_I51@PURE_QUANTA.SOCKET4677_AZIF0045P001C01CS(CHIPS)':
 'UPI0_RX_DN12': CDS_PINID='UPI0_RX_DN12';
NET_NAME
'UPI_CPU0_CPU1_P1P0_DN<13>'
 '@S9S_MB_2U_LIB.S9S_MB_2U(SCH_1):UPI_CPU0_CPU1_P1P0_DN'<13>:
 C_SIGNAL='@s9s_mb_2u_lib.s9s_mb_2u(sch_1):upi_cpu0_cpu1_p1p0_dn(13)';
NODE_NAME     U2 CW7
 '@S9S_MB_2U_LIB.S9S_MB_2U(SCH_1):PAGE33_I102@PURE_QUANTA.SOCKET4677_AZIF0045P001C01CS(CHIPS)':
 'UPI1_TX_DP13': CDS_PINID='UPI1_TX_DP13';
NODE_NAME     U1 AU5
 '@S9S_MB_2U_LIB.S9S_MB_2U(SCH_1):PAGE63_I51@PURE_QUANTA.SOCKET4677_AZIF0045P001C01CS(CHIPS)':
 'UPI0_RX_DN13': CDS_PINID='UPI0_RX_DN13';
NET_NAME
'UPI_CPU0_CPU1_P1P0_DN<14>'
 '@S9S_MB_2U_LIB.S9S_MB_2U(SCH_1):UPI_CPU0_CPU1_P1P0_DN'<14>:
 C_SIGNAL='@s9s_mb_2u_lib.s9s_mb_2u(sch_1):upi_cpu0_cpu1_p1p0_dn(14)';
NODE_NAME     U2 CV6
 '@S9S_MB_2U_LIB.S9S_MB_2U(SCH_1):PAGE33_I102@PURE_QUANTA.SOCKET4677_AZIF0045P001C01CS(CHIPS)':
 'UPI1_TX_DP14': CDS_PINID='UPI1_TX_DP14';
NODE_NAME     U1 AV6
 '@S9S_MB_2U_LIB.S9S_MB_2U(SCH_1):PAGE63_I51@PURE_QUANTA.SOCKET4677_AZIF0045P001C01CS(CHIPS)':
 'UPI0_RX_DN14': CDS_PINID='UPI0_RX_DN14';
NET_NAME
'UPI_CPU0_CPU1_P1P0_DN<15>'
 '@S9S_MB_2U_LIB.S9S_MB_2U(SCH_1):UPI_CPU0_CPU1_P1P0_DN'<15>:
 C_SIGNAL='@s9s_mb_2u_lib.s9s_mb_2u(sch_1):upi_cpu0_cpu1_p1p0_dn(15)';
NODE_NAME     U2 CR7
 '@S9S_MB_2U_LIB.S9S_MB_2U(SCH_1):PAGE33_I102@PURE_QUANTA.SOCKET4677_AZIF0045P001C01CS(CHIPS)':
 'UPI1_TX_DP15': CDS_PINID='UPI1_TX_DP15';
NODE_NAME     U1 BA5
 '@S9S_MB_2U_LIB.S9S_MB_2U(SCH_1):PAGE63_I51@PURE_QUANTA.SOCKET4677_AZIF0045P001C01CS(CHIPS)':
 'UPI0_RX_DN15': CDS_PINID='UPI0_RX_DN15';
NET_NAME
'UPI_CPU0_CPU1_P1P0_DN<16>'
 '@S9S_MB_2U_LIB.S9S_MB_2U(SCH_1):UPI_CPU0_CPU1_P1P0_DN'<16>:
 C_SIGNAL='@s9s_mb_2u_lib.s9s_mb_2u(sch_1):upi_cpu0_cpu1_p1p0_dn(16)';
NODE_NAME     U2 CP6
 '@S9S_MB_2U_LIB.S9S_MB_2U(SCH_1):PAGE33_I102@PURE_QUANTA.SOCKET4677_AZIF0045P001C01CS(CHIPS)':
 'UPI1_TX_DP16': CDS_PINID='UPI1_TX_DP16';
NODE_NAME     U1 BB6
 '@S9S_MB_2U_LIB.S9S_MB_2U(SCH_1):PAGE63_I51@PURE_QUANTA.SOCKET4677_AZIF0045P001C01CS(CHIPS)':
 'UPI0_RX_DN16': CDS_PINID='UPI0_RX_DN16';
NET_NAME
'UPI_CPU0_CPU1_P1P0_DN<17>'
 '@S9S_MB_2U_LIB.S9S_MB_2U(SCH_1):UPI_CPU0_CPU1_P1P0_DN'<17>:
 C_SIGNAL='@s9s_mb_2u_lib.s9s_mb_2u(sch_1):upi_cpu0_cpu1_p1p0_dn(17)';
NODE_NAME     U2 CL7
 '@S9S_MB_2U_LIB.S9S_MB_2U(SCH_1):PAGE33_I102@PURE_QUANTA.SOCKET4677_AZIF0045P001C01CS(CHIPS)':
 'UPI1_TX_DP17': CDS_PINID='UPI1_TX_DP17';
NODE_NAME     U1 BE5
 '@S9S_MB_2U_LIB.S9S_MB_2U(SCH_1):PAGE63_I51@PURE_QUANTA.SOCKET4677_AZIF0045P001C01CS(CHIPS)':
 'UPI0_RX_DN17': CDS_PINID='UPI0_RX_DN17';
NET_NAME
'UPI_CPU0_CPU1_P1P0_DN<18>'
 '@S9S_MB_2U_LIB.S9S_MB_2U(SCH_1):UPI_CPU0_CPU1_P1P0_DN'<18>:
 C_SIGNAL='@s9s_mb_2u_lib.s9s_mb_2u(sch_1):upi_cpu0_cpu1_p1p0_dn(18)';
NODE_NAME     U2 CK6
 '@S9S_MB_2U_LIB.S9S_MB_2U(SCH_1):PAGE33_I102@PURE_QUANTA.SOCKET4677_AZIF0045P001C01CS(CHIPS)':
 'UPI1_TX_DP18': CDS_PINID='UPI1_TX_DP18';
NODE_NAME     U1 BF6
 '@S9S_MB_2U_LIB.S9S_MB_2U(SCH_1):PAGE63_I51@PURE_QUANTA.SOCKET4677_AZIF0045P001C01CS(CHIPS)':
 'UPI0_RX_DN18': CDS_PINID='UPI0_RX_DN18';
NET_NAME
'UPI_CPU0_CPU1_P1P0_DN<19>'
 '@S9S_MB_2U_LIB.S9S_MB_2U(SCH_1):UPI_CPU0_CPU1_P1P0_DN'<19>:
 C_SIGNAL='@s9s_mb_2u_lib.s9s_mb_2u(sch_1):upi_cpu0_cpu1_p1p0_dn(19)';
NODE_NAME     U2 CG7
 '@S9S_MB_2U_LIB.S9S_MB_2U(SCH_1):PAGE33_I102@PURE_QUANTA.SOCKET4677_AZIF0045P001C01CS(CHIPS)':
 'UPI1_TX_DP19': CDS_PINID='UPI1_TX_DP19';
NODE_NAME     U1 BJ5
 '@S9S_MB_2U_LIB.S9S_MB_2U(SCH_1):PAGE63_I51@PURE_QUANTA.SOCKET4677_AZIF0045P001C01CS(CHIPS)':
 'UPI0_RX_DN19': CDS_PINID='UPI0_RX_DN19';
NET_NAME
'UPI_CPU0_CPU1_P1P0_DN<1>'
 '@S9S_MB_2U_LIB.S9S_MB_2U(SCH_1):UPI_CPU0_CPU1_P1P0_DN'<1>:
 C_SIGNAL='@s9s_mb_2u_lib.s9s_mb_2u(sch_1):upi_cpu0_cpu1_p1p0_dn(1)';
NODE_NAME     U2 EC7
 '@S9S_MB_2U_LIB.S9S_MB_2U(SCH_1):PAGE33_I102@PURE_QUANTA.SOCKET4677_AZIF0045P001C01CS(CHIPS)':
 'UPI1_TX_DN1': CDS_PINID='UPI1_TX_DN1';
NODE_NAME     U1 N5
 '@S9S_MB_2U_LIB.S9S_MB_2U(SCH_1):PAGE63_I51@PURE_QUANTA.SOCKET4677_AZIF0045P001C01CS(CHIPS)':
 'UPI0_RX_DN1': CDS_PINID='UPI0_RX_DN1';
NET_NAME
'UPI_CPU0_CPU1_P1P0_DN<20>'
 '@S9S_MB_2U_LIB.S9S_MB_2U(SCH_1):UPI_CPU0_CPU1_P1P0_DN'<20>:
 C_SIGNAL='@s9s_mb_2u_lib.s9s_mb_2u(sch_1):upi_cpu0_cpu1_p1p0_dn(20)';
NODE_NAME     U2 CF6
 '@S9S_MB_2U_LIB.S9S_MB_2U(SCH_1):PAGE33_I102@PURE_QUANTA.SOCKET4677_AZIF0045P001C01CS(CHIPS)':
 'UPI1_TX_DP20': CDS_PINID='UPI1_TX_DP20';
NODE_NAME     U1 BK6
 '@S9S_MB_2U_LIB.S9S_MB_2U(SCH_1):PAGE63_I51@PURE_QUANTA.SOCKET4677_AZIF0045P001C01CS(CHIPS)':
 'UPI0_RX_DN20': CDS_PINID='UPI0_RX_DN20';
NET_NAME
'UPI_CPU0_CPU1_P1P0_DN<21>'
 '@S9S_MB_2U_LIB.S9S_MB_2U(SCH_1):UPI_CPU0_CPU1_P1P0_DN'<21>:
 C_SIGNAL='@s9s_mb_2u_lib.s9s_mb_2u(sch_1):upi_cpu0_cpu1_p1p0_dn(21)';
NODE_NAME     U2 CC7
 '@S9S_MB_2U_LIB.S9S_MB_2U(SCH_1):PAGE33_I102@PURE_QUANTA.SOCKET4677_AZIF0045P001C01CS(CHIPS)':
 'UPI1_TX_DP21': CDS_PINID='UPI1_TX_DP21';
NODE_NAME     U1 BN5
 '@S9S_MB_2U_LIB.S9S_MB_2U(SCH_1):PAGE63_I51@PURE_QUANTA.SOCKET4677_AZIF0045P001C01CS(CHIPS)':
 'UPI0_RX_DN21': CDS_PINID='UPI0_RX_DN21';
NET_NAME
'UPI_CPU0_CPU1_P1P0_DN<22>'
 '@S9S_MB_2U_LIB.S9S_MB_2U(SCH_1):UPI_CPU0_CPU1_P1P0_DN'<22>:
 C_SIGNAL='@s9s_mb_2u_lib.s9s_mb_2u(sch_1):upi_cpu0_cpu1_p1p0_dn(22)';
NODE_NAME     U2 CA5
 '@S9S_MB_2U_LIB.S9S_MB_2U(SCH_1):PAGE33_I102@PURE_QUANTA.SOCKET4677_AZIF0045P001C01CS(CHIPS)':
 'UPI1_TX_DN22': CDS_PINID='UPI1_TX_DN22';
NODE_NAME     U1 BR7
 '@S9S_MB_2U_LIB.S9S_MB_2U(SCH_1):PAGE63_I51@PURE_QUANTA.SOCKET4677_AZIF0045P001C01CS(CHIPS)':
 'UPI0_RX_DN22': CDS_PINID='UPI0_RX_DN22';
NET_NAME
'UPI_CPU0_CPU1_P1P0_DN<23>'
 '@S9S_MB_2U_LIB.S9S_MB_2U(SCH_1):UPI_CPU0_CPU1_P1P0_DN'<23>:
 C_SIGNAL='@s9s_mb_2u_lib.s9s_mb_2u(sch_1):upi_cpu0_cpu1_p1p0_dn(23)';
NODE_NAME     U2 BW7
 '@S9S_MB_2U_LIB.S9S_MB_2U(SCH_1):PAGE33_I102@PURE_QUANTA.SOCKET4677_AZIF0045P001C01CS(CHIPS)':
 'UPI1_TX_DP23': CDS_PINID='UPI1_TX_DP23';
NODE_NAME     U1 BU5
 '@S9S_MB_2U_LIB.S9S_MB_2U(SCH_1):PAGE63_I51@PURE_QUANTA.SOCKET4677_AZIF0045P001C01CS(CHIPS)':
 'UPI0_RX_DN23': CDS_PINID='UPI0_RX_DN23';
NET_NAME
'UPI_CPU0_CPU1_P1P0_DN<2>'
 '@S9S_MB_2U_LIB.S9S_MB_2U(SCH_1):UPI_CPU0_CPU1_P1P0_DN'<2>:
 C_SIGNAL='@s9s_mb_2u_lib.s9s_mb_2u(sch_1):upi_cpu0_cpu1_p1p0_dn(2)';
NODE_NAME     U2 EB6
 '@S9S_MB_2U_LIB.S9S_MB_2U(SCH_1):PAGE33_I102@PURE_QUANTA.SOCKET4677_AZIF0045P001C01CS(CHIPS)':
 'UPI1_TX_DN2': CDS_PINID='UPI1_TX_DN2';
NODE_NAME     U1 P6
 '@S9S_MB_2U_LIB.S9S_MB_2U(SCH_1):PAGE63_I51@PURE_QUANTA.SOCKET4677_AZIF0045P001C01CS(CHIPS)':
 'UPI0_RX_DN2': CDS_PINID='UPI0_RX_DN2';
NET_NAME
'UPI_CPU0_CPU1_P1P0_DN<3>'
 '@S9S_MB_2U_LIB.S9S_MB_2U(SCH_1):UPI_CPU0_CPU1_P1P0_DN'<3>:
 C_SIGNAL='@s9s_mb_2u_lib.s9s_mb_2u(sch_1):upi_cpu0_cpu1_p1p0_dn(3)';
NODE_NAME     U2 DW7
 '@S9S_MB_2U_LIB.S9S_MB_2U(SCH_1):PAGE33_I102@PURE_QUANTA.SOCKET4677_AZIF0045P001C01CS(CHIPS)':
 'UPI1_TX_DP3': CDS_PINID='UPI1_TX_DP3';
NODE_NAME     U1 U5
 '@S9S_MB_2U_LIB.S9S_MB_2U(SCH_1):PAGE63_I51@PURE_QUANTA.SOCKET4677_AZIF0045P001C01CS(CHIPS)':
 'UPI0_RX_DN3': CDS_PINID='UPI0_RX_DN3';
NET_NAME
'UPI_CPU0_CPU1_P1P0_DN<4>'
 '@S9S_MB_2U_LIB.S9S_MB_2U(SCH_1):UPI_CPU0_CPU1_P1P0_DN'<4>:
 C_SIGNAL='@s9s_mb_2u_lib.s9s_mb_2u(sch_1):upi_cpu0_cpu1_p1p0_dn(4)';
NODE_NAME     U2 DV6
 '@S9S_MB_2U_LIB.S9S_MB_2U(SCH_1):PAGE33_I102@PURE_QUANTA.SOCKET4677_AZIF0045P001C01CS(CHIPS)':
 'UPI1_TX_DN4': CDS_PINID='UPI1_TX_DN4';
NODE_NAME     U1 V6
 '@S9S_MB_2U_LIB.S9S_MB_2U(SCH_1):PAGE63_I51@PURE_QUANTA.SOCKET4677_AZIF0045P001C01CS(CHIPS)':
 'UPI0_RX_DN4': CDS_PINID='UPI0_RX_DN4';
NET_NAME
'UPI_CPU0_CPU1_P1P0_DN<5>'
 '@S9S_MB_2U_LIB.S9S_MB_2U(SCH_1):UPI_CPU0_CPU1_P1P0_DN'<5>:
 C_SIGNAL='@s9s_mb_2u_lib.s9s_mb_2u(sch_1):upi_cpu0_cpu1_p1p0_dn(5)';
NODE_NAME     U2 DR7
 '@S9S_MB_2U_LIB.S9S_MB_2U(SCH_1):PAGE33_I102@PURE_QUANTA.SOCKET4677_AZIF0045P001C01CS(CHIPS)':
 'UPI1_TX_DP5': CDS_PINID='UPI1_TX_DP5';
NODE_NAME     U1 AA5
 '@S9S_MB_2U_LIB.S9S_MB_2U(SCH_1):PAGE63_I51@PURE_QUANTA.SOCKET4677_AZIF0045P001C01CS(CHIPS)':
 'UPI0_RX_DN5': CDS_PINID='UPI0_RX_DN5';
NET_NAME
'UPI_CPU0_CPU1_P1P0_DN<6>'
 '@S9S_MB_2U_LIB.S9S_MB_2U(SCH_1):UPI_CPU0_CPU1_P1P0_DN'<6>:
 C_SIGNAL='@s9s_mb_2u_lib.s9s_mb_2u(sch_1):upi_cpu0_cpu1_p1p0_dn(6)';
NODE_NAME     U2 DP6
 '@S9S_MB_2U_LIB.S9S_MB_2U(SCH_1):PAGE33_I102@PURE_QUANTA.SOCKET4677_AZIF0045P001C01CS(CHIPS)':
 'UPI1_TX_DN6': CDS_PINID='UPI1_TX_DN6';
NODE_NAME     U1 AB6
 '@S9S_MB_2U_LIB.S9S_MB_2U(SCH_1):PAGE63_I51@PURE_QUANTA.SOCKET4677_AZIF0045P001C01CS(CHIPS)':
 'UPI0_RX_DN6': CDS_PINID='UPI0_RX_DN6';
NET_NAME
'UPI_CPU0_CPU1_P1P0_DN<7>'
 '@S9S_MB_2U_LIB.S9S_MB_2U(SCH_1):UPI_CPU0_CPU1_P1P0_DN'<7>:
 C_SIGNAL='@s9s_mb_2u_lib.s9s_mb_2u(sch_1):upi_cpu0_cpu1_p1p0_dn(7)';
NODE_NAME     U2 DL7
 '@S9S_MB_2U_LIB.S9S_MB_2U(SCH_1):PAGE33_I102@PURE_QUANTA.SOCKET4677_AZIF0045P001C01CS(CHIPS)':
 'UPI1_TX_DN7': CDS_PINID='UPI1_TX_DN7';
NODE_NAME     U1 AE5
 '@S9S_MB_2U_LIB.S9S_MB_2U(SCH_1):PAGE63_I51@PURE_QUANTA.SOCKET4677_AZIF0045P001C01CS(CHIPS)':
 'UPI0_RX_DN7': CDS_PINID='UPI0_RX_DN7';
NET_NAME
'UPI_CPU0_CPU1_P1P0_DN<8>'
 '@S9S_MB_2U_LIB.S9S_MB_2U(SCH_1):UPI_CPU0_CPU1_P1P0_DN'<8>:
 C_SIGNAL='@s9s_mb_2u_lib.s9s_mb_2u(sch_1):upi_cpu0_cpu1_p1p0_dn(8)';
NODE_NAME     U2 DK6
 '@S9S_MB_2U_LIB.S9S_MB_2U(SCH_1):PAGE33_I102@PURE_QUANTA.SOCKET4677_AZIF0045P001C01CS(CHIPS)':
 'UPI1_TX_DN8': CDS_PINID='UPI1_TX_DN8';
NODE_NAME     U1 AF6
 '@S9S_MB_2U_LIB.S9S_MB_2U(SCH_1):PAGE63_I51@PURE_QUANTA.SOCKET4677_AZIF0045P001C01CS(CHIPS)':
 'UPI0_RX_DN8': CDS_PINID='UPI0_RX_DN8';
NET_NAME
'UPI_CPU0_CPU1_P1P0_DN<9>'
 '@S9S_MB_2U_LIB.S9S_MB_2U(SCH_1):UPI_CPU0_CPU1_P1P0_DN'<9>:
 C_SIGNAL='@s9s_mb_2u_lib.s9s_mb_2u(sch_1):upi_cpu0_cpu1_p1p0_dn(9)';
NODE_NAME     U2 DH6
 '@S9S_MB_2U_LIB.S9S_MB_2U(SCH_1):PAGE33_I102@PURE_QUANTA.SOCKET4677_AZIF0045P001C01CS(CHIPS)':
 'UPI1_TX_DN9': CDS_PINID='UPI1_TX_DN9';
NODE_NAME     U1 AH6
 '@S9S_MB_2U_LIB.S9S_MB_2U(SCH_1):PAGE63_I51@PURE_QUANTA.SOCKET4677_AZIF0045P001C01CS(CHIPS)':
 'UPI0_RX_DN9': CDS_PINID='UPI0_RX_DN9';
NET_NAME
'UPI_CPU0_CPU1_P1P0_DP<0>'
 '@S9S_MB_2U_LIB.S9S_MB_2U(SCH_1):UPI_CPU0_CPU1_P1P0_DP'<0>:
 C_SIGNAL='@s9s_mb_2u_lib.s9s_mb_2u(sch_1):upi_cpu0_cpu1_p1p0_dp(0)';
NODE_NAME     U2 EE5
 '@S9S_MB_2U_LIB.S9S_MB_2U(SCH_1):PAGE33_I102@PURE_QUANTA.SOCKET4677_AZIF0045P001C01CS(CHIPS)':
 'UPI1_TX_DP0': CDS_PINID='UPI1_TX_DP0';
NODE_NAME     U1 L7
 '@S9S_MB_2U_LIB.S9S_MB_2U(SCH_1):PAGE63_I51@PURE_QUANTA.SOCKET4677_AZIF0045P001C01CS(CHIPS)':
 'UPI0_RX_DP0': CDS_PINID='UPI0_RX_DP0';
NET_NAME
'UPI_CPU0_CPU1_P1P0_DP<10>'
 '@S9S_MB_2U_LIB.S9S_MB_2U(SCH_1):UPI_CPU0_CPU1_P1P0_DP'<10>:
 C_SIGNAL='@s9s_mb_2u_lib.s9s_mb_2u(sch_1):upi_cpu0_cpu1_p1p0_dp(10)';
NODE_NAME     U2 DE5
 '@S9S_MB_2U_LIB.S9S_MB_2U(SCH_1):PAGE33_I102@PURE_QUANTA.SOCKET4677_AZIF0045P001C01CS(CHIPS)':
 'UPI1_TX_DN10': CDS_PINID='UPI1_TX_DN10';
NODE_NAME     U1 AL7
 '@S9S_MB_2U_LIB.S9S_MB_2U(SCH_1):PAGE63_I51@PURE_QUANTA.SOCKET4677_AZIF0045P001C01CS(CHIPS)':
 'UPI0_RX_DP10': CDS_PINID='UPI0_RX_DP10';
NET_NAME
'UPI_CPU0_CPU1_P1P0_DP<11>'
 '@S9S_MB_2U_LIB.S9S_MB_2U(SCH_1):UPI_CPU0_CPU1_P1P0_DP'<11>:
 C_SIGNAL='@s9s_mb_2u_lib.s9s_mb_2u(sch_1):upi_cpu0_cpu1_p1p0_dp(11)';
NODE_NAME     U2 DD6
 '@S9S_MB_2U_LIB.S9S_MB_2U(SCH_1):PAGE33_I102@PURE_QUANTA.SOCKET4677_AZIF0045P001C01CS(CHIPS)':
 'UPI1_TX_DN11': CDS_PINID='UPI1_TX_DN11';
NODE_NAME     U1 AM6
 '@S9S_MB_2U_LIB.S9S_MB_2U(SCH_1):PAGE63_I51@PURE_QUANTA.SOCKET4677_AZIF0045P001C01CS(CHIPS)':
 'UPI0_RX_DP11': CDS_PINID='UPI0_RX_DP11';
NET_NAME
'UPI_CPU0_CPU1_P1P0_DP<12>'
 '@S9S_MB_2U_LIB.S9S_MB_2U(SCH_1):UPI_CPU0_CPU1_P1P0_DP'<12>:
 C_SIGNAL='@s9s_mb_2u_lib.s9s_mb_2u(sch_1):upi_cpu0_cpu1_p1p0_dp(12)';
NODE_NAME     U2 DA5
 '@S9S_MB_2U_LIB.S9S_MB_2U(SCH_1):PAGE33_I102@PURE_QUANTA.SOCKET4677_AZIF0045P001C01CS(CHIPS)':
 'UPI1_TX_DN12': CDS_PINID='UPI1_TX_DN12';
NODE_NAME     U1 AR7
 '@S9S_MB_2U_LIB.S9S_MB_2U(SCH_1):PAGE63_I51@PURE_QUANTA.SOCKET4677_AZIF0045P001C01CS(CHIPS)':
 'UPI0_RX_DP12': CDS_PINID='UPI0_RX_DP12';
NET_NAME
'UPI_CPU0_CPU1_P1P0_DP<13>'
 '@S9S_MB_2U_LIB.S9S_MB_2U(SCH_1):UPI_CPU0_CPU1_P1P0_DP'<13>:
 C_SIGNAL='@s9s_mb_2u_lib.s9s_mb_2u(sch_1):upi_cpu0_cpu1_p1p0_dp(13)';
NODE_NAME     U2 CY6
 '@S9S_MB_2U_LIB.S9S_MB_2U(SCH_1):PAGE33_I102@PURE_QUANTA.SOCKET4677_AZIF0045P001C01CS(CHIPS)':
 'UPI1_TX_DN13': CDS_PINID='UPI1_TX_DN13';
NODE_NAME     U1 AT6
 '@S9S_MB_2U_LIB.S9S_MB_2U(SCH_1):PAGE63_I51@PURE_QUANTA.SOCKET4677_AZIF0045P001C01CS(CHIPS)':
 'UPI0_RX_DP13': CDS_PINID='UPI0_RX_DP13';
NET_NAME
'UPI_CPU0_CPU1_P1P0_DP<14>'
 '@S9S_MB_2U_LIB.S9S_MB_2U(SCH_1):UPI_CPU0_CPU1_P1P0_DP'<14>:
 C_SIGNAL='@s9s_mb_2u_lib.s9s_mb_2u(sch_1):upi_cpu0_cpu1_p1p0_dp(14)';
NODE_NAME     U2 CU5
 '@S9S_MB_2U_LIB.S9S_MB_2U(SCH_1):PAGE33_I102@PURE_QUANTA.SOCKET4677_AZIF0045P001C01CS(CHIPS)':
 'UPI1_TX_DN14': CDS_PINID='UPI1_TX_DN14';
NODE_NAME     U1 AW7
 '@S9S_MB_2U_LIB.S9S_MB_2U(SCH_1):PAGE63_I51@PURE_QUANTA.SOCKET4677_AZIF0045P001C01CS(CHIPS)':
 'UPI0_RX_DP14': CDS_PINID='UPI0_RX_DP14';
NET_NAME
'UPI_CPU0_CPU1_P1P0_DP<15>'
 '@S9S_MB_2U_LIB.S9S_MB_2U(SCH_1):UPI_CPU0_CPU1_P1P0_DP'<15>:
 C_SIGNAL='@s9s_mb_2u_lib.s9s_mb_2u(sch_1):upi_cpu0_cpu1_p1p0_dp(15)';
NODE_NAME     U2 CT6
 '@S9S_MB_2U_LIB.S9S_MB_2U(SCH_1):PAGE33_I102@PURE_QUANTA.SOCKET4677_AZIF0045P001C01CS(CHIPS)':
 'UPI1_TX_DN15': CDS_PINID='UPI1_TX_DN15';
NODE_NAME     U1 AY6
 '@S9S_MB_2U_LIB.S9S_MB_2U(SCH_1):PAGE63_I51@PURE_QUANTA.SOCKET4677_AZIF0045P001C01CS(CHIPS)':
 'UPI0_RX_DP15': CDS_PINID='UPI0_RX_DP15';
NET_NAME
'UPI_CPU0_CPU1_P1P0_DP<16>'
 '@S9S_MB_2U_LIB.S9S_MB_2U(SCH_1):UPI_CPU0_CPU1_P1P0_DP'<16>:
 C_SIGNAL='@s9s_mb_2u_lib.s9s_mb_2u(sch_1):upi_cpu0_cpu1_p1p0_dp(16)';
NODE_NAME     U2 CN5
 '@S9S_MB_2U_LIB.S9S_MB_2U(SCH_1):PAGE33_I102@PURE_QUANTA.SOCKET4677_AZIF0045P001C01CS(CHIPS)':
 'UPI1_TX_DN16': CDS_PINID='UPI1_TX_DN16';
NODE_NAME     U1 BC7
 '@S9S_MB_2U_LIB.S9S_MB_2U(SCH_1):PAGE63_I51@PURE_QUANTA.SOCKET4677_AZIF0045P001C01CS(CHIPS)':
 'UPI0_RX_DP16': CDS_PINID='UPI0_RX_DP16';
NET_NAME
'UPI_CPU0_CPU1_P1P0_DP<17>'
 '@S9S_MB_2U_LIB.S9S_MB_2U(SCH_1):UPI_CPU0_CPU1_P1P0_DP'<17>:
 C_SIGNAL='@s9s_mb_2u_lib.s9s_mb_2u(sch_1):upi_cpu0_cpu1_p1p0_dp(17)';
NODE_NAME     U2 CM6
 '@S9S_MB_2U_LIB.S9S_MB_2U(SCH_1):PAGE33_I102@PURE_QUANTA.SOCKET4677_AZIF0045P001C01CS(CHIPS)':
 'UPI1_TX_DN17': CDS_PINID='UPI1_TX_DN17';
NODE_NAME     U1 BD6
 '@S9S_MB_2U_LIB.S9S_MB_2U(SCH_1):PAGE63_I51@PURE_QUANTA.SOCKET4677_AZIF0045P001C01CS(CHIPS)':
 'UPI0_RX_DP17': CDS_PINID='UPI0_RX_DP17';
NET_NAME
'UPI_CPU0_CPU1_P1P0_DP<18>'
 '@S9S_MB_2U_LIB.S9S_MB_2U(SCH_1):UPI_CPU0_CPU1_P1P0_DP'<18>:
 C_SIGNAL='@s9s_mb_2u_lib.s9s_mb_2u(sch_1):upi_cpu0_cpu1_p1p0_dp(18)';
NODE_NAME     U2 CJ5
 '@S9S_MB_2U_LIB.S9S_MB_2U(SCH_1):PAGE33_I102@PURE_QUANTA.SOCKET4677_AZIF0045P001C01CS(CHIPS)':
 'UPI1_TX_DN18': CDS_PINID='UPI1_TX_DN18';
NODE_NAME     U1 BG7
 '@S9S_MB_2U_LIB.S9S_MB_2U(SCH_1):PAGE63_I51@PURE_QUANTA.SOCKET4677_AZIF0045P001C01CS(CHIPS)':
 'UPI0_RX_DP18': CDS_PINID='UPI0_RX_DP18';
NET_NAME
'UPI_CPU0_CPU1_P1P0_DP<19>'
 '@S9S_MB_2U_LIB.S9S_MB_2U(SCH_1):UPI_CPU0_CPU1_P1P0_DP'<19>:
 C_SIGNAL='@s9s_mb_2u_lib.s9s_mb_2u(sch_1):upi_cpu0_cpu1_p1p0_dp(19)';
NODE_NAME     U2 CH6
 '@S9S_MB_2U_LIB.S9S_MB_2U(SCH_1):PAGE33_I102@PURE_QUANTA.SOCKET4677_AZIF0045P001C01CS(CHIPS)':
 'UPI1_TX_DN19': CDS_PINID='UPI1_TX_DN19';
NODE_NAME     U1 BH6
 '@S9S_MB_2U_LIB.S9S_MB_2U(SCH_1):PAGE63_I51@PURE_QUANTA.SOCKET4677_AZIF0045P001C01CS(CHIPS)':
 'UPI0_RX_DP19': CDS_PINID='UPI0_RX_DP19';
NET_NAME
'UPI_CPU0_CPU1_P1P0_DP<1>'
 '@S9S_MB_2U_LIB.S9S_MB_2U(SCH_1):UPI_CPU0_CPU1_P1P0_DP'<1>:
 C_SIGNAL='@s9s_mb_2u_lib.s9s_mb_2u(sch_1):upi_cpu0_cpu1_p1p0_dp(1)';
NODE_NAME     U2 ED6
 '@S9S_MB_2U_LIB.S9S_MB_2U(SCH_1):PAGE33_I102@PURE_QUANTA.SOCKET4677_AZIF0045P001C01CS(CHIPS)':
 'UPI1_TX_DP1': CDS_PINID='UPI1_TX_DP1';
NODE_NAME     U1 M6
 '@S9S_MB_2U_LIB.S9S_MB_2U(SCH_1):PAGE63_I51@PURE_QUANTA.SOCKET4677_AZIF0045P001C01CS(CHIPS)':
 'UPI0_RX_DP1': CDS_PINID='UPI0_RX_DP1';
NET_NAME
'UPI_CPU0_CPU1_P1P0_DP<20>'
 '@S9S_MB_2U_LIB.S9S_MB_2U(SCH_1):UPI_CPU0_CPU1_P1P0_DP'<20>:
 C_SIGNAL='@s9s_mb_2u_lib.s9s_mb_2u(sch_1):upi_cpu0_cpu1_p1p0_dp(20)';
NODE_NAME     U2 CE5
 '@S9S_MB_2U_LIB.S9S_MB_2U(SCH_1):PAGE33_I102@PURE_QUANTA.SOCKET4677_AZIF0045P001C01CS(CHIPS)':
 'UPI1_TX_DN20': CDS_PINID='UPI1_TX_DN20';
NODE_NAME     U1 BL7
 '@S9S_MB_2U_LIB.S9S_MB_2U(SCH_1):PAGE63_I51@PURE_QUANTA.SOCKET4677_AZIF0045P001C01CS(CHIPS)':
 'UPI0_RX_DP20': CDS_PINID='UPI0_RX_DP20';
NET_NAME
'UPI_CPU0_CPU1_P1P0_DP<21>'
 '@S9S_MB_2U_LIB.S9S_MB_2U(SCH_1):UPI_CPU0_CPU1_P1P0_DP'<21>:
 C_SIGNAL='@s9s_mb_2u_lib.s9s_mb_2u(sch_1):upi_cpu0_cpu1_p1p0_dp(21)';
NODE_NAME     U2 CD6
 '@S9S_MB_2U_LIB.S9S_MB_2U(SCH_1):PAGE33_I102@PURE_QUANTA.SOCKET4677_AZIF0045P001C01CS(CHIPS)':
 'UPI1_TX_DN21': CDS_PINID='UPI1_TX_DN21';
NODE_NAME     U1 BM6
 '@S9S_MB_2U_LIB.S9S_MB_2U(SCH_1):PAGE63_I51@PURE_QUANTA.SOCKET4677_AZIF0045P001C01CS(CHIPS)':
 'UPI0_RX_DP21': CDS_PINID='UPI0_RX_DP21';
NET_NAME
'UPI_CPU0_CPU1_P1P0_DP<22>'
 '@S9S_MB_2U_LIB.S9S_MB_2U(SCH_1):UPI_CPU0_CPU1_P1P0_DP'<22>:
 C_SIGNAL='@s9s_mb_2u_lib.s9s_mb_2u(sch_1):upi_cpu0_cpu1_p1p0_dp(22)';
NODE_NAME     U2 CB6
 '@S9S_MB_2U_LIB.S9S_MB_2U(SCH_1):PAGE33_I102@PURE_QUANTA.SOCKET4677_AZIF0045P001C01CS(CHIPS)':
 'UPI1_TX_DP22': CDS_PINID='UPI1_TX_DP22';
NODE_NAME     U1 BP6
 '@S9S_MB_2U_LIB.S9S_MB_2U(SCH_1):PAGE63_I51@PURE_QUANTA.SOCKET4677_AZIF0045P001C01CS(CHIPS)':
 'UPI0_RX_DP22': CDS_PINID='UPI0_RX_DP22';
NET_NAME
'UPI_CPU0_CPU1_P1P0_DP<23>'
 '@S9S_MB_2U_LIB.S9S_MB_2U(SCH_1):UPI_CPU0_CPU1_P1P0_DP'<23>:
 C_SIGNAL='@s9s_mb_2u_lib.s9s_mb_2u(sch_1):upi_cpu0_cpu1_p1p0_dp(23)';
NODE_NAME     U2 BY6
 '@S9S_MB_2U_LIB.S9S_MB_2U(SCH_1):PAGE33_I102@PURE_QUANTA.SOCKET4677_AZIF0045P001C01CS(CHIPS)':
 'UPI1_TX_DN23': CDS_PINID='UPI1_TX_DN23';
NODE_NAME     U1 BT6
 '@S9S_MB_2U_LIB.S9S_MB_2U(SCH_1):PAGE63_I51@PURE_QUANTA.SOCKET4677_AZIF0045P001C01CS(CHIPS)':
 'UPI0_RX_DP23': CDS_PINID='UPI0_RX_DP23';
NET_NAME
'UPI_CPU0_CPU1_P1P0_DP<2>'
 '@S9S_MB_2U_LIB.S9S_MB_2U(SCH_1):UPI_CPU0_CPU1_P1P0_DP'<2>:
 C_SIGNAL='@s9s_mb_2u_lib.s9s_mb_2u(sch_1):upi_cpu0_cpu1_p1p0_dp(2)';
NODE_NAME     U2 EA5
 '@S9S_MB_2U_LIB.S9S_MB_2U(SCH_1):PAGE33_I102@PURE_QUANTA.SOCKET4677_AZIF0045P001C01CS(CHIPS)':
 'UPI1_TX_DP2': CDS_PINID='UPI1_TX_DP2';
NODE_NAME     U1 R7
 '@S9S_MB_2U_LIB.S9S_MB_2U(SCH_1):PAGE63_I51@PURE_QUANTA.SOCKET4677_AZIF0045P001C01CS(CHIPS)':
 'UPI0_RX_DP2': CDS_PINID='UPI0_RX_DP2';
NET_NAME
'UPI_CPU0_CPU1_P1P0_DP<3>'
 '@S9S_MB_2U_LIB.S9S_MB_2U(SCH_1):UPI_CPU0_CPU1_P1P0_DP'<3>:
 C_SIGNAL='@s9s_mb_2u_lib.s9s_mb_2u(sch_1):upi_cpu0_cpu1_p1p0_dp(3)';
NODE_NAME     U2 DY6
 '@S9S_MB_2U_LIB.S9S_MB_2U(SCH_1):PAGE33_I102@PURE_QUANTA.SOCKET4677_AZIF0045P001C01CS(CHIPS)':
 'UPI1_TX_DN3': CDS_PINID='UPI1_TX_DN3';
NODE_NAME     U1 T6
 '@S9S_MB_2U_LIB.S9S_MB_2U(SCH_1):PAGE63_I51@PURE_QUANTA.SOCKET4677_AZIF0045P001C01CS(CHIPS)':
 'UPI0_RX_DP3': CDS_PINID='UPI0_RX_DP3';
NET_NAME
'UPI_CPU0_CPU1_P1P0_DP<4>'
 '@S9S_MB_2U_LIB.S9S_MB_2U(SCH_1):UPI_CPU0_CPU1_P1P0_DP'<4>:
 C_SIGNAL='@s9s_mb_2u_lib.s9s_mb_2u(sch_1):upi_cpu0_cpu1_p1p0_dp(4)';
NODE_NAME     U2 DU5
 '@S9S_MB_2U_LIB.S9S_MB_2U(SCH_1):PAGE33_I102@PURE_QUANTA.SOCKET4677_AZIF0045P001C01CS(CHIPS)':
 'UPI1_TX_DP4': CDS_PINID='UPI1_TX_DP4';
NODE_NAME     U1 W7
 '@S9S_MB_2U_LIB.S9S_MB_2U(SCH_1):PAGE63_I51@PURE_QUANTA.SOCKET4677_AZIF0045P001C01CS(CHIPS)':
 'UPI0_RX_DP4': CDS_PINID='UPI0_RX_DP4';
NET_NAME
'UPI_CPU0_CPU1_P1P0_DP<5>'
 '@S9S_MB_2U_LIB.S9S_MB_2U(SCH_1):UPI_CPU0_CPU1_P1P0_DP'<5>:
 C_SIGNAL='@s9s_mb_2u_lib.s9s_mb_2u(sch_1):upi_cpu0_cpu1_p1p0_dp(5)';
NODE_NAME     U2 DT6
 '@S9S_MB_2U_LIB.S9S_MB_2U(SCH_1):PAGE33_I102@PURE_QUANTA.SOCKET4677_AZIF0045P001C01CS(CHIPS)':
 'UPI1_TX_DN5': CDS_PINID='UPI1_TX_DN5';
NODE_NAME     U1 Y6
 '@S9S_MB_2U_LIB.S9S_MB_2U(SCH_1):PAGE63_I51@PURE_QUANTA.SOCKET4677_AZIF0045P001C01CS(CHIPS)':
 'UPI0_RX_DP5': CDS_PINID='UPI0_RX_DP5';
NET_NAME
'UPI_CPU0_CPU1_P1P0_DP<6>'
 '@S9S_MB_2U_LIB.S9S_MB_2U(SCH_1):UPI_CPU0_CPU1_P1P0_DP'<6>:
 C_SIGNAL='@s9s_mb_2u_lib.s9s_mb_2u(sch_1):upi_cpu0_cpu1_p1p0_dp(6)';
NODE_NAME     U2 DN5
 '@S9S_MB_2U_LIB.S9S_MB_2U(SCH_1):PAGE33_I102@PURE_QUANTA.SOCKET4677_AZIF0045P001C01CS(CHIPS)':
 'UPI1_TX_DP6': CDS_PINID='UPI1_TX_DP6';
NODE_NAME     U1 AC7
 '@S9S_MB_2U_LIB.S9S_MB_2U(SCH_1):PAGE63_I51@PURE_QUANTA.SOCKET4677_AZIF0045P001C01CS(CHIPS)':
 'UPI0_RX_DP6': CDS_PINID='UPI0_RX_DP6';
NET_NAME
'UPI_CPU0_CPU1_P1P0_DP<7>'
 '@S9S_MB_2U_LIB.S9S_MB_2U(SCH_1):UPI_CPU0_CPU1_P1P0_DP'<7>:
 C_SIGNAL='@s9s_mb_2u_lib.s9s_mb_2u(sch_1):upi_cpu0_cpu1_p1p0_dp(7)';
NODE_NAME     U2 DM6
 '@S9S_MB_2U_LIB.S9S_MB_2U(SCH_1):PAGE33_I102@PURE_QUANTA.SOCKET4677_AZIF0045P001C01CS(CHIPS)':
 'UPI1_TX_DP7': CDS_PINID='UPI1_TX_DP7';
NODE_NAME     U1 AD6
 '@S9S_MB_2U_LIB.S9S_MB_2U(SCH_1):PAGE63_I51@PURE_QUANTA.SOCKET4677_AZIF0045P001C01CS(CHIPS)':
 'UPI0_RX_DP7': CDS_PINID='UPI0_RX_DP7';
NET_NAME
'UPI_CPU0_CPU1_P1P0_DP<8>'
 '@S9S_MB_2U_LIB.S9S_MB_2U(SCH_1):UPI_CPU0_CPU1_P1P0_DP'<8>:
 C_SIGNAL='@s9s_mb_2u_lib.s9s_mb_2u(sch_1):upi_cpu0_cpu1_p1p0_dp(8)';
NODE_NAME     U2 DJ5
 '@S9S_MB_2U_LIB.S9S_MB_2U(SCH_1):PAGE33_I102@PURE_QUANTA.SOCKET4677_AZIF0045P001C01CS(CHIPS)':
 'UPI1_TX_DP8': CDS_PINID='UPI1_TX_DP8';
NODE_NAME     U1 AG7
 '@S9S_MB_2U_LIB.S9S_MB_2U(SCH_1):PAGE63_I51@PURE_QUANTA.SOCKET4677_AZIF0045P001C01CS(CHIPS)':
 'UPI0_RX_DP8': CDS_PINID='UPI0_RX_DP8';
NET_NAME
'UPI_CPU0_CPU1_P1P0_DP<9>'
 '@S9S_MB_2U_LIB.S9S_MB_2U(SCH_1):UPI_CPU0_CPU1_P1P0_DP'<9>:
 C_SIGNAL='@s9s_mb_2u_lib.s9s_mb_2u(sch_1):upi_cpu0_cpu1_p1p0_dp(9)';
NODE_NAME     U2 DG7
 '@S9S_MB_2U_LIB.S9S_MB_2U(SCH_1):PAGE33_I102@PURE_QUANTA.SOCKET4677_AZIF0045P001C01CS(CHIPS)':
 'UPI1_TX_DP9': CDS_PINID='UPI1_TX_DP9';
NODE_NAME     U1 AJ5
 '@S9S_MB_2U_LIB.S9S_MB_2U(SCH_1):PAGE63_I51@PURE_QUANTA.SOCKET4677_AZIF0045P001C01CS(CHIPS)':
 'UPI0_RX_DP9': CDS_PINID='UPI0_RX_DP9';
NET_NAME
'UPI_CPU0_CPU1_P2P2_DN<0>'
 '@S9S_MB_2U_LIB.S9S_MB_2U(SCH_1):UPI_CPU0_CPU1_P2P2_DN'<0>:
 C_SIGNAL='@s9s_mb_2u_lib.s9s_mb_2u(sch_1):upi_cpu0_cpu1_p2p2_dn(0)';
NODE_NAME     U2 BM71
 '@S9S_MB_2U_LIB.S9S_MB_2U(SCH_1):PAGE34_I102@PURE_QUANTA.SOCKET4677_AZIF0045P001C01CS(CHIPS)':
 'UPI2_TX_DN23': CDS_PINID='UPI2_TX_DN23';
NODE_NAME     U1 E80
 '@S9S_MB_2U_LIB.S9S_MB_2U(SCH_1):PAGE65_I16@PURE_QUANTA.SOCKET4677_AZIF0045P001C01CS(CHIPS)':
 'UPI2_RX_DN0': CDS_PINID='UPI2_RX_DN0';
NET_NAME
'UPI_CPU0_CPU1_P2P2_DN<10>'
 '@S9S_MB_2U_LIB.S9S_MB_2U(SCH_1):UPI_CPU0_CPU1_P2P2_DN'<10>:
 C_SIGNAL='@s9s_mb_2u_lib.s9s_mb_2u(sch_1):upi_cpu0_cpu1_p2p2_dn(10)';
NODE_NAME     U2 AN82
 '@S9S_MB_2U_LIB.S9S_MB_2U(SCH_1):PAGE34_I102@PURE_QUANTA.SOCKET4677_AZIF0045P001C01CS(CHIPS)':
 'UPI2_TX_DN13': CDS_PINID='UPI2_TX_DN13';
NODE_NAME     U1 AJ80
 '@S9S_MB_2U_LIB.S9S_MB_2U(SCH_1):PAGE65_I16@PURE_QUANTA.SOCKET4677_AZIF0045P001C01CS(CHIPS)':
 'UPI2_RX_DN10': CDS_PINID='UPI2_RX_DN10';
NET_NAME
'UPI_CPU0_CPU1_P2P2_DN<11>'
 '@S9S_MB_2U_LIB.S9S_MB_2U(SCH_1):UPI_CPU0_CPU1_P2P2_DN'<11>:
 C_SIGNAL='@s9s_mb_2u_lib.s9s_mb_2u(sch_1):upi_cpu0_cpu1_p2p2_dn(11)';
NODE_NAME     U2 AM81
 '@S9S_MB_2U_LIB.S9S_MB_2U(SCH_1):PAGE34_I102@PURE_QUANTA.SOCKET4677_AZIF0045P001C01CS(CHIPS)':
 'UPI2_TX_DN12': CDS_PINID='UPI2_TX_DN12';
NODE_NAME     U1 AG82
 '@S9S_MB_2U_LIB.S9S_MB_2U(SCH_1):PAGE65_I16@PURE_QUANTA.SOCKET4677_AZIF0045P001C01CS(CHIPS)':
 'UPI2_RX_DN11': CDS_PINID='UPI2_RX_DN11';
NET_NAME
'UPI_CPU0_CPU1_P2P2_DN<12>'
 '@S9S_MB_2U_LIB.S9S_MB_2U(SCH_1):UPI_CPU0_CPU1_P2P2_DN'<12>:
 C_SIGNAL='@s9s_mb_2u_lib.s9s_mb_2u(sch_1):upi_cpu0_cpu1_p2p2_dn(12)';
NODE_NAME     U2 AU78
 '@S9S_MB_2U_LIB.S9S_MB_2U(SCH_1):PAGE34_I102@PURE_QUANTA.SOCKET4677_AZIF0045P001C01CS(CHIPS)':
 'UPI2_TX_DN11': CDS_PINID='UPI2_TX_DN11';
NODE_NAME     U1 BA72
 '@S9S_MB_2U_LIB.S9S_MB_2U(SCH_1):PAGE65_I16@PURE_QUANTA.SOCKET4677_AZIF0045P001C01CS(CHIPS)':
 'UPI2_RX_DN12': CDS_PINID='UPI2_RX_DN12';
NET_NAME
'UPI_CPU0_CPU1_P2P2_DN<13>'
 '@S9S_MB_2U_LIB.S9S_MB_2U(SCH_1):UPI_CPU0_CPU1_P2P2_DN'<13>:
 C_SIGNAL='@s9s_mb_2u_lib.s9s_mb_2u(sch_1):upi_cpu0_cpu1_p2p2_dn(13)';
NODE_NAME     U2 AW78
 '@S9S_MB_2U_LIB.S9S_MB_2U(SCH_1):PAGE34_I102@PURE_QUANTA.SOCKET4677_AZIF0045P001C01CS(CHIPS)':
 'UPI2_TX_DN10': CDS_PINID='UPI2_TX_DN10';
NODE_NAME     U1 AV73
 '@S9S_MB_2U_LIB.S9S_MB_2U(SCH_1):PAGE65_I16@PURE_QUANTA.SOCKET4677_AZIF0045P001C01CS(CHIPS)':
 'UPI2_RX_DN13': CDS_PINID='UPI2_RX_DN13';
NET_NAME
'UPI_CPU0_CPU1_P2P2_DN<14>'
 '@S9S_MB_2U_LIB.S9S_MB_2U(SCH_1):UPI_CPU0_CPU1_P2P2_DN'<14>:
 C_SIGNAL='@s9s_mb_2u_lib.s9s_mb_2u(sch_1):upi_cpu0_cpu1_p2p2_dn(14)';
NODE_NAME     U2 Y81
 '@S9S_MB_2U_LIB.S9S_MB_2U(SCH_1):PAGE34_I102@PURE_QUANTA.SOCKET4677_AZIF0045P001C01CS(CHIPS)':
 'UPI2_TX_DN9': CDS_PINID='UPI2_TX_DN9';
NODE_NAME     U1 AY75
 '@S9S_MB_2U_LIB.S9S_MB_2U(SCH_1):PAGE65_I16@PURE_QUANTA.SOCKET4677_AZIF0045P001C01CS(CHIPS)':
 'UPI2_RX_DN14': CDS_PINID='UPI2_RX_DN14';
NET_NAME
'UPI_CPU0_CPU1_P2P2_DN<15>'
 '@S9S_MB_2U_LIB.S9S_MB_2U(SCH_1):UPI_CPU0_CPU1_P2P2_DN'<15>:
 C_SIGNAL='@s9s_mb_2u_lib.s9s_mb_2u(sch_1):upi_cpu0_cpu1_p2p2_dn(15)';
NODE_NAME     U2 V83
 '@S9S_MB_2U_LIB.S9S_MB_2U(SCH_1):PAGE34_I102@PURE_QUANTA.SOCKET4677_AZIF0045P001C01CS(CHIPS)':
 'UPI2_TX_DN8': CDS_PINID='UPI2_TX_DN8';
NODE_NAME     U1 BB75
 '@S9S_MB_2U_LIB.S9S_MB_2U(SCH_1):PAGE65_I16@PURE_QUANTA.SOCKET4677_AZIF0045P001C01CS(CHIPS)':
 'UPI2_RX_DN15': CDS_PINID='UPI2_RX_DN15';
NET_NAME
'UPI_CPU0_CPU1_P2P2_DN<16>'
 '@S9S_MB_2U_LIB.S9S_MB_2U(SCH_1):UPI_CPU0_CPU1_P2P2_DN'<16>:
 C_SIGNAL='@s9s_mb_2u_lib.s9s_mb_2u(sch_1):upi_cpu0_cpu1_p2p2_dn(16)';
NODE_NAME     U2 U80
 '@S9S_MB_2U_LIB.S9S_MB_2U(SCH_1):PAGE34_I102@PURE_QUANTA.SOCKET4677_AZIF0045P001C01CS(CHIPS)':
 'UPI2_TX_DN7': CDS_PINID='UPI2_TX_DN7';
NODE_NAME     U1 AW74
 '@S9S_MB_2U_LIB.S9S_MB_2U(SCH_1):PAGE65_I16@PURE_QUANTA.SOCKET4677_AZIF0045P001C01CS(CHIPS)':
 'UPI2_RX_DN16': CDS_PINID='UPI2_RX_DN16';
NET_NAME
'UPI_CPU0_CPU1_P2P2_DN<17>'
 '@S9S_MB_2U_LIB.S9S_MB_2U(SCH_1):UPI_CPU0_CPU1_P2P2_DN'<17>:
 C_SIGNAL='@s9s_mb_2u_lib.s9s_mb_2u(sch_1):upi_cpu0_cpu1_p2p2_dn(17)';
NODE_NAME     U2 R82
 '@S9S_MB_2U_LIB.S9S_MB_2U(SCH_1):PAGE34_I102@PURE_QUANTA.SOCKET4677_AZIF0045P001C01CS(CHIPS)':
 'UPI2_TX_DN6': CDS_PINID='UPI2_TX_DN6';
NODE_NAME     U1 BH75
 '@S9S_MB_2U_LIB.S9S_MB_2U(SCH_1):PAGE65_I16@PURE_QUANTA.SOCKET4677_AZIF0045P001C01CS(CHIPS)':
 'UPI2_RX_DN17': CDS_PINID='UPI2_RX_DN17';
NET_NAME
'UPI_CPU0_CPU1_P2P2_DN<18>'
 '@S9S_MB_2U_LIB.S9S_MB_2U(SCH_1):UPI_CPU0_CPU1_P2P2_DN'<18>:
 C_SIGNAL='@s9s_mb_2u_lib.s9s_mb_2u(sch_1):upi_cpu0_cpu1_p2p2_dn(18)';
NODE_NAME     U2 P81
 '@S9S_MB_2U_LIB.S9S_MB_2U(SCH_1):PAGE34_I102@PURE_QUANTA.SOCKET4677_AZIF0045P001C01CS(CHIPS)':
 'UPI2_TX_DN5': CDS_PINID='UPI2_TX_DN5';
NODE_NAME     U1 BJ76
 '@S9S_MB_2U_LIB.S9S_MB_2U(SCH_1):PAGE65_I16@PURE_QUANTA.SOCKET4677_AZIF0045P001C01CS(CHIPS)':
 'UPI2_RX_DN18': CDS_PINID='UPI2_RX_DN18';
NET_NAME
'UPI_CPU0_CPU1_P2P2_DN<19>'
 '@S9S_MB_2U_LIB.S9S_MB_2U(SCH_1):UPI_CPU0_CPU1_P2P2_DN'<19>:
 C_SIGNAL='@s9s_mb_2u_lib.s9s_mb_2u(sch_1):upi_cpu0_cpu1_p2p2_dn(19)';
NODE_NAME     U2 H85
 '@S9S_MB_2U_LIB.S9S_MB_2U(SCH_1):PAGE34_I102@PURE_QUANTA.SOCKET4677_AZIF0045P001C01CS(CHIPS)':
 'UPI2_TX_DN4': CDS_PINID='UPI2_TX_DN4';
NODE_NAME     U1 BL76
 '@S9S_MB_2U_LIB.S9S_MB_2U(SCH_1):PAGE65_I16@PURE_QUANTA.SOCKET4677_AZIF0045P001C01CS(CHIPS)':
 'UPI2_RX_DN19': CDS_PINID='UPI2_RX_DN19';
NET_NAME
'UPI_CPU0_CPU1_P2P2_DN<1>'
 '@S9S_MB_2U_LIB.S9S_MB_2U(SCH_1):UPI_CPU0_CPU1_P2P2_DN'<1>:
 C_SIGNAL='@s9s_mb_2u_lib.s9s_mb_2u(sch_1):upi_cpu0_cpu1_p2p2_dn(1)';
NODE_NAME     U2 BG80
 '@S9S_MB_2U_LIB.S9S_MB_2U(SCH_1):PAGE34_I102@PURE_QUANTA.SOCKET4677_AZIF0045P001C01CS(CHIPS)':
 'UPI2_TX_DN22': CDS_PINID='UPI2_TX_DN22';
NODE_NAME     U1 F81
 '@S9S_MB_2U_LIB.S9S_MB_2U(SCH_1):PAGE65_I16@PURE_QUANTA.SOCKET4677_AZIF0045P001C01CS(CHIPS)':
 'UPI2_RX_DN1': CDS_PINID='UPI2_RX_DN1';
NET_NAME
'UPI_CPU0_CPU1_P2P2_DN<20>'
 '@S9S_MB_2U_LIB.S9S_MB_2U(SCH_1):UPI_CPU0_CPU1_P2P2_DN'<20>:
 C_SIGNAL='@s9s_mb_2u_lib.s9s_mb_2u(sch_1):upi_cpu0_cpu1_p2p2_dn(20)';
NODE_NAME     U2 F87
 '@S9S_MB_2U_LIB.S9S_MB_2U(SCH_1):PAGE34_I102@PURE_QUANTA.SOCKET4677_AZIF0045P001C01CS(CHIPS)':
 'UPI2_TX_DN3': CDS_PINID='UPI2_TX_DN3';
NODE_NAME     U1 BG74
 '@S9S_MB_2U_LIB.S9S_MB_2U(SCH_1):PAGE65_I16@PURE_QUANTA.SOCKET4677_AZIF0045P001C01CS(CHIPS)':
 'UPI2_RX_DN20': CDS_PINID='UPI2_RX_DN20';
NET_NAME
'UPI_CPU0_CPU1_P2P2_DN<21>'
 '@S9S_MB_2U_LIB.S9S_MB_2U(SCH_1):UPI_CPU0_CPU1_P2P2_DN'<21>:
 C_SIGNAL='@s9s_mb_2u_lib.s9s_mb_2u(sch_1):upi_cpu0_cpu1_p2p2_dn(21)';
NODE_NAME     U2 D87
 '@S9S_MB_2U_LIB.S9S_MB_2U(SCH_1):PAGE34_I102@PURE_QUANTA.SOCKET4677_AZIF0045P001C01CS(CHIPS)':
 'UPI2_TX_DN2': CDS_PINID='UPI2_TX_DN2';
NODE_NAME     U1 BN74
 '@S9S_MB_2U_LIB.S9S_MB_2U(SCH_1):PAGE65_I16@PURE_QUANTA.SOCKET4677_AZIF0045P001C01CS(CHIPS)':
 'UPI2_RX_DN21': CDS_PINID='UPI2_RX_DN21';
NET_NAME
'UPI_CPU0_CPU1_P2P2_DN<22>'
 '@S9S_MB_2U_LIB.S9S_MB_2U(SCH_1):UPI_CPU0_CPU1_P2P2_DN'<22>:
 C_SIGNAL='@s9s_mb_2u_lib.s9s_mb_2u(sch_1):upi_cpu0_cpu1_p2p2_dn(22)';
NODE_NAME     U2 E84
 '@S9S_MB_2U_LIB.S9S_MB_2U(SCH_1):PAGE34_I102@PURE_QUANTA.SOCKET4677_AZIF0045P001C01CS(CHIPS)':
 'UPI2_TX_DN1': CDS_PINID='UPI2_TX_DN1';
NODE_NAME     U1 BK73
 '@S9S_MB_2U_LIB.S9S_MB_2U(SCH_1):PAGE65_I16@PURE_QUANTA.SOCKET4677_AZIF0045P001C01CS(CHIPS)':
 'UPI2_RX_DN22': CDS_PINID='UPI2_RX_DN22';
NET_NAME
'UPI_CPU0_CPU1_P2P2_DN<23>'
 '@S9S_MB_2U_LIB.S9S_MB_2U(SCH_1):UPI_CPU0_CPU1_P2P2_DN'<23>:
 C_SIGNAL='@s9s_mb_2u_lib.s9s_mb_2u(sch_1):upi_cpu0_cpu1_p2p2_dn(23)';
NODE_NAME     U2 B85
 '@S9S_MB_2U_LIB.S9S_MB_2U(SCH_1):PAGE34_I102@PURE_QUANTA.SOCKET4677_AZIF0045P001C01CS(CHIPS)':
 'UPI2_TX_DN0': CDS_PINID='UPI2_TX_DN0';
NODE_NAME     U1 BD73
 '@S9S_MB_2U_LIB.S9S_MB_2U(SCH_1):PAGE65_I16@PURE_QUANTA.SOCKET4677_AZIF0045P001C01CS(CHIPS)':
 'UPI2_RX_DN23': CDS_PINID='UPI2_RX_DN23';
NET_NAME
'UPI_CPU0_CPU1_P2P2_DN<2>'
 '@S9S_MB_2U_LIB.S9S_MB_2U(SCH_1):UPI_CPU0_CPU1_P2P2_DN'<2>:
 C_SIGNAL='@s9s_mb_2u_lib.s9s_mb_2u(sch_1):upi_cpu0_cpu1_p2p2_dn(2)';
NODE_NAME     U2 BF81
 '@S9S_MB_2U_LIB.S9S_MB_2U(SCH_1):PAGE34_I102@PURE_QUANTA.SOCKET4677_AZIF0045P001C01CS(CHIPS)':
 'UPI2_TX_DN21': CDS_PINID='UPI2_TX_DN21';
NODE_NAME     U1 G82
 '@S9S_MB_2U_LIB.S9S_MB_2U(SCH_1):PAGE65_I16@PURE_QUANTA.SOCKET4677_AZIF0045P001C01CS(CHIPS)':
 'UPI2_RX_DN2': CDS_PINID='UPI2_RX_DN2';
NET_NAME
'UPI_CPU0_CPU1_P2P2_DN<3>'
 '@S9S_MB_2U_LIB.S9S_MB_2U(SCH_1):UPI_CPU0_CPU1_P2P2_DN'<3>:
 C_SIGNAL='@s9s_mb_2u_lib.s9s_mb_2u(sch_1):upi_cpu0_cpu1_p2p2_dn(3)';
NODE_NAME     U2 BD79
 '@S9S_MB_2U_LIB.S9S_MB_2U(SCH_1):PAGE34_I102@PURE_QUANTA.SOCKET4677_AZIF0045P001C01CS(CHIPS)':
 'UPI2_TX_DN20': CDS_PINID='UPI2_TX_DN20';
NODE_NAME     U1 K79
 '@S9S_MB_2U_LIB.S9S_MB_2U(SCH_1):PAGE65_I16@PURE_QUANTA.SOCKET4677_AZIF0045P001C01CS(CHIPS)':
 'UPI2_RX_DN3': CDS_PINID='UPI2_RX_DN3';
NET_NAME
'UPI_CPU0_CPU1_P2P2_DN<4>'
 '@S9S_MB_2U_LIB.S9S_MB_2U(SCH_1):UPI_CPU0_CPU1_P2P2_DN'<4>:
 C_SIGNAL='@s9s_mb_2u_lib.s9s_mb_2u(sch_1):upi_cpu0_cpu1_p2p2_dn(4)';
NODE_NAME     U2 BE82
 '@S9S_MB_2U_LIB.S9S_MB_2U(SCH_1):PAGE34_I102@PURE_QUANTA.SOCKET4677_AZIF0045P001C01CS(CHIPS)':
 'UPI2_TX_DN19': CDS_PINID='UPI2_TX_DN19';
NODE_NAME     U1 J82
 '@S9S_MB_2U_LIB.S9S_MB_2U(SCH_1):PAGE65_I16@PURE_QUANTA.SOCKET4677_AZIF0045P001C01CS(CHIPS)':
 'UPI2_RX_DN4': CDS_PINID='UPI2_RX_DN4';
NET_NAME
'UPI_CPU0_CPU1_P2P2_DN<5>'
 '@S9S_MB_2U_LIB.S9S_MB_2U(SCH_1):UPI_CPU0_CPU1_P2P2_DN'<5>:
 C_SIGNAL='@s9s_mb_2u_lib.s9s_mb_2u(sch_1):upi_cpu0_cpu1_p2p2_dn(5)';
NODE_NAME     U2 BC82
 '@S9S_MB_2U_LIB.S9S_MB_2U(SCH_1):PAGE34_I102@PURE_QUANTA.SOCKET4677_AZIF0045P001C01CS(CHIPS)':
 'UPI2_TX_DN18': CDS_PINID='UPI2_TX_DN18';
NODE_NAME     U1 L80
 '@S9S_MB_2U_LIB.S9S_MB_2U(SCH_1):PAGE65_I16@PURE_QUANTA.SOCKET4677_AZIF0045P001C01CS(CHIPS)':
 'UPI2_RX_DN5': CDS_PINID='UPI2_RX_DN5';
NET_NAME
'UPI_CPU0_CPU1_P2P2_DN<6>'
 '@S9S_MB_2U_LIB.S9S_MB_2U(SCH_1):UPI_CPU0_CPU1_P2P2_DN'<6>:
 C_SIGNAL='@s9s_mb_2u_lib.s9s_mb_2u(sch_1):upi_cpu0_cpu1_p2p2_dn(6)';
NODE_NAME     U2 BA80
 '@S9S_MB_2U_LIB.S9S_MB_2U(SCH_1):PAGE34_I102@PURE_QUANTA.SOCKET4677_AZIF0045P001C01CS(CHIPS)':
 'UPI2_TX_DN17': CDS_PINID='UPI2_TX_DN17';
NODE_NAME     U1 AC80
 '@S9S_MB_2U_LIB.S9S_MB_2U(SCH_1):PAGE65_I16@PURE_QUANTA.SOCKET4677_AZIF0045P001C01CS(CHIPS)':
 'UPI2_RX_DN6': CDS_PINID='UPI2_RX_DN6';
NET_NAME
'UPI_CPU0_CPU1_P2P2_DN<7>'
 '@S9S_MB_2U_LIB.S9S_MB_2U(SCH_1):UPI_CPU0_CPU1_P2P2_DN'<7>:
 C_SIGNAL='@s9s_mb_2u_lib.s9s_mb_2u(sch_1):upi_cpu0_cpu1_p2p2_dn(7)';
NODE_NAME     U2 AV81
 '@S9S_MB_2U_LIB.S9S_MB_2U(SCH_1):PAGE34_I102@PURE_QUANTA.SOCKET4677_AZIF0045P001C01CS(CHIPS)':
 'UPI2_TX_DN16': CDS_PINID='UPI2_TX_DN16';
NODE_NAME     U1 AD81
 '@S9S_MB_2U_LIB.S9S_MB_2U(SCH_1):PAGE65_I16@PURE_QUANTA.SOCKET4677_AZIF0045P001C01CS(CHIPS)':
 'UPI2_RX_DN7': CDS_PINID='UPI2_RX_DN7';
NET_NAME
'UPI_CPU0_CPU1_P2P2_DN<8>'
 '@S9S_MB_2U_LIB.S9S_MB_2U(SCH_1):UPI_CPU0_CPU1_P2P2_DN'<8>:
 C_SIGNAL='@s9s_mb_2u_lib.s9s_mb_2u(sch_1):upi_cpu0_cpu1_p2p2_dn(8)';
NODE_NAME     U2 AT83
 '@S9S_MB_2U_LIB.S9S_MB_2U(SCH_1):PAGE34_I102@PURE_QUANTA.SOCKET4677_AZIF0045P001C01CS(CHIPS)':
 'UPI2_TX_DN15': CDS_PINID='UPI2_TX_DN15';
NODE_NAME     U1 AF79
 '@S9S_MB_2U_LIB.S9S_MB_2U(SCH_1):PAGE65_I16@PURE_QUANTA.SOCKET4677_AZIF0045P001C01CS(CHIPS)':
 'UPI2_RX_DN8': CDS_PINID='UPI2_RX_DN8';
NET_NAME
'UPI_CPU0_CPU1_P2P2_DN<9>'
 '@S9S_MB_2U_LIB.S9S_MB_2U(SCH_1):UPI_CPU0_CPU1_P2P2_DN'<9>:
 C_SIGNAL='@s9s_mb_2u_lib.s9s_mb_2u(sch_1):upi_cpu0_cpu1_p2p2_dn(9)';
NODE_NAME     U2 AR80
 '@S9S_MB_2U_LIB.S9S_MB_2U(SCH_1):PAGE34_I102@PURE_QUANTA.SOCKET4677_AZIF0045P001C01CS(CHIPS)':
 'UPI2_TX_DN14': CDS_PINID='UPI2_TX_DN14';
NODE_NAME     U1 AE82
 '@S9S_MB_2U_LIB.S9S_MB_2U(SCH_1):PAGE65_I16@PURE_QUANTA.SOCKET4677_AZIF0045P001C01CS(CHIPS)':
 'UPI2_RX_DN9': CDS_PINID='UPI2_RX_DN9';
NET_NAME
'UPI_CPU0_CPU1_P2P2_DP<0>'
 '@S9S_MB_2U_LIB.S9S_MB_2U(SCH_1):UPI_CPU0_CPU1_P2P2_DP'<0>:
 C_SIGNAL='@s9s_mb_2u_lib.s9s_mb_2u(sch_1):upi_cpu0_cpu1_p2p2_dp(0)';
NODE_NAME     U2 BN72
 '@S9S_MB_2U_LIB.S9S_MB_2U(SCH_1):PAGE34_I102@PURE_QUANTA.SOCKET4677_AZIF0045P001C01CS(CHIPS)':
 'UPI2_TX_DP23': CDS_PINID='UPI2_TX_DP23';
NODE_NAME     U1 G80
 '@S9S_MB_2U_LIB.S9S_MB_2U(SCH_1):PAGE65_I16@PURE_QUANTA.SOCKET4677_AZIF0045P001C01CS(CHIPS)':
 'UPI2_RX_DP0': CDS_PINID='UPI2_RX_DP0';
NET_NAME
'UPI_CPU0_CPU1_P2P2_DP<10>'
 '@S9S_MB_2U_LIB.S9S_MB_2U(SCH_1):UPI_CPU0_CPU1_P2P2_DP'<10>:
 C_SIGNAL='@s9s_mb_2u_lib.s9s_mb_2u(sch_1):upi_cpu0_cpu1_p2p2_dp(10)';
NODE_NAME     U2 AM83
 '@S9S_MB_2U_LIB.S9S_MB_2U(SCH_1):PAGE34_I102@PURE_QUANTA.SOCKET4677_AZIF0045P001C01CS(CHIPS)':
 'UPI2_TX_DP13': CDS_PINID='UPI2_TX_DP13';
NODE_NAME     U1 AH81
 '@S9S_MB_2U_LIB.S9S_MB_2U(SCH_1):PAGE65_I16@PURE_QUANTA.SOCKET4677_AZIF0045P001C01CS(CHIPS)':
 'UPI2_RX_DP10': CDS_PINID='UPI2_RX_DP10';
NET_NAME
'UPI_CPU0_CPU1_P2P2_DP<11>'
 '@S9S_MB_2U_LIB.S9S_MB_2U(SCH_1):UPI_CPU0_CPU1_P2P2_DP'<11>:
 C_SIGNAL='@s9s_mb_2u_lib.s9s_mb_2u(sch_1):upi_cpu0_cpu1_p2p2_dp(11)';
NODE_NAME     U2 AP81
 '@S9S_MB_2U_LIB.S9S_MB_2U(SCH_1):PAGE34_I102@PURE_QUANTA.SOCKET4677_AZIF0045P001C01CS(CHIPS)':
 'UPI2_TX_DP12': CDS_PINID='UPI2_TX_DP12';
NODE_NAME     U1 AJ82
 '@S9S_MB_2U_LIB.S9S_MB_2U(SCH_1):PAGE65_I16@PURE_QUANTA.SOCKET4677_AZIF0045P001C01CS(CHIPS)':
 'UPI2_RX_DP11': CDS_PINID='UPI2_RX_DP11';
NET_NAME
'UPI_CPU0_CPU1_P2P2_DP<12>'
 '@S9S_MB_2U_LIB.S9S_MB_2U(SCH_1):UPI_CPU0_CPU1_P2P2_DP'<12>:
 C_SIGNAL='@s9s_mb_2u_lib.s9s_mb_2u(sch_1):upi_cpu0_cpu1_p2p2_dp(12)';
NODE_NAME     U2 AV79
 '@S9S_MB_2U_LIB.S9S_MB_2U(SCH_1):PAGE34_I102@PURE_QUANTA.SOCKET4677_AZIF0045P001C01CS(CHIPS)':
 'UPI2_TX_DP11': CDS_PINID='UPI2_TX_DP11';
NODE_NAME     U1 BB73
 '@S9S_MB_2U_LIB.S9S_MB_2U(SCH_1):PAGE65_I16@PURE_QUANTA.SOCKET4677_AZIF0045P001C01CS(CHIPS)':
 'UPI2_RX_DP12': CDS_PINID='UPI2_RX_DP12';
NET_NAME
'UPI_CPU0_CPU1_P2P2_DP<13>'
 '@S9S_MB_2U_LIB.S9S_MB_2U(SCH_1):UPI_CPU0_CPU1_P2P2_DP'<13>:
 C_SIGNAL='@s9s_mb_2u_lib.s9s_mb_2u(sch_1):upi_cpu0_cpu1_p2p2_dp(13)';
NODE_NAME     U2 BA78
 '@S9S_MB_2U_LIB.S9S_MB_2U(SCH_1):PAGE34_I102@PURE_QUANTA.SOCKET4677_AZIF0045P001C01CS(CHIPS)':
 'UPI2_TX_DP10': CDS_PINID='UPI2_TX_DP10';
NODE_NAME     U1 AY73
 '@S9S_MB_2U_LIB.S9S_MB_2U(SCH_1):PAGE65_I16@PURE_QUANTA.SOCKET4677_AZIF0045P001C01CS(CHIPS)':
 'UPI2_RX_DP13': CDS_PINID='UPI2_RX_DP13';
NET_NAME
'UPI_CPU0_CPU1_P2P2_DP<14>'
 '@S9S_MB_2U_LIB.S9S_MB_2U(SCH_1):UPI_CPU0_CPU1_P2P2_DP'<14>:
 C_SIGNAL='@s9s_mb_2u_lib.s9s_mb_2u(sch_1):upi_cpu0_cpu1_p2p2_dp(14)';
NODE_NAME     U2 W82
 '@S9S_MB_2U_LIB.S9S_MB_2U(SCH_1):PAGE34_I102@PURE_QUANTA.SOCKET4677_AZIF0045P001C01CS(CHIPS)':
 'UPI2_TX_DP9': CDS_PINID='UPI2_TX_DP9';
NODE_NAME     U1 BA76
 '@S9S_MB_2U_LIB.S9S_MB_2U(SCH_1):PAGE65_I16@PURE_QUANTA.SOCKET4677_AZIF0045P001C01CS(CHIPS)':
 'UPI2_RX_DP14': CDS_PINID='UPI2_RX_DP14';
NET_NAME
'UPI_CPU0_CPU1_P2P2_DP<15>'
 '@S9S_MB_2U_LIB.S9S_MB_2U(SCH_1):UPI_CPU0_CPU1_P2P2_DP'<15>:
 C_SIGNAL='@s9s_mb_2u_lib.s9s_mb_2u(sch_1):upi_cpu0_cpu1_p2p2_dp(15)';
NODE_NAME     U2 Y83
 '@S9S_MB_2U_LIB.S9S_MB_2U(SCH_1):PAGE34_I102@PURE_QUANTA.SOCKET4677_AZIF0045P001C01CS(CHIPS)':
 'UPI2_TX_DP8': CDS_PINID='UPI2_TX_DP8';
NODE_NAME     U1 BD75
 '@S9S_MB_2U_LIB.S9S_MB_2U(SCH_1):PAGE65_I16@PURE_QUANTA.SOCKET4677_AZIF0045P001C01CS(CHIPS)':
 'UPI2_RX_DP15': CDS_PINID='UPI2_RX_DP15';
NET_NAME
'UPI_CPU0_CPU1_P2P2_DP<16>'
 '@S9S_MB_2U_LIB.S9S_MB_2U(SCH_1):UPI_CPU0_CPU1_P2P2_DP'<16>:
 C_SIGNAL='@s9s_mb_2u_lib.s9s_mb_2u(sch_1):upi_cpu0_cpu1_p2p2_dp(16)';
NODE_NAME     U2 V81
 '@S9S_MB_2U_LIB.S9S_MB_2U(SCH_1):PAGE34_I102@PURE_QUANTA.SOCKET4677_AZIF0045P001C01CS(CHIPS)':
 'UPI2_TX_DP7': CDS_PINID='UPI2_TX_DP7';
NODE_NAME     U1 AV75
 '@S9S_MB_2U_LIB.S9S_MB_2U(SCH_1):PAGE65_I16@PURE_QUANTA.SOCKET4677_AZIF0045P001C01CS(CHIPS)':
 'UPI2_RX_DP16': CDS_PINID='UPI2_RX_DP16';
NET_NAME
'UPI_CPU0_CPU1_P2P2_DP<17>'
 '@S9S_MB_2U_LIB.S9S_MB_2U(SCH_1):UPI_CPU0_CPU1_P2P2_DP'<17>:
 C_SIGNAL='@s9s_mb_2u_lib.s9s_mb_2u(sch_1):upi_cpu0_cpu1_p2p2_dp(17)';
NODE_NAME     U2 P83
 '@S9S_MB_2U_LIB.S9S_MB_2U(SCH_1):PAGE34_I102@PURE_QUANTA.SOCKET4677_AZIF0045P001C01CS(CHIPS)':
 'UPI2_TX_DP6': CDS_PINID='UPI2_TX_DP6';
NODE_NAME     U1 BG76
 '@S9S_MB_2U_LIB.S9S_MB_2U(SCH_1):PAGE65_I16@PURE_QUANTA.SOCKET4677_AZIF0045P001C01CS(CHIPS)':
 'UPI2_RX_DP17': CDS_PINID='UPI2_RX_DP17';
NET_NAME
'UPI_CPU0_CPU1_P2P2_DP<18>'
 '@S9S_MB_2U_LIB.S9S_MB_2U(SCH_1):UPI_CPU0_CPU1_P2P2_DP'<18>:
 C_SIGNAL='@s9s_mb_2u_lib.s9s_mb_2u(sch_1):upi_cpu0_cpu1_p2p2_dp(18)';
NODE_NAME     U2 T81
 '@S9S_MB_2U_LIB.S9S_MB_2U(SCH_1):PAGE34_I102@PURE_QUANTA.SOCKET4677_AZIF0045P001C01CS(CHIPS)':
 'UPI2_TX_DP5': CDS_PINID='UPI2_TX_DP5';
NODE_NAME     U1 BK77
 '@S9S_MB_2U_LIB.S9S_MB_2U(SCH_1):PAGE65_I16@PURE_QUANTA.SOCKET4677_AZIF0045P001C01CS(CHIPS)':
 'UPI2_RX_DP18': CDS_PINID='UPI2_RX_DP18';
NET_NAME
'UPI_CPU0_CPU1_P2P2_DP<19>'
 '@S9S_MB_2U_LIB.S9S_MB_2U(SCH_1):UPI_CPU0_CPU1_P2P2_DP'<19>:
 C_SIGNAL='@s9s_mb_2u_lib.s9s_mb_2u(sch_1):upi_cpu0_cpu1_p2p2_dp(19)';
NODE_NAME     U2 G86
 '@S9S_MB_2U_LIB.S9S_MB_2U(SCH_1):PAGE34_I102@PURE_QUANTA.SOCKET4677_AZIF0045P001C01CS(CHIPS)':
 'UPI2_TX_DP4': CDS_PINID='UPI2_TX_DP4';
NODE_NAME     U1 BN76
 '@S9S_MB_2U_LIB.S9S_MB_2U(SCH_1):PAGE65_I16@PURE_QUANTA.SOCKET4677_AZIF0045P001C01CS(CHIPS)':
 'UPI2_RX_DP19': CDS_PINID='UPI2_RX_DP19';
NET_NAME
'UPI_CPU0_CPU1_P2P2_DP<1>'
 '@S9S_MB_2U_LIB.S9S_MB_2U(SCH_1):UPI_CPU0_CPU1_P2P2_DP'<1>:
 C_SIGNAL='@s9s_mb_2u_lib.s9s_mb_2u(sch_1):upi_cpu0_cpu1_p2p2_dp(1)';
NODE_NAME     U2 BE80
 '@S9S_MB_2U_LIB.S9S_MB_2U(SCH_1):PAGE34_I102@PURE_QUANTA.SOCKET4677_AZIF0045P001C01CS(CHIPS)':
 'UPI2_TX_DP22': CDS_PINID='UPI2_TX_DP22';
NODE_NAME     U1 E82
 '@S9S_MB_2U_LIB.S9S_MB_2U(SCH_1):PAGE65_I16@PURE_QUANTA.SOCKET4677_AZIF0045P001C01CS(CHIPS)':
 'UPI2_RX_DP1': CDS_PINID='UPI2_RX_DP1';
NET_NAME
'UPI_CPU0_CPU1_P2P2_DP<20>'
 '@S9S_MB_2U_LIB.S9S_MB_2U(SCH_1):UPI_CPU0_CPU1_P2P2_DP'<20>:
 C_SIGNAL='@s9s_mb_2u_lib.s9s_mb_2u(sch_1):upi_cpu0_cpu1_p2p2_dp(20)';
NODE_NAME     U2 H87
 '@S9S_MB_2U_LIB.S9S_MB_2U(SCH_1):PAGE34_I102@PURE_QUANTA.SOCKET4677_AZIF0045P001C01CS(CHIPS)':
 'UPI2_TX_DP3': CDS_PINID='UPI2_TX_DP3';
NODE_NAME     U1 BJ74
 '@S9S_MB_2U_LIB.S9S_MB_2U(SCH_1):PAGE65_I16@PURE_QUANTA.SOCKET4677_AZIF0045P001C01CS(CHIPS)':
 'UPI2_RX_DP20': CDS_PINID='UPI2_RX_DP20';
NET_NAME
'UPI_CPU0_CPU1_P2P2_DP<21>'
 '@S9S_MB_2U_LIB.S9S_MB_2U(SCH_1):UPI_CPU0_CPU1_P2P2_DP'<21>:
 C_SIGNAL='@s9s_mb_2u_lib.s9s_mb_2u(sch_1):upi_cpu0_cpu1_p2p2_dp(21)';
NODE_NAME     U2 E88
 '@S9S_MB_2U_LIB.S9S_MB_2U(SCH_1):PAGE34_I102@PURE_QUANTA.SOCKET4677_AZIF0045P001C01CS(CHIPS)':
 'UPI2_TX_DP2': CDS_PINID='UPI2_TX_DP2';
NODE_NAME     U1 BM75
 '@S9S_MB_2U_LIB.S9S_MB_2U(SCH_1):PAGE65_I16@PURE_QUANTA.SOCKET4677_AZIF0045P001C01CS(CHIPS)':
 'UPI2_RX_DP21': CDS_PINID='UPI2_RX_DP21';
NET_NAME
'UPI_CPU0_CPU1_P2P2_DP<22>'
 '@S9S_MB_2U_LIB.S9S_MB_2U(SCH_1):UPI_CPU0_CPU1_P2P2_DP'<22>:
 C_SIGNAL='@s9s_mb_2u_lib.s9s_mb_2u(sch_1):upi_cpu0_cpu1_p2p2_dp(22)';
NODE_NAME     U2 F85
 '@S9S_MB_2U_LIB.S9S_MB_2U(SCH_1):PAGE34_I102@PURE_QUANTA.SOCKET4677_AZIF0045P001C01CS(CHIPS)':
 'UPI2_TX_DP1': CDS_PINID='UPI2_TX_DP1';
NODE_NAME     U1 BL74
 '@S9S_MB_2U_LIB.S9S_MB_2U(SCH_1):PAGE65_I16@PURE_QUANTA.SOCKET4677_AZIF0045P001C01CS(CHIPS)':
 'UPI2_RX_DP22': CDS_PINID='UPI2_RX_DP22';
NET_NAME
'UPI_CPU0_CPU1_P2P2_DP<23>'
 '@S9S_MB_2U_LIB.S9S_MB_2U(SCH_1):UPI_CPU0_CPU1_P2P2_DP'<23>:
 C_SIGNAL='@s9s_mb_2u_lib.s9s_mb_2u(sch_1):upi_cpu0_cpu1_p2p2_dp(23)';
NODE_NAME     U2 D85
 '@S9S_MB_2U_LIB.S9S_MB_2U(SCH_1):PAGE34_I102@PURE_QUANTA.SOCKET4677_AZIF0045P001C01CS(CHIPS)':
 'UPI2_TX_DP0': CDS_PINID='UPI2_TX_DP0';
NODE_NAME     U1 BC74
 '@S9S_MB_2U_LIB.S9S_MB_2U(SCH_1):PAGE65_I16@PURE_QUANTA.SOCKET4677_AZIF0045P001C01CS(CHIPS)':
 'UPI2_RX_DP23': CDS_PINID='UPI2_RX_DP23';
NET_NAME
'UPI_CPU0_CPU1_P2P2_DP<2>'
 '@S9S_MB_2U_LIB.S9S_MB_2U(SCH_1):UPI_CPU0_CPU1_P2P2_DP'<2>:
 C_SIGNAL='@s9s_mb_2u_lib.s9s_mb_2u(sch_1):upi_cpu0_cpu1_p2p2_dp(2)';
NODE_NAME     U2 BG82
 '@S9S_MB_2U_LIB.S9S_MB_2U(SCH_1):PAGE34_I102@PURE_QUANTA.SOCKET4677_AZIF0045P001C01CS(CHIPS)':
 'UPI2_TX_DP21': CDS_PINID='UPI2_TX_DP21';
NODE_NAME     U1 H83
 '@S9S_MB_2U_LIB.S9S_MB_2U(SCH_1):PAGE65_I16@PURE_QUANTA.SOCKET4677_AZIF0045P001C01CS(CHIPS)':
 'UPI2_RX_DP2': CDS_PINID='UPI2_RX_DP2';
NET_NAME
'UPI_CPU0_CPU1_P2P2_DP<3>'
 '@S9S_MB_2U_LIB.S9S_MB_2U(SCH_1):UPI_CPU0_CPU1_P2P2_DP'<3>:
 C_SIGNAL='@s9s_mb_2u_lib.s9s_mb_2u(sch_1):upi_cpu0_cpu1_p2p2_dp(3)';
NODE_NAME     U2 BC80
 '@S9S_MB_2U_LIB.S9S_MB_2U(SCH_1):PAGE34_I102@PURE_QUANTA.SOCKET4677_AZIF0045P001C01CS(CHIPS)':
 'UPI2_TX_DP20': CDS_PINID='UPI2_TX_DP20';
NODE_NAME     U1 M79
 '@S9S_MB_2U_LIB.S9S_MB_2U(SCH_1):PAGE65_I16@PURE_QUANTA.SOCKET4677_AZIF0045P001C01CS(CHIPS)':
 'UPI2_RX_DP3': CDS_PINID='UPI2_RX_DP3';
NET_NAME
'UPI_CPU0_CPU1_P2P2_DP<4>'
 '@S9S_MB_2U_LIB.S9S_MB_2U(SCH_1):UPI_CPU0_CPU1_P2P2_DP'<4>:
 C_SIGNAL='@s9s_mb_2u_lib.s9s_mb_2u(sch_1):upi_cpu0_cpu1_p2p2_dp(4)';
NODE_NAME     U2 BD83
 '@S9S_MB_2U_LIB.S9S_MB_2U(SCH_1):PAGE34_I102@PURE_QUANTA.SOCKET4677_AZIF0045P001C01CS(CHIPS)':
 'UPI2_TX_DP19': CDS_PINID='UPI2_TX_DP19';
NODE_NAME     U1 L82
 '@S9S_MB_2U_LIB.S9S_MB_2U(SCH_1):PAGE65_I16@PURE_QUANTA.SOCKET4677_AZIF0045P001C01CS(CHIPS)':
 'UPI2_RX_DP4': CDS_PINID='UPI2_RX_DP4';
NET_NAME
'UPI_CPU0_CPU1_P2P2_DP<5>'
 '@S9S_MB_2U_LIB.S9S_MB_2U(SCH_1):UPI_CPU0_CPU1_P2P2_DP'<5>:
 C_SIGNAL='@s9s_mb_2u_lib.s9s_mb_2u(sch_1):upi_cpu0_cpu1_p2p2_dp(5)';
NODE_NAME     U2 BA82
 '@S9S_MB_2U_LIB.S9S_MB_2U(SCH_1):PAGE34_I102@PURE_QUANTA.SOCKET4677_AZIF0045P001C01CS(CHIPS)':
 'UPI2_TX_DP18': CDS_PINID='UPI2_TX_DP18';
NODE_NAME     U1 K81
 '@S9S_MB_2U_LIB.S9S_MB_2U(SCH_1):PAGE65_I16@PURE_QUANTA.SOCKET4677_AZIF0045P001C01CS(CHIPS)':
 'UPI2_RX_DP5': CDS_PINID='UPI2_RX_DP5';
NET_NAME
'UPI_CPU0_CPU1_P2P2_DP<6>'
 '@S9S_MB_2U_LIB.S9S_MB_2U(SCH_1):UPI_CPU0_CPU1_P2P2_DP'<6>:
 C_SIGNAL='@s9s_mb_2u_lib.s9s_mb_2u(sch_1):upi_cpu0_cpu1_p2p2_dp(6)';
NODE_NAME     U2 BB81
 '@S9S_MB_2U_LIB.S9S_MB_2U(SCH_1):PAGE34_I102@PURE_QUANTA.SOCKET4677_AZIF0045P001C01CS(CHIPS)':
 'UPI2_TX_DP17': CDS_PINID='UPI2_TX_DP17';
NODE_NAME     U1 AE80
 '@S9S_MB_2U_LIB.S9S_MB_2U(SCH_1):PAGE65_I16@PURE_QUANTA.SOCKET4677_AZIF0045P001C01CS(CHIPS)':
 'UPI2_RX_DP6': CDS_PINID='UPI2_RX_DP6';
NET_NAME
'UPI_CPU0_CPU1_P2P2_DP<7>'
 '@S9S_MB_2U_LIB.S9S_MB_2U(SCH_1):UPI_CPU0_CPU1_P2P2_DP'<7>:
 C_SIGNAL='@s9s_mb_2u_lib.s9s_mb_2u(sch_1):upi_cpu0_cpu1_p2p2_dp(7)';
NODE_NAME     U2 AU82
 '@S9S_MB_2U_LIB.S9S_MB_2U(SCH_1):PAGE34_I102@PURE_QUANTA.SOCKET4677_AZIF0045P001C01CS(CHIPS)':
 'UPI2_TX_DP16': CDS_PINID='UPI2_TX_DP16';
NODE_NAME     U1 AC82
 '@S9S_MB_2U_LIB.S9S_MB_2U(SCH_1):PAGE65_I16@PURE_QUANTA.SOCKET4677_AZIF0045P001C01CS(CHIPS)':
 'UPI2_RX_DP7': CDS_PINID='UPI2_RX_DP7';
NET_NAME
'UPI_CPU0_CPU1_P2P2_DP<8>'
 '@S9S_MB_2U_LIB.S9S_MB_2U(SCH_1):UPI_CPU0_CPU1_P2P2_DP'<8>:
 C_SIGNAL='@s9s_mb_2u_lib.s9s_mb_2u(sch_1):upi_cpu0_cpu1_p2p2_dp(8)';
NODE_NAME     U2 AV83
 '@S9S_MB_2U_LIB.S9S_MB_2U(SCH_1):PAGE34_I102@PURE_QUANTA.SOCKET4677_AZIF0045P001C01CS(CHIPS)':
 'UPI2_TX_DP15': CDS_PINID='UPI2_TX_DP15';
NODE_NAME     U1 AG80
 '@S9S_MB_2U_LIB.S9S_MB_2U(SCH_1):PAGE65_I16@PURE_QUANTA.SOCKET4677_AZIF0045P001C01CS(CHIPS)':
 'UPI2_RX_DP8': CDS_PINID='UPI2_RX_DP8';
NET_NAME
'UPI_CPU0_CPU1_P2P2_DP<9>'
 '@S9S_MB_2U_LIB.S9S_MB_2U(SCH_1):UPI_CPU0_CPU1_P2P2_DP'<9>:
 C_SIGNAL='@s9s_mb_2u_lib.s9s_mb_2u(sch_1):upi_cpu0_cpu1_p2p2_dp(9)';
NODE_NAME     U2 AT81
 '@S9S_MB_2U_LIB.S9S_MB_2U(SCH_1):PAGE34_I102@PURE_QUANTA.SOCKET4677_AZIF0045P001C01CS(CHIPS)':
 'UPI2_TX_DP14': CDS_PINID='UPI2_TX_DP14';
NODE_NAME     U1 AF83
 '@S9S_MB_2U_LIB.S9S_MB_2U(SCH_1):PAGE65_I16@PURE_QUANTA.SOCKET4677_AZIF0045P001C01CS(CHIPS)':
 'UPI2_RX_DP9': CDS_PINID='UPI2_RX_DP9';
NET_NAME
'UPI_CPU1_CPU0_P0P1_DN<0>'
 '@S9S_MB_2U_LIB.S9S_MB_2U(SCH_1):UPI_CPU1_CPU0_P0P1_DN'<0>:
 C_SIGNAL='@s9s_mb_2u_lib.s9s_mb_2u(sch_1):upi_cpu1_cpu0_p0p1_dn(0)';
NODE_NAME     U2 EH2
 '@S9S_MB_2U_LIB.S9S_MB_2U(SCH_1):PAGE33_I102@PURE_QUANTA.SOCKET4677_AZIF0045P001C01CS(CHIPS)':
 'UPI1_RX_DN0': CDS_PINID='UPI1_RX_DN0';
NODE_NAME     U1 K4
 '@S9S_MB_2U_LIB.S9S_MB_2U(SCH_1):PAGE63_I51@PURE_QUANTA.SOCKET4677_AZIF0045P001C01CS(CHIPS)':
 'UPI0_TX_DN0': CDS_PINID='UPI0_TX_DN0';
NET_NAME
'UPI_CPU1_CPU0_P0P1_DN<10>'
 '@S9S_MB_2U_LIB.S9S_MB_2U(SCH_1):UPI_CPU1_CPU0_P0P1_DN'<10>:
 C_SIGNAL='@s9s_mb_2u_lib.s9s_mb_2u(sch_1):upi_cpu1_cpu0_p0p1_dn(10)';
NODE_NAME     U2 DG3
 '@S9S_MB_2U_LIB.S9S_MB_2U(SCH_1):PAGE33_I102@PURE_QUANTA.SOCKET4677_AZIF0045P001C01CS(CHIPS)':
 'UPI1_RX_DN10': CDS_PINID='UPI1_RX_DN10';
NODE_NAME     U1 AK2
 '@S9S_MB_2U_LIB.S9S_MB_2U(SCH_1):PAGE63_I51@PURE_QUANTA.SOCKET4677_AZIF0045P001C01CS(CHIPS)':
 'UPI0_TX_DN10': CDS_PINID='UPI0_TX_DN10';
NET_NAME
'UPI_CPU1_CPU0_P0P1_DN<11>'
 '@S9S_MB_2U_LIB.S9S_MB_2U(SCH_1):UPI_CPU1_CPU0_P0P1_DN'<11>:
 C_SIGNAL='@s9s_mb_2u_lib.s9s_mb_2u(sch_1):upi_cpu1_cpu0_p0p1_dn(11)';
NODE_NAME     U2 DE1
 '@S9S_MB_2U_LIB.S9S_MB_2U(SCH_1):PAGE33_I102@PURE_QUANTA.SOCKET4677_AZIF0045P001C01CS(CHIPS)':
 'UPI1_RX_DN11': CDS_PINID='UPI1_RX_DN11';
NODE_NAME     U1 AM2
 '@S9S_MB_2U_LIB.S9S_MB_2U(SCH_1):PAGE63_I51@PURE_QUANTA.SOCKET4677_AZIF0045P001C01CS(CHIPS)':
 'UPI0_TX_DN11': CDS_PINID='UPI0_TX_DN11';
NET_NAME
'UPI_CPU1_CPU0_P0P1_DN<12>'
 '@S9S_MB_2U_LIB.S9S_MB_2U(SCH_1):UPI_CPU1_CPU0_P0P1_DN'<12>:
 C_SIGNAL='@s9s_mb_2u_lib.s9s_mb_2u(sch_1):upi_cpu1_cpu0_p0p1_dn(12)';
NODE_NAME     U2 DC3
 '@S9S_MB_2U_LIB.S9S_MB_2U(SCH_1):PAGE33_I102@PURE_QUANTA.SOCKET4677_AZIF0045P001C01CS(CHIPS)':
 'UPI1_RX_DP12': CDS_PINID='UPI1_RX_DP12';
NODE_NAME     U1 AP2
 '@S9S_MB_2U_LIB.S9S_MB_2U(SCH_1):PAGE63_I51@PURE_QUANTA.SOCKET4677_AZIF0045P001C01CS(CHIPS)':
 'UPI0_TX_DN12': CDS_PINID='UPI0_TX_DN12';
NET_NAME
'UPI_CPU1_CPU0_P0P1_DN<13>'
 '@S9S_MB_2U_LIB.S9S_MB_2U(SCH_1):UPI_CPU1_CPU0_P0P1_DN'<13>:
 C_SIGNAL='@s9s_mb_2u_lib.s9s_mb_2u(sch_1):upi_cpu1_cpu0_p0p1_dn(13)';
NODE_NAME     U2 DB2
 '@S9S_MB_2U_LIB.S9S_MB_2U(SCH_1):PAGE33_I102@PURE_QUANTA.SOCKET4677_AZIF0045P001C01CS(CHIPS)':
 'UPI1_RX_DN13': CDS_PINID='UPI1_RX_DN13';
NODE_NAME     U1 AT2
 '@S9S_MB_2U_LIB.S9S_MB_2U(SCH_1):PAGE63_I51@PURE_QUANTA.SOCKET4677_AZIF0045P001C01CS(CHIPS)':
 'UPI0_TX_DN13': CDS_PINID='UPI0_TX_DN13';
NET_NAME
'UPI_CPU1_CPU0_P0P1_DN<14>'
 '@S9S_MB_2U_LIB.S9S_MB_2U(SCH_1):UPI_CPU1_CPU0_P0P1_DN'<14>:
 C_SIGNAL='@s9s_mb_2u_lib.s9s_mb_2u(sch_1):upi_cpu1_cpu0_p0p1_dn(14)';
NODE_NAME     U2 CY2
 '@S9S_MB_2U_LIB.S9S_MB_2U(SCH_1):PAGE33_I102@PURE_QUANTA.SOCKET4677_AZIF0045P001C01CS(CHIPS)':
 'UPI1_RX_DN14': CDS_PINID='UPI1_RX_DN14';
NODE_NAME     U1 AU1
 '@S9S_MB_2U_LIB.S9S_MB_2U(SCH_1):PAGE63_I51@PURE_QUANTA.SOCKET4677_AZIF0045P001C01CS(CHIPS)':
 'UPI0_TX_DN14': CDS_PINID='UPI0_TX_DN14';
NET_NAME
'UPI_CPU1_CPU0_P0P1_DN<15>'
 '@S9S_MB_2U_LIB.S9S_MB_2U(SCH_1):UPI_CPU1_CPU0_P0P1_DN'<15>:
 C_SIGNAL='@s9s_mb_2u_lib.s9s_mb_2u(sch_1):upi_cpu1_cpu0_p0p1_dn(15)';
NODE_NAME     U2 CV2
 '@S9S_MB_2U_LIB.S9S_MB_2U(SCH_1):PAGE33_I102@PURE_QUANTA.SOCKET4677_AZIF0045P001C01CS(CHIPS)':
 'UPI1_RX_DN15': CDS_PINID='UPI1_RX_DN15';
NODE_NAME     U1 AY2
 '@S9S_MB_2U_LIB.S9S_MB_2U(SCH_1):PAGE63_I51@PURE_QUANTA.SOCKET4677_AZIF0045P001C01CS(CHIPS)':
 'UPI0_TX_DN15': CDS_PINID='UPI0_TX_DN15';
NET_NAME
'UPI_CPU1_CPU0_P0P1_DN<16>'
 '@S9S_MB_2U_LIB.S9S_MB_2U(SCH_1):UPI_CPU1_CPU0_P0P1_DN'<16>:
 C_SIGNAL='@s9s_mb_2u_lib.s9s_mb_2u(sch_1):upi_cpu1_cpu0_p0p1_dn(16)';
NODE_NAME     U2 CR3
 '@S9S_MB_2U_LIB.S9S_MB_2U(SCH_1):PAGE33_I102@PURE_QUANTA.SOCKET4677_AZIF0045P001C01CS(CHIPS)':
 'UPI1_RX_DN16': CDS_PINID='UPI1_RX_DN16';
NODE_NAME     U1 BB2
 '@S9S_MB_2U_LIB.S9S_MB_2U(SCH_1):PAGE63_I51@PURE_QUANTA.SOCKET4677_AZIF0045P001C01CS(CHIPS)':
 'UPI0_TX_DN16': CDS_PINID='UPI0_TX_DN16';
NET_NAME
'UPI_CPU1_CPU0_P0P1_DN<17>'
 '@S9S_MB_2U_LIB.S9S_MB_2U(SCH_1):UPI_CPU1_CPU0_P0P1_DN'<17>:
 C_SIGNAL='@s9s_mb_2u_lib.s9s_mb_2u(sch_1):upi_cpu1_cpu0_p0p1_dn(17)';
NODE_NAME     U2 CP2
 '@S9S_MB_2U_LIB.S9S_MB_2U(SCH_1):PAGE33_I102@PURE_QUANTA.SOCKET4677_AZIF0045P001C01CS(CHIPS)':
 'UPI1_RX_DP17': CDS_PINID='UPI1_RX_DP17';
NODE_NAME     U1 BD2
 '@S9S_MB_2U_LIB.S9S_MB_2U(SCH_1):PAGE63_I51@PURE_QUANTA.SOCKET4677_AZIF0045P001C01CS(CHIPS)':
 'UPI0_TX_DN17': CDS_PINID='UPI0_TX_DN17';
NET_NAME
'UPI_CPU1_CPU0_P0P1_DN<18>'
 '@S9S_MB_2U_LIB.S9S_MB_2U(SCH_1):UPI_CPU1_CPU0_P0P1_DN'<18>:
 C_SIGNAL='@s9s_mb_2u_lib.s9s_mb_2u(sch_1):upi_cpu1_cpu0_p0p1_dn(18)';
NODE_NAME     U2 CL3
 '@S9S_MB_2U_LIB.S9S_MB_2U(SCH_1):PAGE33_I102@PURE_QUANTA.SOCKET4677_AZIF0045P001C01CS(CHIPS)':
 'UPI1_RX_DN18': CDS_PINID='UPI1_RX_DN18';
NODE_NAME     U1 BF2
 '@S9S_MB_2U_LIB.S9S_MB_2U(SCH_1):PAGE63_I51@PURE_QUANTA.SOCKET4677_AZIF0045P001C01CS(CHIPS)':
 'UPI0_TX_DN18': CDS_PINID='UPI0_TX_DN18';
NET_NAME
'UPI_CPU1_CPU0_P0P1_DN<19>'
 '@S9S_MB_2U_LIB.S9S_MB_2U(SCH_1):UPI_CPU1_CPU0_P0P1_DN'<19>:
 C_SIGNAL='@s9s_mb_2u_lib.s9s_mb_2u(sch_1):upi_cpu1_cpu0_p0p1_dn(19)';
NODE_NAME     U2 CK2
 '@S9S_MB_2U_LIB.S9S_MB_2U(SCH_1):PAGE33_I102@PURE_QUANTA.SOCKET4677_AZIF0045P001C01CS(CHIPS)':
 'UPI1_RX_DP19': CDS_PINID='UPI1_RX_DP19';
NODE_NAME     U1 BH2
 '@S9S_MB_2U_LIB.S9S_MB_2U(SCH_1):PAGE63_I51@PURE_QUANTA.SOCKET4677_AZIF0045P001C01CS(CHIPS)':
 'UPI0_TX_DN19': CDS_PINID='UPI0_TX_DN19';
NET_NAME
'UPI_CPU1_CPU0_P0P1_DN<1>'
 '@S9S_MB_2U_LIB.S9S_MB_2U(SCH_1):UPI_CPU1_CPU0_P0P1_DN'<1>:
 C_SIGNAL='@s9s_mb_2u_lib.s9s_mb_2u(sch_1):upi_cpu1_cpu0_p0p1_dn(1)';
NODE_NAME     U2 EE3
 '@S9S_MB_2U_LIB.S9S_MB_2U(SCH_1):PAGE33_I102@PURE_QUANTA.SOCKET4677_AZIF0045P001C01CS(CHIPS)':
 'UPI1_RX_DN1': CDS_PINID='UPI1_RX_DN1';
NODE_NAME     U1 M2
 '@S9S_MB_2U_LIB.S9S_MB_2U(SCH_1):PAGE63_I51@PURE_QUANTA.SOCKET4677_AZIF0045P001C01CS(CHIPS)':
 'UPI0_TX_DN1': CDS_PINID='UPI0_TX_DN1';
NET_NAME
'UPI_CPU1_CPU0_P0P1_DN<20>'
 '@S9S_MB_2U_LIB.S9S_MB_2U(SCH_1):UPI_CPU1_CPU0_P0P1_DN'<20>:
 C_SIGNAL='@s9s_mb_2u_lib.s9s_mb_2u(sch_1):upi_cpu1_cpu0_p0p1_dn(20)';
NODE_NAME     U2 CG3
 '@S9S_MB_2U_LIB.S9S_MB_2U(SCH_1):PAGE33_I102@PURE_QUANTA.SOCKET4677_AZIF0045P001C01CS(CHIPS)':
 'UPI1_RX_DP20': CDS_PINID='UPI1_RX_DP20';
NODE_NAME     U1 BK2
 '@S9S_MB_2U_LIB.S9S_MB_2U(SCH_1):PAGE63_I51@PURE_QUANTA.SOCKET4677_AZIF0045P001C01CS(CHIPS)':
 'UPI0_TX_DN20': CDS_PINID='UPI0_TX_DN20';
NET_NAME
'UPI_CPU1_CPU0_P0P1_DN<21>'
 '@S9S_MB_2U_LIB.S9S_MB_2U(SCH_1):UPI_CPU1_CPU0_P0P1_DN'<21>:
 C_SIGNAL='@s9s_mb_2u_lib.s9s_mb_2u(sch_1):upi_cpu1_cpu0_p0p1_dn(21)';
NODE_NAME     U2 CF2
 '@S9S_MB_2U_LIB.S9S_MB_2U(SCH_1):PAGE33_I102@PURE_QUANTA.SOCKET4677_AZIF0045P001C01CS(CHIPS)':
 'UPI1_RX_DN21': CDS_PINID='UPI1_RX_DN21';
NODE_NAME     U1 BM2
 '@S9S_MB_2U_LIB.S9S_MB_2U(SCH_1):PAGE63_I51@PURE_QUANTA.SOCKET4677_AZIF0045P001C01CS(CHIPS)':
 'UPI0_TX_DN21': CDS_PINID='UPI0_TX_DN21';
NET_NAME
'UPI_CPU1_CPU0_P0P1_DN<22>'
 '@S9S_MB_2U_LIB.S9S_MB_2U(SCH_1):UPI_CPU1_CPU0_P0P1_DN'<22>:
 C_SIGNAL='@s9s_mb_2u_lib.s9s_mb_2u(sch_1):upi_cpu1_cpu0_p0p1_dn(22)';
NODE_NAME     U2 CC3
 '@S9S_MB_2U_LIB.S9S_MB_2U(SCH_1):PAGE33_I102@PURE_QUANTA.SOCKET4677_AZIF0045P001C01CS(CHIPS)':
 'UPI1_RX_DP22': CDS_PINID='UPI1_RX_DP22';
NODE_NAME     U1 BR3
 '@S9S_MB_2U_LIB.S9S_MB_2U(SCH_1):PAGE63_I51@PURE_QUANTA.SOCKET4677_AZIF0045P001C01CS(CHIPS)':
 'UPI0_TX_DN22': CDS_PINID='UPI0_TX_DN22';
NET_NAME
'UPI_CPU1_CPU0_P0P1_DN<23>'
 '@S9S_MB_2U_LIB.S9S_MB_2U(SCH_1):UPI_CPU1_CPU0_P0P1_DN'<23>:
 C_SIGNAL='@s9s_mb_2u_lib.s9s_mb_2u(sch_1):upi_cpu1_cpu0_p0p1_dn(23)';
NODE_NAME     U2 BY2
 '@S9S_MB_2U_LIB.S9S_MB_2U(SCH_1):PAGE33_I102@PURE_QUANTA.SOCKET4677_AZIF0045P001C01CS(CHIPS)':
 'UPI1_RX_DP23': CDS_PINID='UPI1_RX_DP23';
NODE_NAME     U1 BT2
 '@S9S_MB_2U_LIB.S9S_MB_2U(SCH_1):PAGE63_I51@PURE_QUANTA.SOCKET4677_AZIF0045P001C01CS(CHIPS)':
 'UPI0_TX_DN23': CDS_PINID='UPI0_TX_DN23';
NET_NAME
'UPI_CPU1_CPU0_P0P1_DN<2>'
 '@S9S_MB_2U_LIB.S9S_MB_2U(SCH_1):UPI_CPU1_CPU0_P0P1_DN'<2>:
 C_SIGNAL='@s9s_mb_2u_lib.s9s_mb_2u(sch_1):upi_cpu1_cpu0_p0p1_dn(2)';
NODE_NAME     U2 EC3
 '@S9S_MB_2U_LIB.S9S_MB_2U(SCH_1):PAGE33_I102@PURE_QUANTA.SOCKET4677_AZIF0045P001C01CS(CHIPS)':
 'UPI1_RX_DP2': CDS_PINID='UPI1_RX_DP2';
NODE_NAME     U1 N1
 '@S9S_MB_2U_LIB.S9S_MB_2U(SCH_1):PAGE63_I51@PURE_QUANTA.SOCKET4677_AZIF0045P001C01CS(CHIPS)':
 'UPI0_TX_DN2': CDS_PINID='UPI0_TX_DN2';
NET_NAME
'UPI_CPU1_CPU0_P0P1_DN<3>'
 '@S9S_MB_2U_LIB.S9S_MB_2U(SCH_1):UPI_CPU1_CPU0_P0P1_DN'<3>:
 C_SIGNAL='@s9s_mb_2u_lib.s9s_mb_2u(sch_1):upi_cpu1_cpu0_p0p1_dn(3)';
NODE_NAME     U2 EA1
 '@S9S_MB_2U_LIB.S9S_MB_2U(SCH_1):PAGE33_I102@PURE_QUANTA.SOCKET4677_AZIF0045P001C01CS(CHIPS)':
 'UPI1_RX_DN3': CDS_PINID='UPI1_RX_DN3';
NODE_NAME     U1 T2
 '@S9S_MB_2U_LIB.S9S_MB_2U(SCH_1):PAGE63_I51@PURE_QUANTA.SOCKET4677_AZIF0045P001C01CS(CHIPS)':
 'UPI0_TX_DN3': CDS_PINID='UPI0_TX_DN3';
NET_NAME
'UPI_CPU1_CPU0_P0P1_DN<4>'
 '@S9S_MB_2U_LIB.S9S_MB_2U(SCH_1):UPI_CPU1_CPU0_P0P1_DN'<4>:
 C_SIGNAL='@s9s_mb_2u_lib.s9s_mb_2u(sch_1):upi_cpu1_cpu0_p0p1_dn(4)';
NODE_NAME     U2 DY2
 '@S9S_MB_2U_LIB.S9S_MB_2U(SCH_1):PAGE33_I102@PURE_QUANTA.SOCKET4677_AZIF0045P001C01CS(CHIPS)':
 'UPI1_RX_DN4': CDS_PINID='UPI1_RX_DN4';
NODE_NAME     U1 U1
 '@S9S_MB_2U_LIB.S9S_MB_2U(SCH_1):PAGE63_I51@PURE_QUANTA.SOCKET4677_AZIF0045P001C01CS(CHIPS)':
 'UPI0_TX_DN4': CDS_PINID='UPI0_TX_DN4';
NET_NAME
'UPI_CPU1_CPU0_P0P1_DN<5>'
 '@S9S_MB_2U_LIB.S9S_MB_2U(SCH_1):UPI_CPU1_CPU0_P0P1_DN'<5>:
 C_SIGNAL='@s9s_mb_2u_lib.s9s_mb_2u(sch_1):upi_cpu1_cpu0_p0p1_dn(5)';
NODE_NAME     U2 DU1
 '@S9S_MB_2U_LIB.S9S_MB_2U(SCH_1):PAGE33_I102@PURE_QUANTA.SOCKET4677_AZIF0045P001C01CS(CHIPS)':
 'UPI1_RX_DN5': CDS_PINID='UPI1_RX_DN5';
NODE_NAME     U1 Y2
 '@S9S_MB_2U_LIB.S9S_MB_2U(SCH_1):PAGE63_I51@PURE_QUANTA.SOCKET4677_AZIF0045P001C01CS(CHIPS)':
 'UPI0_TX_DN5': CDS_PINID='UPI0_TX_DN5';
NET_NAME
'UPI_CPU1_CPU0_P0P1_DN<6>'
 '@S9S_MB_2U_LIB.S9S_MB_2U(SCH_1):UPI_CPU1_CPU0_P0P1_DN'<6>:
 C_SIGNAL='@s9s_mb_2u_lib.s9s_mb_2u(sch_1):upi_cpu1_cpu0_p0p1_dn(6)';
NODE_NAME     U2 DT2
 '@S9S_MB_2U_LIB.S9S_MB_2U(SCH_1):PAGE33_I102@PURE_QUANTA.SOCKET4677_AZIF0045P001C01CS(CHIPS)':
 'UPI1_RX_DN6': CDS_PINID='UPI1_RX_DN6';
NODE_NAME     U1 AA1
 '@S9S_MB_2U_LIB.S9S_MB_2U(SCH_1):PAGE63_I51@PURE_QUANTA.SOCKET4677_AZIF0045P001C01CS(CHIPS)':
 'UPI0_TX_DN6': CDS_PINID='UPI0_TX_DN6';
NET_NAME
'UPI_CPU1_CPU0_P0P1_DN<7>'
 '@S9S_MB_2U_LIB.S9S_MB_2U(SCH_1):UPI_CPU1_CPU0_P0P1_DN'<7>:
 C_SIGNAL='@s9s_mb_2u_lib.s9s_mb_2u(sch_1):upi_cpu1_cpu0_p0p1_dn(7)';
NODE_NAME     U2 DN1
 '@S9S_MB_2U_LIB.S9S_MB_2U(SCH_1):PAGE33_I102@PURE_QUANTA.SOCKET4677_AZIF0045P001C01CS(CHIPS)':
 'UPI1_RX_DN7': CDS_PINID='UPI1_RX_DN7';
NODE_NAME     U1 AD2
 '@S9S_MB_2U_LIB.S9S_MB_2U(SCH_1):PAGE63_I51@PURE_QUANTA.SOCKET4677_AZIF0045P001C01CS(CHIPS)':
 'UPI0_TX_DN7': CDS_PINID='UPI0_TX_DN7';
NET_NAME
'UPI_CPU1_CPU0_P0P1_DN<8>'
 '@S9S_MB_2U_LIB.S9S_MB_2U(SCH_1):UPI_CPU1_CPU0_P0P1_DN'<8>:
 C_SIGNAL='@s9s_mb_2u_lib.s9s_mb_2u(sch_1):upi_cpu1_cpu0_p0p1_dn(8)';
NODE_NAME     U2 DL3
 '@S9S_MB_2U_LIB.S9S_MB_2U(SCH_1):PAGE33_I102@PURE_QUANTA.SOCKET4677_AZIF0045P001C01CS(CHIPS)':
 'UPI1_RX_DN8': CDS_PINID='UPI1_RX_DN8';
NODE_NAME     U1 AF2
 '@S9S_MB_2U_LIB.S9S_MB_2U(SCH_1):PAGE63_I51@PURE_QUANTA.SOCKET4677_AZIF0045P001C01CS(CHIPS)':
 'UPI0_TX_DN8': CDS_PINID='UPI0_TX_DN8';
NET_NAME
'UPI_CPU1_CPU0_P0P1_DN<9>'
 '@S9S_MB_2U_LIB.S9S_MB_2U(SCH_1):UPI_CPU1_CPU0_P0P1_DN'<9>:
 C_SIGNAL='@s9s_mb_2u_lib.s9s_mb_2u(sch_1):upi_cpu1_cpu0_p0p1_dn(9)';
NODE_NAME     U2 DJ1
 '@S9S_MB_2U_LIB.S9S_MB_2U(SCH_1):PAGE33_I102@PURE_QUANTA.SOCKET4677_AZIF0045P001C01CS(CHIPS)':
 'UPI1_RX_DN9': CDS_PINID='UPI1_RX_DN9';
NODE_NAME     U1 AH2
 '@S9S_MB_2U_LIB.S9S_MB_2U(SCH_1):PAGE63_I51@PURE_QUANTA.SOCKET4677_AZIF0045P001C01CS(CHIPS)':
 'UPI0_TX_DN9': CDS_PINID='UPI0_TX_DN9';
NET_NAME
'UPI_CPU1_CPU0_P0P1_DP<0>'
 '@S9S_MB_2U_LIB.S9S_MB_2U(SCH_1):UPI_CPU1_CPU0_P0P1_DP'<0>:
 C_SIGNAL='@s9s_mb_2u_lib.s9s_mb_2u(sch_1):upi_cpu1_cpu0_p0p1_dp(0)';
NODE_NAME     U2 EJ3
 '@S9S_MB_2U_LIB.S9S_MB_2U(SCH_1):PAGE33_I102@PURE_QUANTA.SOCKET4677_AZIF0045P001C01CS(CHIPS)':
 'UPI1_RX_DP0': CDS_PINID='UPI1_RX_DP0';
NODE_NAME     U1 J3
 '@S9S_MB_2U_LIB.S9S_MB_2U(SCH_1):PAGE63_I51@PURE_QUANTA.SOCKET4677_AZIF0045P001C01CS(CHIPS)':
 'UPI0_TX_DP0': CDS_PINID='UPI0_TX_DP0';
NET_NAME
'UPI_CPU1_CPU0_P0P1_DP<10>'
 '@S9S_MB_2U_LIB.S9S_MB_2U(SCH_1):UPI_CPU1_CPU0_P0P1_DP'<10>:
 C_SIGNAL='@s9s_mb_2u_lib.s9s_mb_2u(sch_1):upi_cpu1_cpu0_p0p1_dp(10)';
NODE_NAME     U2 DH2
 '@S9S_MB_2U_LIB.S9S_MB_2U(SCH_1):PAGE33_I102@PURE_QUANTA.SOCKET4677_AZIF0045P001C01CS(CHIPS)':
 'UPI1_RX_DP10': CDS_PINID='UPI1_RX_DP10';
NODE_NAME     U1 AJ1
 '@S9S_MB_2U_LIB.S9S_MB_2U(SCH_1):PAGE63_I51@PURE_QUANTA.SOCKET4677_AZIF0045P001C01CS(CHIPS)':
 'UPI0_TX_DP10': CDS_PINID='UPI0_TX_DP10';
NET_NAME
'UPI_CPU1_CPU0_P0P1_DP<11>'
 '@S9S_MB_2U_LIB.S9S_MB_2U(SCH_1):UPI_CPU1_CPU0_P0P1_DP'<11>:
 C_SIGNAL='@s9s_mb_2u_lib.s9s_mb_2u(sch_1):upi_cpu1_cpu0_p0p1_dp(11)';
NODE_NAME     U2 DF2
 '@S9S_MB_2U_LIB.S9S_MB_2U(SCH_1):PAGE33_I102@PURE_QUANTA.SOCKET4677_AZIF0045P001C01CS(CHIPS)':
 'UPI1_RX_DP11': CDS_PINID='UPI1_RX_DP11';
NODE_NAME     U1 AL3
 '@S9S_MB_2U_LIB.S9S_MB_2U(SCH_1):PAGE63_I51@PURE_QUANTA.SOCKET4677_AZIF0045P001C01CS(CHIPS)':
 'UPI0_TX_DP11': CDS_PINID='UPI0_TX_DP11';
NET_NAME
'UPI_CPU1_CPU0_P0P1_DP<12>'
 '@S9S_MB_2U_LIB.S9S_MB_2U(SCH_1):UPI_CPU1_CPU0_P0P1_DP'<12>:
 C_SIGNAL='@s9s_mb_2u_lib.s9s_mb_2u(sch_1):upi_cpu1_cpu0_p0p1_dp(12)';
NODE_NAME     U2 DD2
 '@S9S_MB_2U_LIB.S9S_MB_2U(SCH_1):PAGE33_I102@PURE_QUANTA.SOCKET4677_AZIF0045P001C01CS(CHIPS)':
 'UPI1_RX_DN12': CDS_PINID='UPI1_RX_DN12';
NODE_NAME     U1 AN1
 '@S9S_MB_2U_LIB.S9S_MB_2U(SCH_1):PAGE63_I51@PURE_QUANTA.SOCKET4677_AZIF0045P001C01CS(CHIPS)':
 'UPI0_TX_DP12': CDS_PINID='UPI0_TX_DP12';
NET_NAME
'UPI_CPU1_CPU0_P0P1_DP<13>'
 '@S9S_MB_2U_LIB.S9S_MB_2U(SCH_1):UPI_CPU1_CPU0_P0P1_DP'<13>:
 C_SIGNAL='@s9s_mb_2u_lib.s9s_mb_2u(sch_1):upi_cpu1_cpu0_p0p1_dp(13)';
NODE_NAME     U2 DA1
 '@S9S_MB_2U_LIB.S9S_MB_2U(SCH_1):PAGE33_I102@PURE_QUANTA.SOCKET4677_AZIF0045P001C01CS(CHIPS)':
 'UPI1_RX_DP13': CDS_PINID='UPI1_RX_DP13';
NODE_NAME     U1 AR3
 '@S9S_MB_2U_LIB.S9S_MB_2U(SCH_1):PAGE63_I51@PURE_QUANTA.SOCKET4677_AZIF0045P001C01CS(CHIPS)':
 'UPI0_TX_DP13': CDS_PINID='UPI0_TX_DP13';
NET_NAME
'UPI_CPU1_CPU0_P0P1_DP<14>'
 '@S9S_MB_2U_LIB.S9S_MB_2U(SCH_1):UPI_CPU1_CPU0_P0P1_DP'<14>:
 C_SIGNAL='@s9s_mb_2u_lib.s9s_mb_2u(sch_1):upi_cpu1_cpu0_p0p1_dp(14)';
NODE_NAME     U2 CW3
 '@S9S_MB_2U_LIB.S9S_MB_2U(SCH_1):PAGE33_I102@PURE_QUANTA.SOCKET4677_AZIF0045P001C01CS(CHIPS)':
 'UPI1_RX_DP14': CDS_PINID='UPI1_RX_DP14';
NODE_NAME     U1 AV2
 '@S9S_MB_2U_LIB.S9S_MB_2U(SCH_1):PAGE63_I51@PURE_QUANTA.SOCKET4677_AZIF0045P001C01CS(CHIPS)':
 'UPI0_TX_DP14': CDS_PINID='UPI0_TX_DP14';
NET_NAME
'UPI_CPU1_CPU0_P0P1_DP<15>'
 '@S9S_MB_2U_LIB.S9S_MB_2U(SCH_1):UPI_CPU1_CPU0_P0P1_DP'<15>:
 C_SIGNAL='@s9s_mb_2u_lib.s9s_mb_2u(sch_1):upi_cpu1_cpu0_p0p1_dp(15)';
NODE_NAME     U2 CU1
 '@S9S_MB_2U_LIB.S9S_MB_2U(SCH_1):PAGE33_I102@PURE_QUANTA.SOCKET4677_AZIF0045P001C01CS(CHIPS)':
 'UPI1_RX_DP15': CDS_PINID='UPI1_RX_DP15';
NODE_NAME     U1 AW3
 '@S9S_MB_2U_LIB.S9S_MB_2U(SCH_1):PAGE63_I51@PURE_QUANTA.SOCKET4677_AZIF0045P001C01CS(CHIPS)':
 'UPI0_TX_DP15': CDS_PINID='UPI0_TX_DP15';
NET_NAME
'UPI_CPU1_CPU0_P0P1_DP<16>'
 '@S9S_MB_2U_LIB.S9S_MB_2U(SCH_1):UPI_CPU1_CPU0_P0P1_DP'<16>:
 C_SIGNAL='@s9s_mb_2u_lib.s9s_mb_2u(sch_1):upi_cpu1_cpu0_p0p1_dp(16)';
NODE_NAME     U2 CT2
 '@S9S_MB_2U_LIB.S9S_MB_2U(SCH_1):PAGE33_I102@PURE_QUANTA.SOCKET4677_AZIF0045P001C01CS(CHIPS)':
 'UPI1_RX_DP16': CDS_PINID='UPI1_RX_DP16';
NODE_NAME     U1 BA1
 '@S9S_MB_2U_LIB.S9S_MB_2U(SCH_1):PAGE63_I51@PURE_QUANTA.SOCKET4677_AZIF0045P001C01CS(CHIPS)':
 'UPI0_TX_DP16': CDS_PINID='UPI0_TX_DP16';
NET_NAME
'UPI_CPU1_CPU0_P0P1_DP<17>'
 '@S9S_MB_2U_LIB.S9S_MB_2U(SCH_1):UPI_CPU1_CPU0_P0P1_DP'<17>:
 C_SIGNAL='@s9s_mb_2u_lib.s9s_mb_2u(sch_1):upi_cpu1_cpu0_p0p1_dp(17)';
NODE_NAME     U2 CN1
 '@S9S_MB_2U_LIB.S9S_MB_2U(SCH_1):PAGE33_I102@PURE_QUANTA.SOCKET4677_AZIF0045P001C01CS(CHIPS)':
 'UPI1_RX_DN17': CDS_PINID='UPI1_RX_DN17';
NODE_NAME     U1 BC3
 '@S9S_MB_2U_LIB.S9S_MB_2U(SCH_1):PAGE63_I51@PURE_QUANTA.SOCKET4677_AZIF0045P001C01CS(CHIPS)':
 'UPI0_TX_DP17': CDS_PINID='UPI0_TX_DP17';
NET_NAME
'UPI_CPU1_CPU0_P0P1_DP<18>'
 '@S9S_MB_2U_LIB.S9S_MB_2U(SCH_1):UPI_CPU1_CPU0_P0P1_DP'<18>:
 C_SIGNAL='@s9s_mb_2u_lib.s9s_mb_2u(sch_1):upi_cpu1_cpu0_p0p1_dp(18)';
NODE_NAME     U2 CM2
 '@S9S_MB_2U_LIB.S9S_MB_2U(SCH_1):PAGE33_I102@PURE_QUANTA.SOCKET4677_AZIF0045P001C01CS(CHIPS)':
 'UPI1_RX_DP18': CDS_PINID='UPI1_RX_DP18';
NODE_NAME     U1 BE1
 '@S9S_MB_2U_LIB.S9S_MB_2U(SCH_1):PAGE63_I51@PURE_QUANTA.SOCKET4677_AZIF0045P001C01CS(CHIPS)':
 'UPI0_TX_DP18': CDS_PINID='UPI0_TX_DP18';
NET_NAME
'UPI_CPU1_CPU0_P0P1_DP<19>'
 '@S9S_MB_2U_LIB.S9S_MB_2U(SCH_1):UPI_CPU1_CPU0_P0P1_DP'<19>:
 C_SIGNAL='@s9s_mb_2u_lib.s9s_mb_2u(sch_1):upi_cpu1_cpu0_p0p1_dp(19)';
NODE_NAME     U2 CJ1
 '@S9S_MB_2U_LIB.S9S_MB_2U(SCH_1):PAGE33_I102@PURE_QUANTA.SOCKET4677_AZIF0045P001C01CS(CHIPS)':
 'UPI1_RX_DN19': CDS_PINID='UPI1_RX_DN19';
NODE_NAME     U1 BG3
 '@S9S_MB_2U_LIB.S9S_MB_2U(SCH_1):PAGE63_I51@PURE_QUANTA.SOCKET4677_AZIF0045P001C01CS(CHIPS)':
 'UPI0_TX_DP19': CDS_PINID='UPI0_TX_DP19';
NET_NAME
'UPI_CPU1_CPU0_P0P1_DP<1>'
 '@S9S_MB_2U_LIB.S9S_MB_2U(SCH_1):UPI_CPU1_CPU0_P0P1_DP'<1>:
 C_SIGNAL='@s9s_mb_2u_lib.s9s_mb_2u(sch_1):upi_cpu1_cpu0_p0p1_dp(1)';
NODE_NAME     U2 EG3
 '@S9S_MB_2U_LIB.S9S_MB_2U(SCH_1):PAGE33_I102@PURE_QUANTA.SOCKET4677_AZIF0045P001C01CS(CHIPS)':
 'UPI1_RX_DP1': CDS_PINID='UPI1_RX_DP1';
NODE_NAME     U1 L3
 '@S9S_MB_2U_LIB.S9S_MB_2U(SCH_1):PAGE63_I51@PURE_QUANTA.SOCKET4677_AZIF0045P001C01CS(CHIPS)':
 'UPI0_TX_DP1': CDS_PINID='UPI0_TX_DP1';
NET_NAME
'UPI_CPU1_CPU0_P0P1_DP<20>'
 '@S9S_MB_2U_LIB.S9S_MB_2U(SCH_1):UPI_CPU1_CPU0_P0P1_DP'<20>:
 C_SIGNAL='@s9s_mb_2u_lib.s9s_mb_2u(sch_1):upi_cpu1_cpu0_p0p1_dp(20)';
NODE_NAME     U2 CH2
 '@S9S_MB_2U_LIB.S9S_MB_2U(SCH_1):PAGE33_I102@PURE_QUANTA.SOCKET4677_AZIF0045P001C01CS(CHIPS)':
 'UPI1_RX_DN20': CDS_PINID='UPI1_RX_DN20';
NODE_NAME     U1 BJ1
 '@S9S_MB_2U_LIB.S9S_MB_2U(SCH_1):PAGE63_I51@PURE_QUANTA.SOCKET4677_AZIF0045P001C01CS(CHIPS)':
 'UPI0_TX_DP20': CDS_PINID='UPI0_TX_DP20';
NET_NAME
'UPI_CPU1_CPU0_P0P1_DP<21>'
 '@S9S_MB_2U_LIB.S9S_MB_2U(SCH_1):UPI_CPU1_CPU0_P0P1_DP'<21>:
 C_SIGNAL='@s9s_mb_2u_lib.s9s_mb_2u(sch_1):upi_cpu1_cpu0_p0p1_dp(21)';
NODE_NAME     U2 CE1
 '@S9S_MB_2U_LIB.S9S_MB_2U(SCH_1):PAGE33_I102@PURE_QUANTA.SOCKET4677_AZIF0045P001C01CS(CHIPS)':
 'UPI1_RX_DP21': CDS_PINID='UPI1_RX_DP21';
NODE_NAME     U1 BL3
 '@S9S_MB_2U_LIB.S9S_MB_2U(SCH_1):PAGE63_I51@PURE_QUANTA.SOCKET4677_AZIF0045P001C01CS(CHIPS)':
 'UPI0_TX_DP21': CDS_PINID='UPI0_TX_DP21';
NET_NAME
'UPI_CPU1_CPU0_P0P1_DP<22>'
 '@S9S_MB_2U_LIB.S9S_MB_2U(SCH_1):UPI_CPU1_CPU0_P0P1_DP'<22>:
 C_SIGNAL='@s9s_mb_2u_lib.s9s_mb_2u(sch_1):upi_cpu1_cpu0_p0p1_dp(22)';
NODE_NAME     U2 CD2
 '@S9S_MB_2U_LIB.S9S_MB_2U(SCH_1):PAGE33_I102@PURE_QUANTA.SOCKET4677_AZIF0045P001C01CS(CHIPS)':
 'UPI1_RX_DN22': CDS_PINID='UPI1_RX_DN22';
NODE_NAME     U1 BN3
 '@S9S_MB_2U_LIB.S9S_MB_2U(SCH_1):PAGE63_I51@PURE_QUANTA.SOCKET4677_AZIF0045P001C01CS(CHIPS)':
 'UPI0_TX_DP22': CDS_PINID='UPI0_TX_DP22';
NET_NAME
'UPI_CPU1_CPU0_P0P1_DP<23>'
 '@S9S_MB_2U_LIB.S9S_MB_2U(SCH_1):UPI_CPU1_CPU0_P0P1_DP'<23>:
 C_SIGNAL='@s9s_mb_2u_lib.s9s_mb_2u(sch_1):upi_cpu1_cpu0_p0p1_dp(23)';
NODE_NAME     U2 CB2
 '@S9S_MB_2U_LIB.S9S_MB_2U(SCH_1):PAGE33_I102@PURE_QUANTA.SOCKET4677_AZIF0045P001C01CS(CHIPS)':
 'UPI1_RX_DN23': CDS_PINID='UPI1_RX_DN23';
NODE_NAME     U1 BU3
 '@S9S_MB_2U_LIB.S9S_MB_2U(SCH_1):PAGE63_I51@PURE_QUANTA.SOCKET4677_AZIF0045P001C01CS(CHIPS)':
 'UPI0_TX_DP23': CDS_PINID='UPI0_TX_DP23';
NET_NAME
'UPI_CPU1_CPU0_P0P1_DP<2>'
 '@S9S_MB_2U_LIB.S9S_MB_2U(SCH_1):UPI_CPU1_CPU0_P0P1_DP'<2>:
 C_SIGNAL='@s9s_mb_2u_lib.s9s_mb_2u(sch_1):upi_cpu1_cpu0_p0p1_dp(2)';
NODE_NAME     U2 ED2
 '@S9S_MB_2U_LIB.S9S_MB_2U(SCH_1):PAGE33_I102@PURE_QUANTA.SOCKET4677_AZIF0045P001C01CS(CHIPS)':
 'UPI1_RX_DN2': CDS_PINID='UPI1_RX_DN2';
NODE_NAME     U1 P2
 '@S9S_MB_2U_LIB.S9S_MB_2U(SCH_1):PAGE63_I51@PURE_QUANTA.SOCKET4677_AZIF0045P001C01CS(CHIPS)':
 'UPI0_TX_DP2': CDS_PINID='UPI0_TX_DP2';
NET_NAME
'UPI_CPU1_CPU0_P0P1_DP<3>'
 '@S9S_MB_2U_LIB.S9S_MB_2U(SCH_1):UPI_CPU1_CPU0_P0P1_DP'<3>:
 C_SIGNAL='@s9s_mb_2u_lib.s9s_mb_2u(sch_1):upi_cpu1_cpu0_p0p1_dp(3)';
NODE_NAME     U2 EB2
 '@S9S_MB_2U_LIB.S9S_MB_2U(SCH_1):PAGE33_I102@PURE_QUANTA.SOCKET4677_AZIF0045P001C01CS(CHIPS)':
 'UPI1_RX_DP3': CDS_PINID='UPI1_RX_DP3';
NODE_NAME     U1 R3
 '@S9S_MB_2U_LIB.S9S_MB_2U(SCH_1):PAGE63_I51@PURE_QUANTA.SOCKET4677_AZIF0045P001C01CS(CHIPS)':
 'UPI0_TX_DP3': CDS_PINID='UPI0_TX_DP3';
NET_NAME
'UPI_CPU1_CPU0_P0P1_DP<4>'
 '@S9S_MB_2U_LIB.S9S_MB_2U(SCH_1):UPI_CPU1_CPU0_P0P1_DP'<4>:
 C_SIGNAL='@s9s_mb_2u_lib.s9s_mb_2u(sch_1):upi_cpu1_cpu0_p0p1_dp(4)';
NODE_NAME     U2 DW3
 '@S9S_MB_2U_LIB.S9S_MB_2U(SCH_1):PAGE33_I102@PURE_QUANTA.SOCKET4677_AZIF0045P001C01CS(CHIPS)':
 'UPI1_RX_DP4': CDS_PINID='UPI1_RX_DP4';
NODE_NAME     U1 V2
 '@S9S_MB_2U_LIB.S9S_MB_2U(SCH_1):PAGE63_I51@PURE_QUANTA.SOCKET4677_AZIF0045P001C01CS(CHIPS)':
 'UPI0_TX_DP4': CDS_PINID='UPI0_TX_DP4';
NET_NAME
'UPI_CPU1_CPU0_P0P1_DP<5>'
 '@S9S_MB_2U_LIB.S9S_MB_2U(SCH_1):UPI_CPU1_CPU0_P0P1_DP'<5>:
 C_SIGNAL='@s9s_mb_2u_lib.s9s_mb_2u(sch_1):upi_cpu1_cpu0_p0p1_dp(5)';
NODE_NAME     U2 DV2
 '@S9S_MB_2U_LIB.S9S_MB_2U(SCH_1):PAGE33_I102@PURE_QUANTA.SOCKET4677_AZIF0045P001C01CS(CHIPS)':
 'UPI1_RX_DP5': CDS_PINID='UPI1_RX_DP5';
NODE_NAME     U1 W3
 '@S9S_MB_2U_LIB.S9S_MB_2U(SCH_1):PAGE63_I51@PURE_QUANTA.SOCKET4677_AZIF0045P001C01CS(CHIPS)':
 'UPI0_TX_DP5': CDS_PINID='UPI0_TX_DP5';
NET_NAME
'UPI_CPU1_CPU0_P0P1_DP<6>'
 '@S9S_MB_2U_LIB.S9S_MB_2U(SCH_1):UPI_CPU1_CPU0_P0P1_DP'<6>:
 C_SIGNAL='@s9s_mb_2u_lib.s9s_mb_2u(sch_1):upi_cpu1_cpu0_p0p1_dp(6)';
NODE_NAME     U2 DR3
 '@S9S_MB_2U_LIB.S9S_MB_2U(SCH_1):PAGE33_I102@PURE_QUANTA.SOCKET4677_AZIF0045P001C01CS(CHIPS)':
 'UPI1_RX_DP6': CDS_PINID='UPI1_RX_DP6';
NODE_NAME     U1 AB2
 '@S9S_MB_2U_LIB.S9S_MB_2U(SCH_1):PAGE63_I51@PURE_QUANTA.SOCKET4677_AZIF0045P001C01CS(CHIPS)':
 'UPI0_TX_DP6': CDS_PINID='UPI0_TX_DP6';
NET_NAME
'UPI_CPU1_CPU0_P0P1_DP<7>'
 '@S9S_MB_2U_LIB.S9S_MB_2U(SCH_1):UPI_CPU1_CPU0_P0P1_DP'<7>:
 C_SIGNAL='@s9s_mb_2u_lib.s9s_mb_2u(sch_1):upi_cpu1_cpu0_p0p1_dp(7)';
NODE_NAME     U2 DP2
 '@S9S_MB_2U_LIB.S9S_MB_2U(SCH_1):PAGE33_I102@PURE_QUANTA.SOCKET4677_AZIF0045P001C01CS(CHIPS)':
 'UPI1_RX_DP7': CDS_PINID='UPI1_RX_DP7';
NODE_NAME     U1 AC3
 '@S9S_MB_2U_LIB.S9S_MB_2U(SCH_1):PAGE63_I51@PURE_QUANTA.SOCKET4677_AZIF0045P001C01CS(CHIPS)':
 'UPI0_TX_DP7': CDS_PINID='UPI0_TX_DP7';
NET_NAME
'UPI_CPU1_CPU0_P0P1_DP<8>'
 '@S9S_MB_2U_LIB.S9S_MB_2U(SCH_1):UPI_CPU1_CPU0_P0P1_DP'<8>:
 C_SIGNAL='@s9s_mb_2u_lib.s9s_mb_2u(sch_1):upi_cpu1_cpu0_p0p1_dp(8)';
NODE_NAME     U2 DM2
 '@S9S_MB_2U_LIB.S9S_MB_2U(SCH_1):PAGE33_I102@PURE_QUANTA.SOCKET4677_AZIF0045P001C01CS(CHIPS)':
 'UPI1_RX_DP8': CDS_PINID='UPI1_RX_DP8';
NODE_NAME     U1 AE1
 '@S9S_MB_2U_LIB.S9S_MB_2U(SCH_1):PAGE63_I51@PURE_QUANTA.SOCKET4677_AZIF0045P001C01CS(CHIPS)':
 'UPI0_TX_DP8': CDS_PINID='UPI0_TX_DP8';
NET_NAME
'UPI_CPU1_CPU0_P0P1_DP<9>'
 '@S9S_MB_2U_LIB.S9S_MB_2U(SCH_1):UPI_CPU1_CPU0_P0P1_DP'<9>:
 C_SIGNAL='@s9s_mb_2u_lib.s9s_mb_2u(sch_1):upi_cpu1_cpu0_p0p1_dp(9)';
NODE_NAME     U2 DK2
 '@S9S_MB_2U_LIB.S9S_MB_2U(SCH_1):PAGE33_I102@PURE_QUANTA.SOCKET4677_AZIF0045P001C01CS(CHIPS)':
 'UPI1_RX_DP9': CDS_PINID='UPI1_RX_DP9';
NODE_NAME     U1 AG3
 '@S9S_MB_2U_LIB.S9S_MB_2U(SCH_1):PAGE63_I51@PURE_QUANTA.SOCKET4677_AZIF0045P001C01CS(CHIPS)':
 'UPI0_TX_DP9': CDS_PINID='UPI0_TX_DP9';
NET_NAME
'UPI_CPU1_CPU0_P1P0_DN<0>'
 '@S9S_MB_2U_LIB.S9S_MB_2U(SCH_1):UPI_CPU1_CPU0_P1P0_DN'<0>:
 C_SIGNAL='@s9s_mb_2u_lib.s9s_mb_2u(sch_1):upi_cpu1_cpu0_p1p0_dn(0)';
NODE_NAME     U2 K6
 '@S9S_MB_2U_LIB.S9S_MB_2U(SCH_1):PAGE32_I70@PURE_QUANTA.SOCKET4677_AZIF0045P001C01CS(CHIPS)':
 'UPI0_RX_DN0': CDS_PINID='UPI0_RX_DN0';
NODE_NAME     U1 EF6
 '@S9S_MB_2U_LIB.S9S_MB_2U(SCH_1):PAGE64_I21@PURE_QUANTA.SOCKET4677_AZIF0045P001C01CS(CHIPS)':
 'UPI1_TX_DN0': CDS_PINID='UPI1_TX_DN0';
NET_NAME
'UPI_CPU1_CPU0_P1P0_DN<10>'
 '@S9S_MB_2U_LIB.S9S_MB_2U(SCH_1):UPI_CPU1_CPU0_P1P0_DN'<10>:
 C_SIGNAL='@s9s_mb_2u_lib.s9s_mb_2u(sch_1):upi_cpu1_cpu0_p1p0_dn(10)';
NODE_NAME     U2 AL7
 '@S9S_MB_2U_LIB.S9S_MB_2U(SCH_1):PAGE32_I70@PURE_QUANTA.SOCKET4677_AZIF0045P001C01CS(CHIPS)':
 'UPI0_RX_DP10': CDS_PINID='UPI0_RX_DP10';
NODE_NAME     U1 DE5
 '@S9S_MB_2U_LIB.S9S_MB_2U(SCH_1):PAGE64_I21@PURE_QUANTA.SOCKET4677_AZIF0045P001C01CS(CHIPS)':
 'UPI1_TX_DN10': CDS_PINID='UPI1_TX_DN10';
NET_NAME
'UPI_CPU1_CPU0_P1P0_DN<11>'
 '@S9S_MB_2U_LIB.S9S_MB_2U(SCH_1):UPI_CPU1_CPU0_P1P0_DN'<11>:
 C_SIGNAL='@s9s_mb_2u_lib.s9s_mb_2u(sch_1):upi_cpu1_cpu0_p1p0_dn(11)';
NODE_NAME     U2 AM6
 '@S9S_MB_2U_LIB.S9S_MB_2U(SCH_1):PAGE32_I70@PURE_QUANTA.SOCKET4677_AZIF0045P001C01CS(CHIPS)':
 'UPI0_RX_DP11': CDS_PINID='UPI0_RX_DP11';
NODE_NAME     U1 DD6
 '@S9S_MB_2U_LIB.S9S_MB_2U(SCH_1):PAGE64_I21@PURE_QUANTA.SOCKET4677_AZIF0045P001C01CS(CHIPS)':
 'UPI1_TX_DN11': CDS_PINID='UPI1_TX_DN11';
NET_NAME
'UPI_CPU1_CPU0_P1P0_DN<12>'
 '@S9S_MB_2U_LIB.S9S_MB_2U(SCH_1):UPI_CPU1_CPU0_P1P0_DN'<12>:
 C_SIGNAL='@s9s_mb_2u_lib.s9s_mb_2u(sch_1):upi_cpu1_cpu0_p1p0_dn(12)';
NODE_NAME     U2 AR7
 '@S9S_MB_2U_LIB.S9S_MB_2U(SCH_1):PAGE32_I70@PURE_QUANTA.SOCKET4677_AZIF0045P001C01CS(CHIPS)':
 'UPI0_RX_DP12': CDS_PINID='UPI0_RX_DP12';
NODE_NAME     U1 DA5
 '@S9S_MB_2U_LIB.S9S_MB_2U(SCH_1):PAGE64_I21@PURE_QUANTA.SOCKET4677_AZIF0045P001C01CS(CHIPS)':
 'UPI1_TX_DN12': CDS_PINID='UPI1_TX_DN12';
NET_NAME
'UPI_CPU1_CPU0_P1P0_DN<13>'
 '@S9S_MB_2U_LIB.S9S_MB_2U(SCH_1):UPI_CPU1_CPU0_P1P0_DN'<13>:
 C_SIGNAL='@s9s_mb_2u_lib.s9s_mb_2u(sch_1):upi_cpu1_cpu0_p1p0_dn(13)';
NODE_NAME     U2 AT6
 '@S9S_MB_2U_LIB.S9S_MB_2U(SCH_1):PAGE32_I70@PURE_QUANTA.SOCKET4677_AZIF0045P001C01CS(CHIPS)':
 'UPI0_RX_DP13': CDS_PINID='UPI0_RX_DP13';
NODE_NAME     U1 CY6
 '@S9S_MB_2U_LIB.S9S_MB_2U(SCH_1):PAGE64_I21@PURE_QUANTA.SOCKET4677_AZIF0045P001C01CS(CHIPS)':
 'UPI1_TX_DN13': CDS_PINID='UPI1_TX_DN13';
NET_NAME
'UPI_CPU1_CPU0_P1P0_DN<14>'
 '@S9S_MB_2U_LIB.S9S_MB_2U(SCH_1):UPI_CPU1_CPU0_P1P0_DN'<14>:
 C_SIGNAL='@s9s_mb_2u_lib.s9s_mb_2u(sch_1):upi_cpu1_cpu0_p1p0_dn(14)';
NODE_NAME     U2 AW7
 '@S9S_MB_2U_LIB.S9S_MB_2U(SCH_1):PAGE32_I70@PURE_QUANTA.SOCKET4677_AZIF0045P001C01CS(CHIPS)':
 'UPI0_RX_DP14': CDS_PINID='UPI0_RX_DP14';
NODE_NAME     U1 CU5
 '@S9S_MB_2U_LIB.S9S_MB_2U(SCH_1):PAGE64_I21@PURE_QUANTA.SOCKET4677_AZIF0045P001C01CS(CHIPS)':
 'UPI1_TX_DN14': CDS_PINID='UPI1_TX_DN14';
NET_NAME
'UPI_CPU1_CPU0_P1P0_DN<15>'
 '@S9S_MB_2U_LIB.S9S_MB_2U(SCH_1):UPI_CPU1_CPU0_P1P0_DN'<15>:
 C_SIGNAL='@s9s_mb_2u_lib.s9s_mb_2u(sch_1):upi_cpu1_cpu0_p1p0_dn(15)';
NODE_NAME     U2 AY6
 '@S9S_MB_2U_LIB.S9S_MB_2U(SCH_1):PAGE32_I70@PURE_QUANTA.SOCKET4677_AZIF0045P001C01CS(CHIPS)':
 'UPI0_RX_DP15': CDS_PINID='UPI0_RX_DP15';
NODE_NAME     U1 CT6
 '@S9S_MB_2U_LIB.S9S_MB_2U(SCH_1):PAGE64_I21@PURE_QUANTA.SOCKET4677_AZIF0045P001C01CS(CHIPS)':
 'UPI1_TX_DN15': CDS_PINID='UPI1_TX_DN15';
NET_NAME
'UPI_CPU1_CPU0_P1P0_DN<16>'
 '@S9S_MB_2U_LIB.S9S_MB_2U(SCH_1):UPI_CPU1_CPU0_P1P0_DN'<16>:
 C_SIGNAL='@s9s_mb_2u_lib.s9s_mb_2u(sch_1):upi_cpu1_cpu0_p1p0_dn(16)';
NODE_NAME     U2 BC7
 '@S9S_MB_2U_LIB.S9S_MB_2U(SCH_1):PAGE32_I70@PURE_QUANTA.SOCKET4677_AZIF0045P001C01CS(CHIPS)':
 'UPI0_RX_DP16': CDS_PINID='UPI0_RX_DP16';
NODE_NAME     U1 CN5
 '@S9S_MB_2U_LIB.S9S_MB_2U(SCH_1):PAGE64_I21@PURE_QUANTA.SOCKET4677_AZIF0045P001C01CS(CHIPS)':
 'UPI1_TX_DN16': CDS_PINID='UPI1_TX_DN16';
NET_NAME
'UPI_CPU1_CPU0_P1P0_DN<17>'
 '@S9S_MB_2U_LIB.S9S_MB_2U(SCH_1):UPI_CPU1_CPU0_P1P0_DN'<17>:
 C_SIGNAL='@s9s_mb_2u_lib.s9s_mb_2u(sch_1):upi_cpu1_cpu0_p1p0_dn(17)';
NODE_NAME     U2 BD6
 '@S9S_MB_2U_LIB.S9S_MB_2U(SCH_1):PAGE32_I70@PURE_QUANTA.SOCKET4677_AZIF0045P001C01CS(CHIPS)':
 'UPI0_RX_DP17': CDS_PINID='UPI0_RX_DP17';
NODE_NAME     U1 CM6
 '@S9S_MB_2U_LIB.S9S_MB_2U(SCH_1):PAGE64_I21@PURE_QUANTA.SOCKET4677_AZIF0045P001C01CS(CHIPS)':
 'UPI1_TX_DN17': CDS_PINID='UPI1_TX_DN17';
NET_NAME
'UPI_CPU1_CPU0_P1P0_DN<18>'
 '@S9S_MB_2U_LIB.S9S_MB_2U(SCH_1):UPI_CPU1_CPU0_P1P0_DN'<18>:
 C_SIGNAL='@s9s_mb_2u_lib.s9s_mb_2u(sch_1):upi_cpu1_cpu0_p1p0_dn(18)';
NODE_NAME     U2 BG7
 '@S9S_MB_2U_LIB.S9S_MB_2U(SCH_1):PAGE32_I70@PURE_QUANTA.SOCKET4677_AZIF0045P001C01CS(CHIPS)':
 'UPI0_RX_DP18': CDS_PINID='UPI0_RX_DP18';
NODE_NAME     U1 CJ5
 '@S9S_MB_2U_LIB.S9S_MB_2U(SCH_1):PAGE64_I21@PURE_QUANTA.SOCKET4677_AZIF0045P001C01CS(CHIPS)':
 'UPI1_TX_DN18': CDS_PINID='UPI1_TX_DN18';
NET_NAME
'UPI_CPU1_CPU0_P1P0_DN<19>'
 '@S9S_MB_2U_LIB.S9S_MB_2U(SCH_1):UPI_CPU1_CPU0_P1P0_DN'<19>:
 C_SIGNAL='@s9s_mb_2u_lib.s9s_mb_2u(sch_1):upi_cpu1_cpu0_p1p0_dn(19)';
NODE_NAME     U2 BH6
 '@S9S_MB_2U_LIB.S9S_MB_2U(SCH_1):PAGE32_I70@PURE_QUANTA.SOCKET4677_AZIF0045P001C01CS(CHIPS)':
 'UPI0_RX_DP19': CDS_PINID='UPI0_RX_DP19';
NODE_NAME     U1 CH6
 '@S9S_MB_2U_LIB.S9S_MB_2U(SCH_1):PAGE64_I21@PURE_QUANTA.SOCKET4677_AZIF0045P001C01CS(CHIPS)':
 'UPI1_TX_DN19': CDS_PINID='UPI1_TX_DN19';
NET_NAME
'UPI_CPU1_CPU0_P1P0_DN<1>'
 '@S9S_MB_2U_LIB.S9S_MB_2U(SCH_1):UPI_CPU1_CPU0_P1P0_DN'<1>:
 C_SIGNAL='@s9s_mb_2u_lib.s9s_mb_2u(sch_1):upi_cpu1_cpu0_p1p0_dn(1)';
NODE_NAME     U2 N5
 '@S9S_MB_2U_LIB.S9S_MB_2U(SCH_1):PAGE32_I70@PURE_QUANTA.SOCKET4677_AZIF0045P001C01CS(CHIPS)':
 'UPI0_RX_DN1': CDS_PINID='UPI0_RX_DN1';
NODE_NAME     U1 EC7
 '@S9S_MB_2U_LIB.S9S_MB_2U(SCH_1):PAGE64_I21@PURE_QUANTA.SOCKET4677_AZIF0045P001C01CS(CHIPS)':
 'UPI1_TX_DN1': CDS_PINID='UPI1_TX_DN1';
NET_NAME
'UPI_CPU1_CPU0_P1P0_DN<20>'
 '@S9S_MB_2U_LIB.S9S_MB_2U(SCH_1):UPI_CPU1_CPU0_P1P0_DN'<20>:
 C_SIGNAL='@s9s_mb_2u_lib.s9s_mb_2u(sch_1):upi_cpu1_cpu0_p1p0_dn(20)';
NODE_NAME     U2 BL7
 '@S9S_MB_2U_LIB.S9S_MB_2U(SCH_1):PAGE32_I70@PURE_QUANTA.SOCKET4677_AZIF0045P001C01CS(CHIPS)':
 'UPI0_RX_DP20': CDS_PINID='UPI0_RX_DP20';
NODE_NAME     U1 CE5
 '@S9S_MB_2U_LIB.S9S_MB_2U(SCH_1):PAGE64_I21@PURE_QUANTA.SOCKET4677_AZIF0045P001C01CS(CHIPS)':
 'UPI1_TX_DN20': CDS_PINID='UPI1_TX_DN20';
NET_NAME
'UPI_CPU1_CPU0_P1P0_DN<21>'
 '@S9S_MB_2U_LIB.S9S_MB_2U(SCH_1):UPI_CPU1_CPU0_P1P0_DN'<21>:
 C_SIGNAL='@s9s_mb_2u_lib.s9s_mb_2u(sch_1):upi_cpu1_cpu0_p1p0_dn(21)';
NODE_NAME     U2 BM6
 '@S9S_MB_2U_LIB.S9S_MB_2U(SCH_1):PAGE32_I70@PURE_QUANTA.SOCKET4677_AZIF0045P001C01CS(CHIPS)':
 'UPI0_RX_DP21': CDS_PINID='UPI0_RX_DP21';
NODE_NAME     U1 CD6
 '@S9S_MB_2U_LIB.S9S_MB_2U(SCH_1):PAGE64_I21@PURE_QUANTA.SOCKET4677_AZIF0045P001C01CS(CHIPS)':
 'UPI1_TX_DN21': CDS_PINID='UPI1_TX_DN21';
NET_NAME
'UPI_CPU1_CPU0_P1P0_DN<22>'
 '@S9S_MB_2U_LIB.S9S_MB_2U(SCH_1):UPI_CPU1_CPU0_P1P0_DN'<22>:
 C_SIGNAL='@s9s_mb_2u_lib.s9s_mb_2u(sch_1):upi_cpu1_cpu0_p1p0_dn(22)';
NODE_NAME     U2 BR7
 '@S9S_MB_2U_LIB.S9S_MB_2U(SCH_1):PAGE32_I70@PURE_QUANTA.SOCKET4677_AZIF0045P001C01CS(CHIPS)':
 'UPI0_RX_DN22': CDS_PINID='UPI0_RX_DN22';
NODE_NAME     U1 CA5
 '@S9S_MB_2U_LIB.S9S_MB_2U(SCH_1):PAGE64_I21@PURE_QUANTA.SOCKET4677_AZIF0045P001C01CS(CHIPS)':
 'UPI1_TX_DN22': CDS_PINID='UPI1_TX_DN22';
NET_NAME
'UPI_CPU1_CPU0_P1P0_DN<23>'
 '@S9S_MB_2U_LIB.S9S_MB_2U(SCH_1):UPI_CPU1_CPU0_P1P0_DN'<23>:
 C_SIGNAL='@s9s_mb_2u_lib.s9s_mb_2u(sch_1):upi_cpu1_cpu0_p1p0_dn(23)';
NODE_NAME     U2 BT6
 '@S9S_MB_2U_LIB.S9S_MB_2U(SCH_1):PAGE32_I70@PURE_QUANTA.SOCKET4677_AZIF0045P001C01CS(CHIPS)':
 'UPI0_RX_DP23': CDS_PINID='UPI0_RX_DP23';
NODE_NAME     U1 BY6
 '@S9S_MB_2U_LIB.S9S_MB_2U(SCH_1):PAGE64_I21@PURE_QUANTA.SOCKET4677_AZIF0045P001C01CS(CHIPS)':
 'UPI1_TX_DN23': CDS_PINID='UPI1_TX_DN23';
NET_NAME
'UPI_CPU1_CPU0_P1P0_DN<2>'
 '@S9S_MB_2U_LIB.S9S_MB_2U(SCH_1):UPI_CPU1_CPU0_P1P0_DN'<2>:
 C_SIGNAL='@s9s_mb_2u_lib.s9s_mb_2u(sch_1):upi_cpu1_cpu0_p1p0_dn(2)';
NODE_NAME     U2 P6
 '@S9S_MB_2U_LIB.S9S_MB_2U(SCH_1):PAGE32_I70@PURE_QUANTA.SOCKET4677_AZIF0045P001C01CS(CHIPS)':
 'UPI0_RX_DN2': CDS_PINID='UPI0_RX_DN2';
NODE_NAME     U1 EB6
 '@S9S_MB_2U_LIB.S9S_MB_2U(SCH_1):PAGE64_I21@PURE_QUANTA.SOCKET4677_AZIF0045P001C01CS(CHIPS)':
 'UPI1_TX_DN2': CDS_PINID='UPI1_TX_DN2';
NET_NAME
'UPI_CPU1_CPU0_P1P0_DN<3>'
 '@S9S_MB_2U_LIB.S9S_MB_2U(SCH_1):UPI_CPU1_CPU0_P1P0_DN'<3>:
 C_SIGNAL='@s9s_mb_2u_lib.s9s_mb_2u(sch_1):upi_cpu1_cpu0_p1p0_dn(3)';
NODE_NAME     U2 T6
 '@S9S_MB_2U_LIB.S9S_MB_2U(SCH_1):PAGE32_I70@PURE_QUANTA.SOCKET4677_AZIF0045P001C01CS(CHIPS)':
 'UPI0_RX_DP3': CDS_PINID='UPI0_RX_DP3';
NODE_NAME     U1 DY6
 '@S9S_MB_2U_LIB.S9S_MB_2U(SCH_1):PAGE64_I21@PURE_QUANTA.SOCKET4677_AZIF0045P001C01CS(CHIPS)':
 'UPI1_TX_DN3': CDS_PINID='UPI1_TX_DN3';
NET_NAME
'UPI_CPU1_CPU0_P1P0_DN<4>'
 '@S9S_MB_2U_LIB.S9S_MB_2U(SCH_1):UPI_CPU1_CPU0_P1P0_DN'<4>:
 C_SIGNAL='@s9s_mb_2u_lib.s9s_mb_2u(sch_1):upi_cpu1_cpu0_p1p0_dn(4)';
NODE_NAME     U2 V6
 '@S9S_MB_2U_LIB.S9S_MB_2U(SCH_1):PAGE32_I70@PURE_QUANTA.SOCKET4677_AZIF0045P001C01CS(CHIPS)':
 'UPI0_RX_DN4': CDS_PINID='UPI0_RX_DN4';
NODE_NAME     U1 DV6
 '@S9S_MB_2U_LIB.S9S_MB_2U(SCH_1):PAGE64_I21@PURE_QUANTA.SOCKET4677_AZIF0045P001C01CS(CHIPS)':
 'UPI1_TX_DN4': CDS_PINID='UPI1_TX_DN4';
NET_NAME
'UPI_CPU1_CPU0_P1P0_DN<5>'
 '@S9S_MB_2U_LIB.S9S_MB_2U(SCH_1):UPI_CPU1_CPU0_P1P0_DN'<5>:
 C_SIGNAL='@s9s_mb_2u_lib.s9s_mb_2u(sch_1):upi_cpu1_cpu0_p1p0_dn(5)';
NODE_NAME     U2 Y6
 '@S9S_MB_2U_LIB.S9S_MB_2U(SCH_1):PAGE32_I70@PURE_QUANTA.SOCKET4677_AZIF0045P001C01CS(CHIPS)':
 'UPI0_RX_DP5': CDS_PINID='UPI0_RX_DP5';
NODE_NAME     U1 DT6
 '@S9S_MB_2U_LIB.S9S_MB_2U(SCH_1):PAGE64_I21@PURE_QUANTA.SOCKET4677_AZIF0045P001C01CS(CHIPS)':
 'UPI1_TX_DN5': CDS_PINID='UPI1_TX_DN5';
NET_NAME
'UPI_CPU1_CPU0_P1P0_DN<6>'
 '@S9S_MB_2U_LIB.S9S_MB_2U(SCH_1):UPI_CPU1_CPU0_P1P0_DN'<6>:
 C_SIGNAL='@s9s_mb_2u_lib.s9s_mb_2u(sch_1):upi_cpu1_cpu0_p1p0_dn(6)';
NODE_NAME     U2 AB6
 '@S9S_MB_2U_LIB.S9S_MB_2U(SCH_1):PAGE32_I70@PURE_QUANTA.SOCKET4677_AZIF0045P001C01CS(CHIPS)':
 'UPI0_RX_DN6': CDS_PINID='UPI0_RX_DN6';
NODE_NAME     U1 DP6
 '@S9S_MB_2U_LIB.S9S_MB_2U(SCH_1):PAGE64_I21@PURE_QUANTA.SOCKET4677_AZIF0045P001C01CS(CHIPS)':
 'UPI1_TX_DN6': CDS_PINID='UPI1_TX_DN6';
NET_NAME
'UPI_CPU1_CPU0_P1P0_DN<7>'
 '@S9S_MB_2U_LIB.S9S_MB_2U(SCH_1):UPI_CPU1_CPU0_P1P0_DN'<7>:
 C_SIGNAL='@s9s_mb_2u_lib.s9s_mb_2u(sch_1):upi_cpu1_cpu0_p1p0_dn(7)';
NODE_NAME     U2 AE5
 '@S9S_MB_2U_LIB.S9S_MB_2U(SCH_1):PAGE32_I70@PURE_QUANTA.SOCKET4677_AZIF0045P001C01CS(CHIPS)':
 'UPI0_RX_DN7': CDS_PINID='UPI0_RX_DN7';
NODE_NAME     U1 DL7
 '@S9S_MB_2U_LIB.S9S_MB_2U(SCH_1):PAGE64_I21@PURE_QUANTA.SOCKET4677_AZIF0045P001C01CS(CHIPS)':
 'UPI1_TX_DN7': CDS_PINID='UPI1_TX_DN7';
NET_NAME
'UPI_CPU1_CPU0_P1P0_DN<8>'
 '@S9S_MB_2U_LIB.S9S_MB_2U(SCH_1):UPI_CPU1_CPU0_P1P0_DN'<8>:
 C_SIGNAL='@s9s_mb_2u_lib.s9s_mb_2u(sch_1):upi_cpu1_cpu0_p1p0_dn(8)';
NODE_NAME     U2 AF6
 '@S9S_MB_2U_LIB.S9S_MB_2U(SCH_1):PAGE32_I70@PURE_QUANTA.SOCKET4677_AZIF0045P001C01CS(CHIPS)':
 'UPI0_RX_DN8': CDS_PINID='UPI0_RX_DN8';
NODE_NAME     U1 DK6
 '@S9S_MB_2U_LIB.S9S_MB_2U(SCH_1):PAGE64_I21@PURE_QUANTA.SOCKET4677_AZIF0045P001C01CS(CHIPS)':
 'UPI1_TX_DN8': CDS_PINID='UPI1_TX_DN8';
NET_NAME
'UPI_CPU1_CPU0_P1P0_DN<9>'
 '@S9S_MB_2U_LIB.S9S_MB_2U(SCH_1):UPI_CPU1_CPU0_P1P0_DN'<9>:
 C_SIGNAL='@s9s_mb_2u_lib.s9s_mb_2u(sch_1):upi_cpu1_cpu0_p1p0_dn(9)';
NODE_NAME     U2 AH6
 '@S9S_MB_2U_LIB.S9S_MB_2U(SCH_1):PAGE32_I70@PURE_QUANTA.SOCKET4677_AZIF0045P001C01CS(CHIPS)':
 'UPI0_RX_DN9': CDS_PINID='UPI0_RX_DN9';
NODE_NAME     U1 DH6
 '@S9S_MB_2U_LIB.S9S_MB_2U(SCH_1):PAGE64_I21@PURE_QUANTA.SOCKET4677_AZIF0045P001C01CS(CHIPS)':
 'UPI1_TX_DN9': CDS_PINID='UPI1_TX_DN9';
NET_NAME
'UPI_CPU1_CPU0_P1P0_DP<0>'
 '@S9S_MB_2U_LIB.S9S_MB_2U(SCH_1):UPI_CPU1_CPU0_P1P0_DP'<0>:
 C_SIGNAL='@s9s_mb_2u_lib.s9s_mb_2u(sch_1):upi_cpu1_cpu0_p1p0_dp(0)';
NODE_NAME     U2 L7
 '@S9S_MB_2U_LIB.S9S_MB_2U(SCH_1):PAGE32_I70@PURE_QUANTA.SOCKET4677_AZIF0045P001C01CS(CHIPS)':
 'UPI0_RX_DP0': CDS_PINID='UPI0_RX_DP0';
NODE_NAME     U1 EE5
 '@S9S_MB_2U_LIB.S9S_MB_2U(SCH_1):PAGE64_I21@PURE_QUANTA.SOCKET4677_AZIF0045P001C01CS(CHIPS)':
 'UPI1_TX_DP0': CDS_PINID='UPI1_TX_DP0';
NET_NAME
'UPI_CPU1_CPU0_P1P0_DP<10>'
 '@S9S_MB_2U_LIB.S9S_MB_2U(SCH_1):UPI_CPU1_CPU0_P1P0_DP'<10>:
 C_SIGNAL='@s9s_mb_2u_lib.s9s_mb_2u(sch_1):upi_cpu1_cpu0_p1p0_dp(10)';
NODE_NAME     U2 AK6
 '@S9S_MB_2U_LIB.S9S_MB_2U(SCH_1):PAGE32_I70@PURE_QUANTA.SOCKET4677_AZIF0045P001C01CS(CHIPS)':
 'UPI0_RX_DN10': CDS_PINID='UPI0_RX_DN10';
NODE_NAME     U1 DF6
 '@S9S_MB_2U_LIB.S9S_MB_2U(SCH_1):PAGE64_I21@PURE_QUANTA.SOCKET4677_AZIF0045P001C01CS(CHIPS)':
 'UPI1_TX_DP10': CDS_PINID='UPI1_TX_DP10';
NET_NAME
'UPI_CPU1_CPU0_P1P0_DP<11>'
 '@S9S_MB_2U_LIB.S9S_MB_2U(SCH_1):UPI_CPU1_CPU0_P1P0_DP'<11>:
 C_SIGNAL='@s9s_mb_2u_lib.s9s_mb_2u(sch_1):upi_cpu1_cpu0_p1p0_dp(11)';
NODE_NAME     U2 AN5
 '@S9S_MB_2U_LIB.S9S_MB_2U(SCH_1):PAGE32_I70@PURE_QUANTA.SOCKET4677_AZIF0045P001C01CS(CHIPS)':
 'UPI0_RX_DN11': CDS_PINID='UPI0_RX_DN11';
NODE_NAME     U1 DC7
 '@S9S_MB_2U_LIB.S9S_MB_2U(SCH_1):PAGE64_I21@PURE_QUANTA.SOCKET4677_AZIF0045P001C01CS(CHIPS)':
 'UPI1_TX_DP11': CDS_PINID='UPI1_TX_DP11';
NET_NAME
'UPI_CPU1_CPU0_P1P0_DP<12>'
 '@S9S_MB_2U_LIB.S9S_MB_2U(SCH_1):UPI_CPU1_CPU0_P1P0_DP'<12>:
 C_SIGNAL='@s9s_mb_2u_lib.s9s_mb_2u(sch_1):upi_cpu1_cpu0_p1p0_dp(12)';
NODE_NAME     U2 AP6
 '@S9S_MB_2U_LIB.S9S_MB_2U(SCH_1):PAGE32_I70@PURE_QUANTA.SOCKET4677_AZIF0045P001C01CS(CHIPS)':
 'UPI0_RX_DN12': CDS_PINID='UPI0_RX_DN12';
NODE_NAME     U1 DB6
 '@S9S_MB_2U_LIB.S9S_MB_2U(SCH_1):PAGE64_I21@PURE_QUANTA.SOCKET4677_AZIF0045P001C01CS(CHIPS)':
 'UPI1_TX_DP12': CDS_PINID='UPI1_TX_DP12';
NET_NAME
'UPI_CPU1_CPU0_P1P0_DP<13>'
 '@S9S_MB_2U_LIB.S9S_MB_2U(SCH_1):UPI_CPU1_CPU0_P1P0_DP'<13>:
 C_SIGNAL='@s9s_mb_2u_lib.s9s_mb_2u(sch_1):upi_cpu1_cpu0_p1p0_dp(13)';
NODE_NAME     U2 AU5
 '@S9S_MB_2U_LIB.S9S_MB_2U(SCH_1):PAGE32_I70@PURE_QUANTA.SOCKET4677_AZIF0045P001C01CS(CHIPS)':
 'UPI0_RX_DN13': CDS_PINID='UPI0_RX_DN13';
NODE_NAME     U1 CW7
 '@S9S_MB_2U_LIB.S9S_MB_2U(SCH_1):PAGE64_I21@PURE_QUANTA.SOCKET4677_AZIF0045P001C01CS(CHIPS)':
 'UPI1_TX_DP13': CDS_PINID='UPI1_TX_DP13';
NET_NAME
'UPI_CPU1_CPU0_P1P0_DP<14>'
 '@S9S_MB_2U_LIB.S9S_MB_2U(SCH_1):UPI_CPU1_CPU0_P1P0_DP'<14>:
 C_SIGNAL='@s9s_mb_2u_lib.s9s_mb_2u(sch_1):upi_cpu1_cpu0_p1p0_dp(14)';
NODE_NAME     U2 AV6
 '@S9S_MB_2U_LIB.S9S_MB_2U(SCH_1):PAGE32_I70@PURE_QUANTA.SOCKET4677_AZIF0045P001C01CS(CHIPS)':
 'UPI0_RX_DN14': CDS_PINID='UPI0_RX_DN14';
NODE_NAME     U1 CV6
 '@S9S_MB_2U_LIB.S9S_MB_2U(SCH_1):PAGE64_I21@PURE_QUANTA.SOCKET4677_AZIF0045P001C01CS(CHIPS)':
 'UPI1_TX_DP14': CDS_PINID='UPI1_TX_DP14';
NET_NAME
'UPI_CPU1_CPU0_P1P0_DP<15>'
 '@S9S_MB_2U_LIB.S9S_MB_2U(SCH_1):UPI_CPU1_CPU0_P1P0_DP'<15>:
 C_SIGNAL='@s9s_mb_2u_lib.s9s_mb_2u(sch_1):upi_cpu1_cpu0_p1p0_dp(15)';
NODE_NAME     U2 BA5
 '@S9S_MB_2U_LIB.S9S_MB_2U(SCH_1):PAGE32_I70@PURE_QUANTA.SOCKET4677_AZIF0045P001C01CS(CHIPS)':
 'UPI0_RX_DN15': CDS_PINID='UPI0_RX_DN15';
NODE_NAME     U1 CR7
 '@S9S_MB_2U_LIB.S9S_MB_2U(SCH_1):PAGE64_I21@PURE_QUANTA.SOCKET4677_AZIF0045P001C01CS(CHIPS)':
 'UPI1_TX_DP15': CDS_PINID='UPI1_TX_DP15';
NET_NAME
'UPI_CPU1_CPU0_P1P0_DP<16>'
 '@S9S_MB_2U_LIB.S9S_MB_2U(SCH_1):UPI_CPU1_CPU0_P1P0_DP'<16>:
 C_SIGNAL='@s9s_mb_2u_lib.s9s_mb_2u(sch_1):upi_cpu1_cpu0_p1p0_dp(16)';
NODE_NAME     U2 BB6
 '@S9S_MB_2U_LIB.S9S_MB_2U(SCH_1):PAGE32_I70@PURE_QUANTA.SOCKET4677_AZIF0045P001C01CS(CHIPS)':
 'UPI0_RX_DN16': CDS_PINID='UPI0_RX_DN16';
NODE_NAME     U1 CP6
 '@S9S_MB_2U_LIB.S9S_MB_2U(SCH_1):PAGE64_I21@PURE_QUANTA.SOCKET4677_AZIF0045P001C01CS(CHIPS)':
 'UPI1_TX_DP16': CDS_PINID='UPI1_TX_DP16';
NET_NAME
'UPI_CPU1_CPU0_P1P0_DP<17>'
 '@S9S_MB_2U_LIB.S9S_MB_2U(SCH_1):UPI_CPU1_CPU0_P1P0_DP'<17>:
 C_SIGNAL='@s9s_mb_2u_lib.s9s_mb_2u(sch_1):upi_cpu1_cpu0_p1p0_dp(17)';
NODE_NAME     U2 BE5
 '@S9S_MB_2U_LIB.S9S_MB_2U(SCH_1):PAGE32_I70@PURE_QUANTA.SOCKET4677_AZIF0045P001C01CS(CHIPS)':
 'UPI0_RX_DN17': CDS_PINID='UPI0_RX_DN17';
NODE_NAME     U1 CL7
 '@S9S_MB_2U_LIB.S9S_MB_2U(SCH_1):PAGE64_I21@PURE_QUANTA.SOCKET4677_AZIF0045P001C01CS(CHIPS)':
 'UPI1_TX_DP17': CDS_PINID='UPI1_TX_DP17';
NET_NAME
'UPI_CPU1_CPU0_P1P0_DP<18>'
 '@S9S_MB_2U_LIB.S9S_MB_2U(SCH_1):UPI_CPU1_CPU0_P1P0_DP'<18>:
 C_SIGNAL='@s9s_mb_2u_lib.s9s_mb_2u(sch_1):upi_cpu1_cpu0_p1p0_dp(18)';
NODE_NAME     U2 BF6
 '@S9S_MB_2U_LIB.S9S_MB_2U(SCH_1):PAGE32_I70@PURE_QUANTA.SOCKET4677_AZIF0045P001C01CS(CHIPS)':
 'UPI0_RX_DN18': CDS_PINID='UPI0_RX_DN18';
NODE_NAME     U1 CK6
 '@S9S_MB_2U_LIB.S9S_MB_2U(SCH_1):PAGE64_I21@PURE_QUANTA.SOCKET4677_AZIF0045P001C01CS(CHIPS)':
 'UPI1_TX_DP18': CDS_PINID='UPI1_TX_DP18';
NET_NAME
'UPI_CPU1_CPU0_P1P0_DP<19>'
 '@S9S_MB_2U_LIB.S9S_MB_2U(SCH_1):UPI_CPU1_CPU0_P1P0_DP'<19>:
 C_SIGNAL='@s9s_mb_2u_lib.s9s_mb_2u(sch_1):upi_cpu1_cpu0_p1p0_dp(19)';
NODE_NAME     U2 BJ5
 '@S9S_MB_2U_LIB.S9S_MB_2U(SCH_1):PAGE32_I70@PURE_QUANTA.SOCKET4677_AZIF0045P001C01CS(CHIPS)':
 'UPI0_RX_DN19': CDS_PINID='UPI0_RX_DN19';
NODE_NAME     U1 CG7
 '@S9S_MB_2U_LIB.S9S_MB_2U(SCH_1):PAGE64_I21@PURE_QUANTA.SOCKET4677_AZIF0045P001C01CS(CHIPS)':
 'UPI1_TX_DP19': CDS_PINID='UPI1_TX_DP19';
NET_NAME
'UPI_CPU1_CPU0_P1P0_DP<1>'
 '@S9S_MB_2U_LIB.S9S_MB_2U(SCH_1):UPI_CPU1_CPU0_P1P0_DP'<1>:
 C_SIGNAL='@s9s_mb_2u_lib.s9s_mb_2u(sch_1):upi_cpu1_cpu0_p1p0_dp(1)';
NODE_NAME     U2 M6
 '@S9S_MB_2U_LIB.S9S_MB_2U(SCH_1):PAGE32_I70@PURE_QUANTA.SOCKET4677_AZIF0045P001C01CS(CHIPS)':
 'UPI0_RX_DP1': CDS_PINID='UPI0_RX_DP1';
NODE_NAME     U1 ED6
 '@S9S_MB_2U_LIB.S9S_MB_2U(SCH_1):PAGE64_I21@PURE_QUANTA.SOCKET4677_AZIF0045P001C01CS(CHIPS)':
 'UPI1_TX_DP1': CDS_PINID='UPI1_TX_DP1';
NET_NAME
'UPI_CPU1_CPU0_P1P0_DP<20>'
 '@S9S_MB_2U_LIB.S9S_MB_2U(SCH_1):UPI_CPU1_CPU0_P1P0_DP'<20>:
 C_SIGNAL='@s9s_mb_2u_lib.s9s_mb_2u(sch_1):upi_cpu1_cpu0_p1p0_dp(20)';
NODE_NAME     U2 BK6
 '@S9S_MB_2U_LIB.S9S_MB_2U(SCH_1):PAGE32_I70@PURE_QUANTA.SOCKET4677_AZIF0045P001C01CS(CHIPS)':
 'UPI0_RX_DN20': CDS_PINID='UPI0_RX_DN20';
NODE_NAME     U1 CF6
 '@S9S_MB_2U_LIB.S9S_MB_2U(SCH_1):PAGE64_I21@PURE_QUANTA.SOCKET4677_AZIF0045P001C01CS(CHIPS)':
 'UPI1_TX_DP20': CDS_PINID='UPI1_TX_DP20';
NET_NAME
'UPI_CPU1_CPU0_P1P0_DP<21>'
 '@S9S_MB_2U_LIB.S9S_MB_2U(SCH_1):UPI_CPU1_CPU0_P1P0_DP'<21>:
 C_SIGNAL='@s9s_mb_2u_lib.s9s_mb_2u(sch_1):upi_cpu1_cpu0_p1p0_dp(21)';
NODE_NAME     U2 BN5
 '@S9S_MB_2U_LIB.S9S_MB_2U(SCH_1):PAGE32_I70@PURE_QUANTA.SOCKET4677_AZIF0045P001C01CS(CHIPS)':
 'UPI0_RX_DN21': CDS_PINID='UPI0_RX_DN21';
NODE_NAME     U1 CC7
 '@S9S_MB_2U_LIB.S9S_MB_2U(SCH_1):PAGE64_I21@PURE_QUANTA.SOCKET4677_AZIF0045P001C01CS(CHIPS)':
 'UPI1_TX_DP21': CDS_PINID='UPI1_TX_DP21';
NET_NAME
'UPI_CPU1_CPU0_P1P0_DP<22>'
 '@S9S_MB_2U_LIB.S9S_MB_2U(SCH_1):UPI_CPU1_CPU0_P1P0_DP'<22>:
 C_SIGNAL='@s9s_mb_2u_lib.s9s_mb_2u(sch_1):upi_cpu1_cpu0_p1p0_dp(22)';
NODE_NAME     U2 BP6
 '@S9S_MB_2U_LIB.S9S_MB_2U(SCH_1):PAGE32_I70@PURE_QUANTA.SOCKET4677_AZIF0045P001C01CS(CHIPS)':
 'UPI0_RX_DP22': CDS_PINID='UPI0_RX_DP22';
NODE_NAME     U1 CB6
 '@S9S_MB_2U_LIB.S9S_MB_2U(SCH_1):PAGE64_I21@PURE_QUANTA.SOCKET4677_AZIF0045P001C01CS(CHIPS)':
 'UPI1_TX_DP22': CDS_PINID='UPI1_TX_DP22';
NET_NAME
'UPI_CPU1_CPU0_P1P0_DP<23>'
 '@S9S_MB_2U_LIB.S9S_MB_2U(SCH_1):UPI_CPU1_CPU0_P1P0_DP'<23>:
 C_SIGNAL='@s9s_mb_2u_lib.s9s_mb_2u(sch_1):upi_cpu1_cpu0_p1p0_dp(23)';
NODE_NAME     U2 BU5
 '@S9S_MB_2U_LIB.S9S_MB_2U(SCH_1):PAGE32_I70@PURE_QUANTA.SOCKET4677_AZIF0045P001C01CS(CHIPS)':
 'UPI0_RX_DN23': CDS_PINID='UPI0_RX_DN23';
NODE_NAME     U1 BW7
 '@S9S_MB_2U_LIB.S9S_MB_2U(SCH_1):PAGE64_I21@PURE_QUANTA.SOCKET4677_AZIF0045P001C01CS(CHIPS)':
 'UPI1_TX_DP23': CDS_PINID='UPI1_TX_DP23';
NET_NAME
'UPI_CPU1_CPU0_P1P0_DP<2>'
 '@S9S_MB_2U_LIB.S9S_MB_2U(SCH_1):UPI_CPU1_CPU0_P1P0_DP'<2>:
 C_SIGNAL='@s9s_mb_2u_lib.s9s_mb_2u(sch_1):upi_cpu1_cpu0_p1p0_dp(2)';
NODE_NAME     U2 R7
 '@S9S_MB_2U_LIB.S9S_MB_2U(SCH_1):PAGE32_I70@PURE_QUANTA.SOCKET4677_AZIF0045P001C01CS(CHIPS)':
 'UPI0_RX_DP2': CDS_PINID='UPI0_RX_DP2';
NODE_NAME     U1 EA5
 '@S9S_MB_2U_LIB.S9S_MB_2U(SCH_1):PAGE64_I21@PURE_QUANTA.SOCKET4677_AZIF0045P001C01CS(CHIPS)':
 'UPI1_TX_DP2': CDS_PINID='UPI1_TX_DP2';
NET_NAME
'UPI_CPU1_CPU0_P1P0_DP<3>'
 '@S9S_MB_2U_LIB.S9S_MB_2U(SCH_1):UPI_CPU1_CPU0_P1P0_DP'<3>:
 C_SIGNAL='@s9s_mb_2u_lib.s9s_mb_2u(sch_1):upi_cpu1_cpu0_p1p0_dp(3)';
NODE_NAME     U2 U5
 '@S9S_MB_2U_LIB.S9S_MB_2U(SCH_1):PAGE32_I70@PURE_QUANTA.SOCKET4677_AZIF0045P001C01CS(CHIPS)':
 'UPI0_RX_DN3': CDS_PINID='UPI0_RX_DN3';
NODE_NAME     U1 DW7
 '@S9S_MB_2U_LIB.S9S_MB_2U(SCH_1):PAGE64_I21@PURE_QUANTA.SOCKET4677_AZIF0045P001C01CS(CHIPS)':
 'UPI1_TX_DP3': CDS_PINID='UPI1_TX_DP3';
NET_NAME
'UPI_CPU1_CPU0_P1P0_DP<4>'
 '@S9S_MB_2U_LIB.S9S_MB_2U(SCH_1):UPI_CPU1_CPU0_P1P0_DP'<4>:
 C_SIGNAL='@s9s_mb_2u_lib.s9s_mb_2u(sch_1):upi_cpu1_cpu0_p1p0_dp(4)';
NODE_NAME     U2 W7
 '@S9S_MB_2U_LIB.S9S_MB_2U(SCH_1):PAGE32_I70@PURE_QUANTA.SOCKET4677_AZIF0045P001C01CS(CHIPS)':
 'UPI0_RX_DP4': CDS_PINID='UPI0_RX_DP4';
NODE_NAME     U1 DU5
 '@S9S_MB_2U_LIB.S9S_MB_2U(SCH_1):PAGE64_I21@PURE_QUANTA.SOCKET4677_AZIF0045P001C01CS(CHIPS)':
 'UPI1_TX_DP4': CDS_PINID='UPI1_TX_DP4';
NET_NAME
'UPI_CPU1_CPU0_P1P0_DP<5>'
 '@S9S_MB_2U_LIB.S9S_MB_2U(SCH_1):UPI_CPU1_CPU0_P1P0_DP'<5>:
 C_SIGNAL='@s9s_mb_2u_lib.s9s_mb_2u(sch_1):upi_cpu1_cpu0_p1p0_dp(5)';
NODE_NAME     U2 AA5
 '@S9S_MB_2U_LIB.S9S_MB_2U(SCH_1):PAGE32_I70@PURE_QUANTA.SOCKET4677_AZIF0045P001C01CS(CHIPS)':
 'UPI0_RX_DN5': CDS_PINID='UPI0_RX_DN5';
NODE_NAME     U1 DR7
 '@S9S_MB_2U_LIB.S9S_MB_2U(SCH_1):PAGE64_I21@PURE_QUANTA.SOCKET4677_AZIF0045P001C01CS(CHIPS)':
 'UPI1_TX_DP5': CDS_PINID='UPI1_TX_DP5';
NET_NAME
'UPI_CPU1_CPU0_P1P0_DP<6>'
 '@S9S_MB_2U_LIB.S9S_MB_2U(SCH_1):UPI_CPU1_CPU0_P1P0_DP'<6>:
 C_SIGNAL='@s9s_mb_2u_lib.s9s_mb_2u(sch_1):upi_cpu1_cpu0_p1p0_dp(6)';
NODE_NAME     U2 AC7
 '@S9S_MB_2U_LIB.S9S_MB_2U(SCH_1):PAGE32_I70@PURE_QUANTA.SOCKET4677_AZIF0045P001C01CS(CHIPS)':
 'UPI0_RX_DP6': CDS_PINID='UPI0_RX_DP6';
NODE_NAME     U1 DN5
 '@S9S_MB_2U_LIB.S9S_MB_2U(SCH_1):PAGE64_I21@PURE_QUANTA.SOCKET4677_AZIF0045P001C01CS(CHIPS)':
 'UPI1_TX_DP6': CDS_PINID='UPI1_TX_DP6';
NET_NAME
'UPI_CPU1_CPU0_P1P0_DP<7>'
 '@S9S_MB_2U_LIB.S9S_MB_2U(SCH_1):UPI_CPU1_CPU0_P1P0_DP'<7>:
 C_SIGNAL='@s9s_mb_2u_lib.s9s_mb_2u(sch_1):upi_cpu1_cpu0_p1p0_dp(7)';
NODE_NAME     U2 AD6
 '@S9S_MB_2U_LIB.S9S_MB_2U(SCH_1):PAGE32_I70@PURE_QUANTA.SOCKET4677_AZIF0045P001C01CS(CHIPS)':
 'UPI0_RX_DP7': CDS_PINID='UPI0_RX_DP7';
NODE_NAME     U1 DM6
 '@S9S_MB_2U_LIB.S9S_MB_2U(SCH_1):PAGE64_I21@PURE_QUANTA.SOCKET4677_AZIF0045P001C01CS(CHIPS)':
 'UPI1_TX_DP7': CDS_PINID='UPI1_TX_DP7';
NET_NAME
'UPI_CPU1_CPU0_P1P0_DP<8>'
 '@S9S_MB_2U_LIB.S9S_MB_2U(SCH_1):UPI_CPU1_CPU0_P1P0_DP'<8>:
 C_SIGNAL='@s9s_mb_2u_lib.s9s_mb_2u(sch_1):upi_cpu1_cpu0_p1p0_dp(8)';
NODE_NAME     U2 AG7
 '@S9S_MB_2U_LIB.S9S_MB_2U(SCH_1):PAGE32_I70@PURE_QUANTA.SOCKET4677_AZIF0045P001C01CS(CHIPS)':
 'UPI0_RX_DP8': CDS_PINID='UPI0_RX_DP8';
NODE_NAME     U1 DJ5
 '@S9S_MB_2U_LIB.S9S_MB_2U(SCH_1):PAGE64_I21@PURE_QUANTA.SOCKET4677_AZIF0045P001C01CS(CHIPS)':
 'UPI1_TX_DP8': CDS_PINID='UPI1_TX_DP8';
NET_NAME
'UPI_CPU1_CPU0_P1P0_DP<9>'
 '@S9S_MB_2U_LIB.S9S_MB_2U(SCH_1):UPI_CPU1_CPU0_P1P0_DP'<9>:
 C_SIGNAL='@s9s_mb_2u_lib.s9s_mb_2u(sch_1):upi_cpu1_cpu0_p1p0_dp(9)';
NODE_NAME     U2 AJ5
 '@S9S_MB_2U_LIB.S9S_MB_2U(SCH_1):PAGE32_I70@PURE_QUANTA.SOCKET4677_AZIF0045P001C01CS(CHIPS)':
 'UPI0_RX_DP9': CDS_PINID='UPI0_RX_DP9';
NODE_NAME     U1 DG7
 '@S9S_MB_2U_LIB.S9S_MB_2U(SCH_1):PAGE64_I21@PURE_QUANTA.SOCKET4677_AZIF0045P001C01CS(CHIPS)':
 'UPI1_TX_DP9': CDS_PINID='UPI1_TX_DP9';
NET_NAME
'UPI_CPU1_CPU0_P2P2_DN<0>'
 '@S9S_MB_2U_LIB.S9S_MB_2U(SCH_1):UPI_CPU1_CPU0_P2P2_DN'<0>:
 C_SIGNAL='@s9s_mb_2u_lib.s9s_mb_2u(sch_1):upi_cpu1_cpu0_p2p2_dn(0)';
NODE_NAME     U2 BC74
 '@S9S_MB_2U_LIB.S9S_MB_2U(SCH_1):PAGE34_I102@PURE_QUANTA.SOCKET4677_AZIF0045P001C01CS(CHIPS)':
 'UPI2_RX_DP23': CDS_PINID='UPI2_RX_DP23';
NODE_NAME     U1 B85
 '@S9S_MB_2U_LIB.S9S_MB_2U(SCH_1):PAGE65_I16@PURE_QUANTA.SOCKET4677_AZIF0045P001C01CS(CHIPS)':
 'UPI2_TX_DN0': CDS_PINID='UPI2_TX_DN0';
NET_NAME
'UPI_CPU1_CPU0_P2P2_DN<10>'
 '@S9S_MB_2U_LIB.S9S_MB_2U(SCH_1):UPI_CPU1_CPU0_P2P2_DN'<10>:
 C_SIGNAL='@s9s_mb_2u_lib.s9s_mb_2u(sch_1):upi_cpu1_cpu0_p2p2_dn(10)';
NODE_NAME     U2 AV73
 '@S9S_MB_2U_LIB.S9S_MB_2U(SCH_1):PAGE34_I102@PURE_QUANTA.SOCKET4677_AZIF0045P001C01CS(CHIPS)':
 'UPI2_RX_DN13': CDS_PINID='UPI2_RX_DN13';
NODE_NAME     U1 AW78
 '@S9S_MB_2U_LIB.S9S_MB_2U(SCH_1):PAGE65_I16@PURE_QUANTA.SOCKET4677_AZIF0045P001C01CS(CHIPS)':
 'UPI2_TX_DN10': CDS_PINID='UPI2_TX_DN10';
NET_NAME
'UPI_CPU1_CPU0_P2P2_DN<11>'
 '@S9S_MB_2U_LIB.S9S_MB_2U(SCH_1):UPI_CPU1_CPU0_P2P2_DN'<11>:
 C_SIGNAL='@s9s_mb_2u_lib.s9s_mb_2u(sch_1):upi_cpu1_cpu0_p2p2_dn(11)';
NODE_NAME     U2 BB73
 '@S9S_MB_2U_LIB.S9S_MB_2U(SCH_1):PAGE34_I102@PURE_QUANTA.SOCKET4677_AZIF0045P001C01CS(CHIPS)':
 'UPI2_RX_DP12': CDS_PINID='UPI2_RX_DP12';
NODE_NAME     U1 AU78
 '@S9S_MB_2U_LIB.S9S_MB_2U(SCH_1):PAGE65_I16@PURE_QUANTA.SOCKET4677_AZIF0045P001C01CS(CHIPS)':
 'UPI2_TX_DN11': CDS_PINID='UPI2_TX_DN11';
NET_NAME
'UPI_CPU1_CPU0_P2P2_DN<12>'
 '@S9S_MB_2U_LIB.S9S_MB_2U(SCH_1):UPI_CPU1_CPU0_P2P2_DN'<12>:
 C_SIGNAL='@s9s_mb_2u_lib.s9s_mb_2u(sch_1):upi_cpu1_cpu0_p2p2_dn(12)';
NODE_NAME     U2 AJ82
 '@S9S_MB_2U_LIB.S9S_MB_2U(SCH_1):PAGE34_I102@PURE_QUANTA.SOCKET4677_AZIF0045P001C01CS(CHIPS)':
 'UPI2_RX_DP11': CDS_PINID='UPI2_RX_DP11';
NODE_NAME     U1 AM81
 '@S9S_MB_2U_LIB.S9S_MB_2U(SCH_1):PAGE65_I16@PURE_QUANTA.SOCKET4677_AZIF0045P001C01CS(CHIPS)':
 'UPI2_TX_DN12': CDS_PINID='UPI2_TX_DN12';
NET_NAME
'UPI_CPU1_CPU0_P2P2_DN<13>'
 '@S9S_MB_2U_LIB.S9S_MB_2U(SCH_1):UPI_CPU1_CPU0_P2P2_DN'<13>:
 C_SIGNAL='@s9s_mb_2u_lib.s9s_mb_2u(sch_1):upi_cpu1_cpu0_p2p2_dn(13)';
NODE_NAME     U2 AJ80
 '@S9S_MB_2U_LIB.S9S_MB_2U(SCH_1):PAGE34_I102@PURE_QUANTA.SOCKET4677_AZIF0045P001C01CS(CHIPS)':
 'UPI2_RX_DN10': CDS_PINID='UPI2_RX_DN10';
NODE_NAME     U1 AN82
 '@S9S_MB_2U_LIB.S9S_MB_2U(SCH_1):PAGE65_I16@PURE_QUANTA.SOCKET4677_AZIF0045P001C01CS(CHIPS)':
 'UPI2_TX_DN13': CDS_PINID='UPI2_TX_DN13';
NET_NAME
'UPI_CPU1_CPU0_P2P2_DN<14>'
 '@S9S_MB_2U_LIB.S9S_MB_2U(SCH_1):UPI_CPU1_CPU0_P2P2_DN'<14>:
 C_SIGNAL='@s9s_mb_2u_lib.s9s_mb_2u(sch_1):upi_cpu1_cpu0_p2p2_dn(14)';
NODE_NAME     U2 AF83
 '@S9S_MB_2U_LIB.S9S_MB_2U(SCH_1):PAGE34_I102@PURE_QUANTA.SOCKET4677_AZIF0045P001C01CS(CHIPS)':
 'UPI2_RX_DP9': CDS_PINID='UPI2_RX_DP9';
NODE_NAME     U1 AR80
 '@S9S_MB_2U_LIB.S9S_MB_2U(SCH_1):PAGE65_I16@PURE_QUANTA.SOCKET4677_AZIF0045P001C01CS(CHIPS)':
 'UPI2_TX_DN14': CDS_PINID='UPI2_TX_DN14';
NET_NAME
'UPI_CPU1_CPU0_P2P2_DN<15>'
 '@S9S_MB_2U_LIB.S9S_MB_2U(SCH_1):UPI_CPU1_CPU0_P2P2_DN'<15>:
 C_SIGNAL='@s9s_mb_2u_lib.s9s_mb_2u(sch_1):upi_cpu1_cpu0_p2p2_dn(15)';
NODE_NAME     U2 AG80
 '@S9S_MB_2U_LIB.S9S_MB_2U(SCH_1):PAGE34_I102@PURE_QUANTA.SOCKET4677_AZIF0045P001C01CS(CHIPS)':
 'UPI2_RX_DP8': CDS_PINID='UPI2_RX_DP8';
NODE_NAME     U1 AT83
 '@S9S_MB_2U_LIB.S9S_MB_2U(SCH_1):PAGE65_I16@PURE_QUANTA.SOCKET4677_AZIF0045P001C01CS(CHIPS)':
 'UPI2_TX_DN15': CDS_PINID='UPI2_TX_DN15';
NET_NAME
'UPI_CPU1_CPU0_P2P2_DN<16>'
 '@S9S_MB_2U_LIB.S9S_MB_2U(SCH_1):UPI_CPU1_CPU0_P2P2_DN'<16>:
 C_SIGNAL='@s9s_mb_2u_lib.s9s_mb_2u(sch_1):upi_cpu1_cpu0_p2p2_dn(16)';
NODE_NAME     U2 AC82
 '@S9S_MB_2U_LIB.S9S_MB_2U(SCH_1):PAGE34_I102@PURE_QUANTA.SOCKET4677_AZIF0045P001C01CS(CHIPS)':
 'UPI2_RX_DP7': CDS_PINID='UPI2_RX_DP7';
NODE_NAME     U1 AV81
 '@S9S_MB_2U_LIB.S9S_MB_2U(SCH_1):PAGE65_I16@PURE_QUANTA.SOCKET4677_AZIF0045P001C01CS(CHIPS)':
 'UPI2_TX_DN16': CDS_PINID='UPI2_TX_DN16';
NET_NAME
'UPI_CPU1_CPU0_P2P2_DN<17>'
 '@S9S_MB_2U_LIB.S9S_MB_2U(SCH_1):UPI_CPU1_CPU0_P2P2_DN'<17>:
 C_SIGNAL='@s9s_mb_2u_lib.s9s_mb_2u(sch_1):upi_cpu1_cpu0_p2p2_dn(17)';
NODE_NAME     U2 AC80
 '@S9S_MB_2U_LIB.S9S_MB_2U(SCH_1):PAGE34_I102@PURE_QUANTA.SOCKET4677_AZIF0045P001C01CS(CHIPS)':
 'UPI2_RX_DN6': CDS_PINID='UPI2_RX_DN6';
NODE_NAME     U1 BA80
 '@S9S_MB_2U_LIB.S9S_MB_2U(SCH_1):PAGE65_I16@PURE_QUANTA.SOCKET4677_AZIF0045P001C01CS(CHIPS)':
 'UPI2_TX_DN17': CDS_PINID='UPI2_TX_DN17';
NET_NAME
'UPI_CPU1_CPU0_P2P2_DN<18>'
 '@S9S_MB_2U_LIB.S9S_MB_2U(SCH_1):UPI_CPU1_CPU0_P2P2_DN'<18>:
 C_SIGNAL='@s9s_mb_2u_lib.s9s_mb_2u(sch_1):upi_cpu1_cpu0_p2p2_dn(18)';
NODE_NAME     U2 L80
 '@S9S_MB_2U_LIB.S9S_MB_2U(SCH_1):PAGE34_I102@PURE_QUANTA.SOCKET4677_AZIF0045P001C01CS(CHIPS)':
 'UPI2_RX_DN5': CDS_PINID='UPI2_RX_DN5';
NODE_NAME     U1 BC82
 '@S9S_MB_2U_LIB.S9S_MB_2U(SCH_1):PAGE65_I16@PURE_QUANTA.SOCKET4677_AZIF0045P001C01CS(CHIPS)':
 'UPI2_TX_DN18': CDS_PINID='UPI2_TX_DN18';
NET_NAME
'UPI_CPU1_CPU0_P2P2_DN<19>'
 '@S9S_MB_2U_LIB.S9S_MB_2U(SCH_1):UPI_CPU1_CPU0_P2P2_DN'<19>:
 C_SIGNAL='@s9s_mb_2u_lib.s9s_mb_2u(sch_1):upi_cpu1_cpu0_p2p2_dn(19)';
NODE_NAME     U2 J82
 '@S9S_MB_2U_LIB.S9S_MB_2U(SCH_1):PAGE34_I102@PURE_QUANTA.SOCKET4677_AZIF0045P001C01CS(CHIPS)':
 'UPI2_RX_DN4': CDS_PINID='UPI2_RX_DN4';
NODE_NAME     U1 BE82
 '@S9S_MB_2U_LIB.S9S_MB_2U(SCH_1):PAGE65_I16@PURE_QUANTA.SOCKET4677_AZIF0045P001C01CS(CHIPS)':
 'UPI2_TX_DN19': CDS_PINID='UPI2_TX_DN19';
NET_NAME
'UPI_CPU1_CPU0_P2P2_DN<1>'
 '@S9S_MB_2U_LIB.S9S_MB_2U(SCH_1):UPI_CPU1_CPU0_P2P2_DN'<1>:
 C_SIGNAL='@s9s_mb_2u_lib.s9s_mb_2u(sch_1):upi_cpu1_cpu0_p2p2_dn(1)';
NODE_NAME     U2 BK73
 '@S9S_MB_2U_LIB.S9S_MB_2U(SCH_1):PAGE34_I102@PURE_QUANTA.SOCKET4677_AZIF0045P001C01CS(CHIPS)':
 'UPI2_RX_DN22': CDS_PINID='UPI2_RX_DN22';
NODE_NAME     U1 E84
 '@S9S_MB_2U_LIB.S9S_MB_2U(SCH_1):PAGE65_I16@PURE_QUANTA.SOCKET4677_AZIF0045P001C01CS(CHIPS)':
 'UPI2_TX_DN1': CDS_PINID='UPI2_TX_DN1';
NET_NAME
'UPI_CPU1_CPU0_P2P2_DN<20>'
 '@S9S_MB_2U_LIB.S9S_MB_2U(SCH_1):UPI_CPU1_CPU0_P2P2_DN'<20>:
 C_SIGNAL='@s9s_mb_2u_lib.s9s_mb_2u(sch_1):upi_cpu1_cpu0_p2p2_dn(20)';
NODE_NAME     U2 K79
 '@S9S_MB_2U_LIB.S9S_MB_2U(SCH_1):PAGE34_I102@PURE_QUANTA.SOCKET4677_AZIF0045P001C01CS(CHIPS)':
 'UPI2_RX_DN3': CDS_PINID='UPI2_RX_DN3';
NODE_NAME     U1 BD79
 '@S9S_MB_2U_LIB.S9S_MB_2U(SCH_1):PAGE65_I16@PURE_QUANTA.SOCKET4677_AZIF0045P001C01CS(CHIPS)':
 'UPI2_TX_DN20': CDS_PINID='UPI2_TX_DN20';
NET_NAME
'UPI_CPU1_CPU0_P2P2_DN<21>'
 '@S9S_MB_2U_LIB.S9S_MB_2U(SCH_1):UPI_CPU1_CPU0_P2P2_DN'<21>:
 C_SIGNAL='@s9s_mb_2u_lib.s9s_mb_2u(sch_1):upi_cpu1_cpu0_p2p2_dn(21)';
NODE_NAME     U2 G82
 '@S9S_MB_2U_LIB.S9S_MB_2U(SCH_1):PAGE34_I102@PURE_QUANTA.SOCKET4677_AZIF0045P001C01CS(CHIPS)':
 'UPI2_RX_DN2': CDS_PINID='UPI2_RX_DN2';
NODE_NAME     U1 BF81
 '@S9S_MB_2U_LIB.S9S_MB_2U(SCH_1):PAGE65_I16@PURE_QUANTA.SOCKET4677_AZIF0045P001C01CS(CHIPS)':
 'UPI2_TX_DN21': CDS_PINID='UPI2_TX_DN21';
NET_NAME
'UPI_CPU1_CPU0_P2P2_DN<22>'
 '@S9S_MB_2U_LIB.S9S_MB_2U(SCH_1):UPI_CPU1_CPU0_P2P2_DN'<22>:
 C_SIGNAL='@s9s_mb_2u_lib.s9s_mb_2u(sch_1):upi_cpu1_cpu0_p2p2_dn(22)';
NODE_NAME     U2 E82
 '@S9S_MB_2U_LIB.S9S_MB_2U(SCH_1):PAGE34_I102@PURE_QUANTA.SOCKET4677_AZIF0045P001C01CS(CHIPS)':
 'UPI2_RX_DP1': CDS_PINID='UPI2_RX_DP1';
NODE_NAME     U1 BG80
 '@S9S_MB_2U_LIB.S9S_MB_2U(SCH_1):PAGE65_I16@PURE_QUANTA.SOCKET4677_AZIF0045P001C01CS(CHIPS)':
 'UPI2_TX_DN22': CDS_PINID='UPI2_TX_DN22';
NET_NAME
'UPI_CPU1_CPU0_P2P2_DN<23>'
 '@S9S_MB_2U_LIB.S9S_MB_2U(SCH_1):UPI_CPU1_CPU0_P2P2_DN'<23>:
 C_SIGNAL='@s9s_mb_2u_lib.s9s_mb_2u(sch_1):upi_cpu1_cpu0_p2p2_dn(23)';
NODE_NAME     U2 E80
 '@S9S_MB_2U_LIB.S9S_MB_2U(SCH_1):PAGE34_I102@PURE_QUANTA.SOCKET4677_AZIF0045P001C01CS(CHIPS)':
 'UPI2_RX_DN0': CDS_PINID='UPI2_RX_DN0';
NODE_NAME     U1 BM71
 '@S9S_MB_2U_LIB.S9S_MB_2U(SCH_1):PAGE65_I16@PURE_QUANTA.SOCKET4677_AZIF0045P001C01CS(CHIPS)':
 'UPI2_TX_DN23': CDS_PINID='UPI2_TX_DN23';
NET_NAME
'UPI_CPU1_CPU0_P2P2_DN<2>'
 '@S9S_MB_2U_LIB.S9S_MB_2U(SCH_1):UPI_CPU1_CPU0_P2P2_DN'<2>:
 C_SIGNAL='@s9s_mb_2u_lib.s9s_mb_2u(sch_1):upi_cpu1_cpu0_p2p2_dn(2)';
NODE_NAME     U2 BM75
 '@S9S_MB_2U_LIB.S9S_MB_2U(SCH_1):PAGE34_I102@PURE_QUANTA.SOCKET4677_AZIF0045P001C01CS(CHIPS)':
 'UPI2_RX_DP21': CDS_PINID='UPI2_RX_DP21';
NODE_NAME     U1 D87
 '@S9S_MB_2U_LIB.S9S_MB_2U(SCH_1):PAGE65_I16@PURE_QUANTA.SOCKET4677_AZIF0045P001C01CS(CHIPS)':
 'UPI2_TX_DN2': CDS_PINID='UPI2_TX_DN2';
NET_NAME
'UPI_CPU1_CPU0_P2P2_DN<3>'
 '@S9S_MB_2U_LIB.S9S_MB_2U(SCH_1):UPI_CPU1_CPU0_P2P2_DN'<3>:
 C_SIGNAL='@s9s_mb_2u_lib.s9s_mb_2u(sch_1):upi_cpu1_cpu0_p2p2_dn(3)';
NODE_NAME     U2 BJ74
 '@S9S_MB_2U_LIB.S9S_MB_2U(SCH_1):PAGE34_I102@PURE_QUANTA.SOCKET4677_AZIF0045P001C01CS(CHIPS)':
 'UPI2_RX_DP20': CDS_PINID='UPI2_RX_DP20';
NODE_NAME     U1 F87
 '@S9S_MB_2U_LIB.S9S_MB_2U(SCH_1):PAGE65_I16@PURE_QUANTA.SOCKET4677_AZIF0045P001C01CS(CHIPS)':
 'UPI2_TX_DN3': CDS_PINID='UPI2_TX_DN3';
NET_NAME
'UPI_CPU1_CPU0_P2P2_DN<4>'
 '@S9S_MB_2U_LIB.S9S_MB_2U(SCH_1):UPI_CPU1_CPU0_P2P2_DN'<4>:
 C_SIGNAL='@s9s_mb_2u_lib.s9s_mb_2u(sch_1):upi_cpu1_cpu0_p2p2_dn(4)';
NODE_NAME     U2 BN76
 '@S9S_MB_2U_LIB.S9S_MB_2U(SCH_1):PAGE34_I102@PURE_QUANTA.SOCKET4677_AZIF0045P001C01CS(CHIPS)':
 'UPI2_RX_DP19': CDS_PINID='UPI2_RX_DP19';
NODE_NAME     U1 H85
 '@S9S_MB_2U_LIB.S9S_MB_2U(SCH_1):PAGE65_I16@PURE_QUANTA.SOCKET4677_AZIF0045P001C01CS(CHIPS)':
 'UPI2_TX_DN4': CDS_PINID='UPI2_TX_DN4';
NET_NAME
'UPI_CPU1_CPU0_P2P2_DN<5>'
 '@S9S_MB_2U_LIB.S9S_MB_2U(SCH_1):UPI_CPU1_CPU0_P2P2_DN'<5>:
 C_SIGNAL='@s9s_mb_2u_lib.s9s_mb_2u(sch_1):upi_cpu1_cpu0_p2p2_dn(5)';
NODE_NAME     U2 BJ76
 '@S9S_MB_2U_LIB.S9S_MB_2U(SCH_1):PAGE34_I102@PURE_QUANTA.SOCKET4677_AZIF0045P001C01CS(CHIPS)':
 'UPI2_RX_DN18': CDS_PINID='UPI2_RX_DN18';
NODE_NAME     U1 P81
 '@S9S_MB_2U_LIB.S9S_MB_2U(SCH_1):PAGE65_I16@PURE_QUANTA.SOCKET4677_AZIF0045P001C01CS(CHIPS)':
 'UPI2_TX_DN5': CDS_PINID='UPI2_TX_DN5';
NET_NAME
'UPI_CPU1_CPU0_P2P2_DN<6>'
 '@S9S_MB_2U_LIB.S9S_MB_2U(SCH_1):UPI_CPU1_CPU0_P2P2_DN'<6>:
 C_SIGNAL='@s9s_mb_2u_lib.s9s_mb_2u(sch_1):upi_cpu1_cpu0_p2p2_dn(6)';
NODE_NAME     U2 BH75
 '@S9S_MB_2U_LIB.S9S_MB_2U(SCH_1):PAGE34_I102@PURE_QUANTA.SOCKET4677_AZIF0045P001C01CS(CHIPS)':
 'UPI2_RX_DN17': CDS_PINID='UPI2_RX_DN17';
NODE_NAME     U1 R82
 '@S9S_MB_2U_LIB.S9S_MB_2U(SCH_1):PAGE65_I16@PURE_QUANTA.SOCKET4677_AZIF0045P001C01CS(CHIPS)':
 'UPI2_TX_DN6': CDS_PINID='UPI2_TX_DN6';
NET_NAME
'UPI_CPU1_CPU0_P2P2_DN<7>'
 '@S9S_MB_2U_LIB.S9S_MB_2U(SCH_1):UPI_CPU1_CPU0_P2P2_DN'<7>:
 C_SIGNAL='@s9s_mb_2u_lib.s9s_mb_2u(sch_1):upi_cpu1_cpu0_p2p2_dn(7)';
NODE_NAME     U2 AV75
 '@S9S_MB_2U_LIB.S9S_MB_2U(SCH_1):PAGE34_I102@PURE_QUANTA.SOCKET4677_AZIF0045P001C01CS(CHIPS)':
 'UPI2_RX_DP16': CDS_PINID='UPI2_RX_DP16';
NODE_NAME     U1 U80
 '@S9S_MB_2U_LIB.S9S_MB_2U(SCH_1):PAGE65_I16@PURE_QUANTA.SOCKET4677_AZIF0045P001C01CS(CHIPS)':
 'UPI2_TX_DN7': CDS_PINID='UPI2_TX_DN7';
NET_NAME
'UPI_CPU1_CPU0_P2P2_DN<8>'
 '@S9S_MB_2U_LIB.S9S_MB_2U(SCH_1):UPI_CPU1_CPU0_P2P2_DN'<8>:
 C_SIGNAL='@s9s_mb_2u_lib.s9s_mb_2u(sch_1):upi_cpu1_cpu0_p2p2_dn(8)';
NODE_NAME     U2 BD75
 '@S9S_MB_2U_LIB.S9S_MB_2U(SCH_1):PAGE34_I102@PURE_QUANTA.SOCKET4677_AZIF0045P001C01CS(CHIPS)':
 'UPI2_RX_DP15': CDS_PINID='UPI2_RX_DP15';
NODE_NAME     U1 V83
 '@S9S_MB_2U_LIB.S9S_MB_2U(SCH_1):PAGE65_I16@PURE_QUANTA.SOCKET4677_AZIF0045P001C01CS(CHIPS)':
 'UPI2_TX_DN8': CDS_PINID='UPI2_TX_DN8';
NET_NAME
'UPI_CPU1_CPU0_P2P2_DN<9>'
 '@S9S_MB_2U_LIB.S9S_MB_2U(SCH_1):UPI_CPU1_CPU0_P2P2_DN'<9>:
 C_SIGNAL='@s9s_mb_2u_lib.s9s_mb_2u(sch_1):upi_cpu1_cpu0_p2p2_dn(9)';
NODE_NAME     U2 AY75
 '@S9S_MB_2U_LIB.S9S_MB_2U(SCH_1):PAGE34_I102@PURE_QUANTA.SOCKET4677_AZIF0045P001C01CS(CHIPS)':
 'UPI2_RX_DN14': CDS_PINID='UPI2_RX_DN14';
NODE_NAME     U1 Y81
 '@S9S_MB_2U_LIB.S9S_MB_2U(SCH_1):PAGE65_I16@PURE_QUANTA.SOCKET4677_AZIF0045P001C01CS(CHIPS)':
 'UPI2_TX_DN9': CDS_PINID='UPI2_TX_DN9';
NET_NAME
'UPI_CPU1_CPU0_P2P2_DP<0>'
 '@S9S_MB_2U_LIB.S9S_MB_2U(SCH_1):UPI_CPU1_CPU0_P2P2_DP'<0>:
 C_SIGNAL='@s9s_mb_2u_lib.s9s_mb_2u(sch_1):upi_cpu1_cpu0_p2p2_dp(0)';
NODE_NAME     U2 BD73
 '@S9S_MB_2U_LIB.S9S_MB_2U(SCH_1):PAGE34_I102@PURE_QUANTA.SOCKET4677_AZIF0045P001C01CS(CHIPS)':
 'UPI2_RX_DN23': CDS_PINID='UPI2_RX_DN23';
NODE_NAME     U1 D85
 '@S9S_MB_2U_LIB.S9S_MB_2U(SCH_1):PAGE65_I16@PURE_QUANTA.SOCKET4677_AZIF0045P001C01CS(CHIPS)':
 'UPI2_TX_DP0': CDS_PINID='UPI2_TX_DP0';
NET_NAME
'UPI_CPU1_CPU0_P2P2_DP<10>'
 '@S9S_MB_2U_LIB.S9S_MB_2U(SCH_1):UPI_CPU1_CPU0_P2P2_DP'<10>:
 C_SIGNAL='@s9s_mb_2u_lib.s9s_mb_2u(sch_1):upi_cpu1_cpu0_p2p2_dp(10)';
NODE_NAME     U2 AY73
 '@S9S_MB_2U_LIB.S9S_MB_2U(SCH_1):PAGE34_I102@PURE_QUANTA.SOCKET4677_AZIF0045P001C01CS(CHIPS)':
 'UPI2_RX_DP13': CDS_PINID='UPI2_RX_DP13';
NODE_NAME     U1 BA78
 '@S9S_MB_2U_LIB.S9S_MB_2U(SCH_1):PAGE65_I16@PURE_QUANTA.SOCKET4677_AZIF0045P001C01CS(CHIPS)':
 'UPI2_TX_DP10': CDS_PINID='UPI2_TX_DP10';
NET_NAME
'UPI_CPU1_CPU0_P2P2_DP<11>'
 '@S9S_MB_2U_LIB.S9S_MB_2U(SCH_1):UPI_CPU1_CPU0_P2P2_DP'<11>:
 C_SIGNAL='@s9s_mb_2u_lib.s9s_mb_2u(sch_1):upi_cpu1_cpu0_p2p2_dp(11)';
NODE_NAME     U2 BA72
 '@S9S_MB_2U_LIB.S9S_MB_2U(SCH_1):PAGE34_I102@PURE_QUANTA.SOCKET4677_AZIF0045P001C01CS(CHIPS)':
 'UPI2_RX_DN12': CDS_PINID='UPI2_RX_DN12';
NODE_NAME     U1 AV79
 '@S9S_MB_2U_LIB.S9S_MB_2U(SCH_1):PAGE65_I16@PURE_QUANTA.SOCKET4677_AZIF0045P001C01CS(CHIPS)':
 'UPI2_TX_DP11': CDS_PINID='UPI2_TX_DP11';
NET_NAME
'UPI_CPU1_CPU0_P2P2_DP<12>'
 '@S9S_MB_2U_LIB.S9S_MB_2U(SCH_1):UPI_CPU1_CPU0_P2P2_DP'<12>:
 C_SIGNAL='@s9s_mb_2u_lib.s9s_mb_2u(sch_1):upi_cpu1_cpu0_p2p2_dp(12)';
NODE_NAME     U2 AG82
 '@S9S_MB_2U_LIB.S9S_MB_2U(SCH_1):PAGE34_I102@PURE_QUANTA.SOCKET4677_AZIF0045P001C01CS(CHIPS)':
 'UPI2_RX_DN11': CDS_PINID='UPI2_RX_DN11';
NODE_NAME     U1 AP81
 '@S9S_MB_2U_LIB.S9S_MB_2U(SCH_1):PAGE65_I16@PURE_QUANTA.SOCKET4677_AZIF0045P001C01CS(CHIPS)':
 'UPI2_TX_DP12': CDS_PINID='UPI2_TX_DP12';
NET_NAME
'UPI_CPU1_CPU0_P2P2_DP<13>'
 '@S9S_MB_2U_LIB.S9S_MB_2U(SCH_1):UPI_CPU1_CPU0_P2P2_DP'<13>:
 C_SIGNAL='@s9s_mb_2u_lib.s9s_mb_2u(sch_1):upi_cpu1_cpu0_p2p2_dp(13)';
NODE_NAME     U2 AH81
 '@S9S_MB_2U_LIB.S9S_MB_2U(SCH_1):PAGE34_I102@PURE_QUANTA.SOCKET4677_AZIF0045P001C01CS(CHIPS)':
 'UPI2_RX_DP10': CDS_PINID='UPI2_RX_DP10';
NODE_NAME     U1 AM83
 '@S9S_MB_2U_LIB.S9S_MB_2U(SCH_1):PAGE65_I16@PURE_QUANTA.SOCKET4677_AZIF0045P001C01CS(CHIPS)':
 'UPI2_TX_DP13': CDS_PINID='UPI2_TX_DP13';
NET_NAME
'UPI_CPU1_CPU0_P2P2_DP<14>'
 '@S9S_MB_2U_LIB.S9S_MB_2U(SCH_1):UPI_CPU1_CPU0_P2P2_DP'<14>:
 C_SIGNAL='@s9s_mb_2u_lib.s9s_mb_2u(sch_1):upi_cpu1_cpu0_p2p2_dp(14)';
NODE_NAME     U2 AE82
 '@S9S_MB_2U_LIB.S9S_MB_2U(SCH_1):PAGE34_I102@PURE_QUANTA.SOCKET4677_AZIF0045P001C01CS(CHIPS)':
 'UPI2_RX_DN9': CDS_PINID='UPI2_RX_DN9';
NODE_NAME     U1 AT81
 '@S9S_MB_2U_LIB.S9S_MB_2U(SCH_1):PAGE65_I16@PURE_QUANTA.SOCKET4677_AZIF0045P001C01CS(CHIPS)':
 'UPI2_TX_DP14': CDS_PINID='UPI2_TX_DP14';
NET_NAME
'UPI_CPU1_CPU0_P2P2_DP<15>'
 '@S9S_MB_2U_LIB.S9S_MB_2U(SCH_1):UPI_CPU1_CPU0_P2P2_DP'<15>:
 C_SIGNAL='@s9s_mb_2u_lib.s9s_mb_2u(sch_1):upi_cpu1_cpu0_p2p2_dp(15)';
NODE_NAME     U2 AF79
 '@S9S_MB_2U_LIB.S9S_MB_2U(SCH_1):PAGE34_I102@PURE_QUANTA.SOCKET4677_AZIF0045P001C01CS(CHIPS)':
 'UPI2_RX_DN8': CDS_PINID='UPI2_RX_DN8';
NODE_NAME     U1 AV83
 '@S9S_MB_2U_LIB.S9S_MB_2U(SCH_1):PAGE65_I16@PURE_QUANTA.SOCKET4677_AZIF0045P001C01CS(CHIPS)':
 'UPI2_TX_DP15': CDS_PINID='UPI2_TX_DP15';
NET_NAME
'UPI_CPU1_CPU0_P2P2_DP<16>'
 '@S9S_MB_2U_LIB.S9S_MB_2U(SCH_1):UPI_CPU1_CPU0_P2P2_DP'<16>:
 C_SIGNAL='@s9s_mb_2u_lib.s9s_mb_2u(sch_1):upi_cpu1_cpu0_p2p2_dp(16)';
NODE_NAME     U2 AD81
 '@S9S_MB_2U_LIB.S9S_MB_2U(SCH_1):PAGE34_I102@PURE_QUANTA.SOCKET4677_AZIF0045P001C01CS(CHIPS)':
 'UPI2_RX_DN7': CDS_PINID='UPI2_RX_DN7';
NODE_NAME     U1 AU82
 '@S9S_MB_2U_LIB.S9S_MB_2U(SCH_1):PAGE65_I16@PURE_QUANTA.SOCKET4677_AZIF0045P001C01CS(CHIPS)':
 'UPI2_TX_DP16': CDS_PINID='UPI2_TX_DP16';
NET_NAME
'UPI_CPU1_CPU0_P2P2_DP<17>'
 '@S9S_MB_2U_LIB.S9S_MB_2U(SCH_1):UPI_CPU1_CPU0_P2P2_DP'<17>:
 C_SIGNAL='@s9s_mb_2u_lib.s9s_mb_2u(sch_1):upi_cpu1_cpu0_p2p2_dp(17)';
NODE_NAME     U2 AE80
 '@S9S_MB_2U_LIB.S9S_MB_2U(SCH_1):PAGE34_I102@PURE_QUANTA.SOCKET4677_AZIF0045P001C01CS(CHIPS)':
 'UPI2_RX_DP6': CDS_PINID='UPI2_RX_DP6';
NODE_NAME     U1 BB81
 '@S9S_MB_2U_LIB.S9S_MB_2U(SCH_1):PAGE65_I16@PURE_QUANTA.SOCKET4677_AZIF0045P001C01CS(CHIPS)':
 'UPI2_TX_DP17': CDS_PINID='UPI2_TX_DP17';
NET_NAME
'UPI_CPU1_CPU0_P2P2_DP<18>'
 '@S9S_MB_2U_LIB.S9S_MB_2U(SCH_1):UPI_CPU1_CPU0_P2P2_DP'<18>:
 C_SIGNAL='@s9s_mb_2u_lib.s9s_mb_2u(sch_1):upi_cpu1_cpu0_p2p2_dp(18)';
NODE_NAME     U2 K81
 '@S9S_MB_2U_LIB.S9S_MB_2U(SCH_1):PAGE34_I102@PURE_QUANTA.SOCKET4677_AZIF0045P001C01CS(CHIPS)':
 'UPI2_RX_DP5': CDS_PINID='UPI2_RX_DP5';
NODE_NAME     U1 BA82
 '@S9S_MB_2U_LIB.S9S_MB_2U(SCH_1):PAGE65_I16@PURE_QUANTA.SOCKET4677_AZIF0045P001C01CS(CHIPS)':
 'UPI2_TX_DP18': CDS_PINID='UPI2_TX_DP18';
NET_NAME
'UPI_CPU1_CPU0_P2P2_DP<19>'
 '@S9S_MB_2U_LIB.S9S_MB_2U(SCH_1):UPI_CPU1_CPU0_P2P2_DP'<19>:
 C_SIGNAL='@s9s_mb_2u_lib.s9s_mb_2u(sch_1):upi_cpu1_cpu0_p2p2_dp(19)';
NODE_NAME     U2 L82
 '@S9S_MB_2U_LIB.S9S_MB_2U(SCH_1):PAGE34_I102@PURE_QUANTA.SOCKET4677_AZIF0045P001C01CS(CHIPS)':
 'UPI2_RX_DP4': CDS_PINID='UPI2_RX_DP4';
NODE_NAME     U1 BD83
 '@S9S_MB_2U_LIB.S9S_MB_2U(SCH_1):PAGE65_I16@PURE_QUANTA.SOCKET4677_AZIF0045P001C01CS(CHIPS)':
 'UPI2_TX_DP19': CDS_PINID='UPI2_TX_DP19';
NET_NAME
'UPI_CPU1_CPU0_P2P2_DP<1>'
 '@S9S_MB_2U_LIB.S9S_MB_2U(SCH_1):UPI_CPU1_CPU0_P2P2_DP'<1>:
 C_SIGNAL='@s9s_mb_2u_lib.s9s_mb_2u(sch_1):upi_cpu1_cpu0_p2p2_dp(1)';
NODE_NAME     U2 BL74
 '@S9S_MB_2U_LIB.S9S_MB_2U(SCH_1):PAGE34_I102@PURE_QUANTA.SOCKET4677_AZIF0045P001C01CS(CHIPS)':
 'UPI2_RX_DP22': CDS_PINID='UPI2_RX_DP22';
NODE_NAME     U1 F85
 '@S9S_MB_2U_LIB.S9S_MB_2U(SCH_1):PAGE65_I16@PURE_QUANTA.SOCKET4677_AZIF0045P001C01CS(CHIPS)':
 'UPI2_TX_DP1': CDS_PINID='UPI2_TX_DP1';
NET_NAME
'UPI_CPU1_CPU0_P2P2_DP<20>'
 '@S9S_MB_2U_LIB.S9S_MB_2U(SCH_1):UPI_CPU1_CPU0_P2P2_DP'<20>:
 C_SIGNAL='@s9s_mb_2u_lib.s9s_mb_2u(sch_1):upi_cpu1_cpu0_p2p2_dp(20)';
NODE_NAME     U2 M79
 '@S9S_MB_2U_LIB.S9S_MB_2U(SCH_1):PAGE34_I102@PURE_QUANTA.SOCKET4677_AZIF0045P001C01CS(CHIPS)':
 'UPI2_RX_DP3': CDS_PINID='UPI2_RX_DP3';
NODE_NAME     U1 BC80
 '@S9S_MB_2U_LIB.S9S_MB_2U(SCH_1):PAGE65_I16@PURE_QUANTA.SOCKET4677_AZIF0045P001C01CS(CHIPS)':
 'UPI2_TX_DP20': CDS_PINID='UPI2_TX_DP20';
NET_NAME
'UPI_CPU1_CPU0_P2P2_DP<21>'
 '@S9S_MB_2U_LIB.S9S_MB_2U(SCH_1):UPI_CPU1_CPU0_P2P2_DP'<21>:
 C_SIGNAL='@s9s_mb_2u_lib.s9s_mb_2u(sch_1):upi_cpu1_cpu0_p2p2_dp(21)';
NODE_NAME     U2 H83
 '@S9S_MB_2U_LIB.S9S_MB_2U(SCH_1):PAGE34_I102@PURE_QUANTA.SOCKET4677_AZIF0045P001C01CS(CHIPS)':
 'UPI2_RX_DP2': CDS_PINID='UPI2_RX_DP2';
NODE_NAME     U1 BG82
 '@S9S_MB_2U_LIB.S9S_MB_2U(SCH_1):PAGE65_I16@PURE_QUANTA.SOCKET4677_AZIF0045P001C01CS(CHIPS)':
 'UPI2_TX_DP21': CDS_PINID='UPI2_TX_DP21';
NET_NAME
'UPI_CPU1_CPU0_P2P2_DP<22>'
 '@S9S_MB_2U_LIB.S9S_MB_2U(SCH_1):UPI_CPU1_CPU0_P2P2_DP'<22>:
 C_SIGNAL='@s9s_mb_2u_lib.s9s_mb_2u(sch_1):upi_cpu1_cpu0_p2p2_dp(22)';
NODE_NAME     U2 F81
 '@S9S_MB_2U_LIB.S9S_MB_2U(SCH_1):PAGE34_I102@PURE_QUANTA.SOCKET4677_AZIF0045P001C01CS(CHIPS)':
 'UPI2_RX_DN1': CDS_PINID='UPI2_RX_DN1';
NODE_NAME     U1 BE80
 '@S9S_MB_2U_LIB.S9S_MB_2U(SCH_1):PAGE65_I16@PURE_QUANTA.SOCKET4677_AZIF0045P001C01CS(CHIPS)':
 'UPI2_TX_DP22': CDS_PINID='UPI2_TX_DP22';
NET_NAME
'UPI_CPU1_CPU0_P2P2_DP<23>'
 '@S9S_MB_2U_LIB.S9S_MB_2U(SCH_1):UPI_CPU1_CPU0_P2P2_DP'<23>:
 C_SIGNAL='@s9s_mb_2u_lib.s9s_mb_2u(sch_1):upi_cpu1_cpu0_p2p2_dp(23)';
NODE_NAME     U2 G80
 '@S9S_MB_2U_LIB.S9S_MB_2U(SCH_1):PAGE34_I102@PURE_QUANTA.SOCKET4677_AZIF0045P001C01CS(CHIPS)':
 'UPI2_RX_DP0': CDS_PINID='UPI2_RX_DP0';
NODE_NAME     U1 BN72
 '@S9S_MB_2U_LIB.S9S_MB_2U(SCH_1):PAGE65_I16@PURE_QUANTA.SOCKET4677_AZIF0045P001C01CS(CHIPS)':
 'UPI2_TX_DP23': CDS_PINID='UPI2_TX_DP23';
NET_NAME
'UPI_CPU1_CPU0_P2P2_DP<2>'
 '@S9S_MB_2U_LIB.S9S_MB_2U(SCH_1):UPI_CPU1_CPU0_P2P2_DP'<2>:
 C_SIGNAL='@s9s_mb_2u_lib.s9s_mb_2u(sch_1):upi_cpu1_cpu0_p2p2_dp(2)';
NODE_NAME     U2 BN74
 '@S9S_MB_2U_LIB.S9S_MB_2U(SCH_1):PAGE34_I102@PURE_QUANTA.SOCKET4677_AZIF0045P001C01CS(CHIPS)':
 'UPI2_RX_DN21': CDS_PINID='UPI2_RX_DN21';
NODE_NAME     U1 E88
 '@S9S_MB_2U_LIB.S9S_MB_2U(SCH_1):PAGE65_I16@PURE_QUANTA.SOCKET4677_AZIF0045P001C01CS(CHIPS)':
 'UPI2_TX_DP2': CDS_PINID='UPI2_TX_DP2';
NET_NAME
'UPI_CPU1_CPU0_P2P2_DP<3>'
 '@S9S_MB_2U_LIB.S9S_MB_2U(SCH_1):UPI_CPU1_CPU0_P2P2_DP'<3>:
 C_SIGNAL='@s9s_mb_2u_lib.s9s_mb_2u(sch_1):upi_cpu1_cpu0_p2p2_dp(3)';
NODE_NAME     U2 BG74
 '@S9S_MB_2U_LIB.S9S_MB_2U(SCH_1):PAGE34_I102@PURE_QUANTA.SOCKET4677_AZIF0045P001C01CS(CHIPS)':
 'UPI2_RX_DN20': CDS_PINID='UPI2_RX_DN20';
NODE_NAME     U1 H87
 '@S9S_MB_2U_LIB.S9S_MB_2U(SCH_1):PAGE65_I16@PURE_QUANTA.SOCKET4677_AZIF0045P001C01CS(CHIPS)':
 'UPI2_TX_DP3': CDS_PINID='UPI2_TX_DP3';
NET_NAME
'UPI_CPU1_CPU0_P2P2_DP<4>'
 '@S9S_MB_2U_LIB.S9S_MB_2U(SCH_1):UPI_CPU1_CPU0_P2P2_DP'<4>:
 C_SIGNAL='@s9s_mb_2u_lib.s9s_mb_2u(sch_1):upi_cpu1_cpu0_p2p2_dp(4)';
NODE_NAME     U2 BL76
 '@S9S_MB_2U_LIB.S9S_MB_2U(SCH_1):PAGE34_I102@PURE_QUANTA.SOCKET4677_AZIF0045P001C01CS(CHIPS)':
 'UPI2_RX_DN19': CDS_PINID='UPI2_RX_DN19';
NODE_NAME     U1 G86
 '@S9S_MB_2U_LIB.S9S_MB_2U(SCH_1):PAGE65_I16@PURE_QUANTA.SOCKET4677_AZIF0045P001C01CS(CHIPS)':
 'UPI2_TX_DP4': CDS_PINID='UPI2_TX_DP4';
NET_NAME
'UPI_CPU1_CPU0_P2P2_DP<5>'
 '@S9S_MB_2U_LIB.S9S_MB_2U(SCH_1):UPI_CPU1_CPU0_P2P2_DP'<5>:
 C_SIGNAL='@s9s_mb_2u_lib.s9s_mb_2u(sch_1):upi_cpu1_cpu0_p2p2_dp(5)';
NODE_NAME     U2 BK77
 '@S9S_MB_2U_LIB.S9S_MB_2U(SCH_1):PAGE34_I102@PURE_QUANTA.SOCKET4677_AZIF0045P001C01CS(CHIPS)':
 'UPI2_RX_DP18': CDS_PINID='UPI2_RX_DP18';
NODE_NAME     U1 T81
 '@S9S_MB_2U_LIB.S9S_MB_2U(SCH_1):PAGE65_I16@PURE_QUANTA.SOCKET4677_AZIF0045P001C01CS(CHIPS)':
 'UPI2_TX_DP5': CDS_PINID='UPI2_TX_DP5';
NET_NAME
'UPI_CPU1_CPU0_P2P2_DP<6>'
 '@S9S_MB_2U_LIB.S9S_MB_2U(SCH_1):UPI_CPU1_CPU0_P2P2_DP'<6>:
 C_SIGNAL='@s9s_mb_2u_lib.s9s_mb_2u(sch_1):upi_cpu1_cpu0_p2p2_dp(6)';
NODE_NAME     U2 BG76
 '@S9S_MB_2U_LIB.S9S_MB_2U(SCH_1):PAGE34_I102@PURE_QUANTA.SOCKET4677_AZIF0045P001C01CS(CHIPS)':
 'UPI2_RX_DP17': CDS_PINID='UPI2_RX_DP17';
NODE_NAME     U1 P83
 '@S9S_MB_2U_LIB.S9S_MB_2U(SCH_1):PAGE65_I16@PURE_QUANTA.SOCKET4677_AZIF0045P001C01CS(CHIPS)':
 'UPI2_TX_DP6': CDS_PINID='UPI2_TX_DP6';
NET_NAME
'UPI_CPU1_CPU0_P2P2_DP<7>'
 '@S9S_MB_2U_LIB.S9S_MB_2U(SCH_1):UPI_CPU1_CPU0_P2P2_DP'<7>:
 C_SIGNAL='@s9s_mb_2u_lib.s9s_mb_2u(sch_1):upi_cpu1_cpu0_p2p2_dp(7)';
NODE_NAME     U2 AW74
 '@S9S_MB_2U_LIB.S9S_MB_2U(SCH_1):PAGE34_I102@PURE_QUANTA.SOCKET4677_AZIF0045P001C01CS(CHIPS)':
 'UPI2_RX_DN16': CDS_PINID='UPI2_RX_DN16';
NODE_NAME     U1 V81
 '@S9S_MB_2U_LIB.S9S_MB_2U(SCH_1):PAGE65_I16@PURE_QUANTA.SOCKET4677_AZIF0045P001C01CS(CHIPS)':
 'UPI2_TX_DP7': CDS_PINID='UPI2_TX_DP7';
NET_NAME
'UPI_CPU1_CPU0_P2P2_DP<8>'
 '@S9S_MB_2U_LIB.S9S_MB_2U(SCH_1):UPI_CPU1_CPU0_P2P2_DP'<8>:
 C_SIGNAL='@s9s_mb_2u_lib.s9s_mb_2u(sch_1):upi_cpu1_cpu0_p2p2_dp(8)';
NODE_NAME     U2 BB75
 '@S9S_MB_2U_LIB.S9S_MB_2U(SCH_1):PAGE34_I102@PURE_QUANTA.SOCKET4677_AZIF0045P001C01CS(CHIPS)':
 'UPI2_RX_DN15': CDS_PINID='UPI2_RX_DN15';
NODE_NAME     U1 Y83
 '@S9S_MB_2U_LIB.S9S_MB_2U(SCH_1):PAGE65_I16@PURE_QUANTA.SOCKET4677_AZIF0045P001C01CS(CHIPS)':
 'UPI2_TX_DP8': CDS_PINID='UPI2_TX_DP8';
NET_NAME
'UPI_CPU1_CPU0_P2P2_DP<9>'
 '@S9S_MB_2U_LIB.S9S_MB_2U(SCH_1):UPI_CPU1_CPU0_P2P2_DP'<9>:
 C_SIGNAL='@s9s_mb_2u_lib.s9s_mb_2u(sch_1):upi_cpu1_cpu0_p2p2_dp(9)';
NODE_NAME     U2 BA76
 '@S9S_MB_2U_LIB.S9S_MB_2U(SCH_1):PAGE34_I102@PURE_QUANTA.SOCKET4677_AZIF0045P001C01CS(CHIPS)':
 'UPI2_RX_DP14': CDS_PINID='UPI2_RX_DP14';
NODE_NAME     U1 W82
 '@S9S_MB_2U_LIB.S9S_MB_2U(SCH_1):PAGE65_I16@PURE_QUANTA.SOCKET4677_AZIF0045P001C01CS(CHIPS)':
 'UPI2_TX_DP9': CDS_PINID='UPI2_TX_DP9';
NET_NAME
'USB2_0_DN'
 '@S9S_MB_2U_LIB.S9S_MB_2U(SCH_1):USB2_0_DN':
 C_SIGNAL='@s9s_mb_2u_lib.s9s_mb_2u(sch_1):usb2_0_dn';
NODE_NAME     U4 AR42
 '@S9S_MB_2U_LIB.S9S_MB_2U(SCH_1):PAGE172_I11@PURE_QUANTA.EMMITSBURG_REV0P9(CHIPS)':
 'USB2N_0': CDS_PINID='USB2N_0';
NODE_NAME     R4474 1
 '@S9S_MB_2U_LIB.S9S_MB_2U(SCH_1):PAGE194_I72@PURE_QUANTA.Q_RES(CHIPS)':
 'A': CDS_PINID='A';
NODE_NAME     R4472 2
 '@S9S_MB_2U_LIB.S9S_MB_2U(SCH_1):PAGE194_I78@PURE_QUANTA.Q_RES(CHIPS)':
 'B': CDS_PINID='B';
NET_NAME
'USB2_0_DP'
 '@S9S_MB_2U_LIB.S9S_MB_2U(SCH_1):USB2_0_DP':
 C_SIGNAL='@s9s_mb_2u_lib.s9s_mb_2u(sch_1):usb2_0_dp';
NODE_NAME     U4 AR40
 '@S9S_MB_2U_LIB.S9S_MB_2U(SCH_1):PAGE172_I11@PURE_QUANTA.EMMITSBURG_REV0P9(CHIPS)':
 'USB2P_0': CDS_PINID='USB2P_0';
NODE_NAME     R4473 1
 '@S9S_MB_2U_LIB.S9S_MB_2U(SCH_1):PAGE194_I73@PURE_QUANTA.Q_RES(CHIPS)':
 'A': CDS_PINID='A';
NODE_NAME     R4471 2
 '@S9S_MB_2U_LIB.S9S_MB_2U(SCH_1):PAGE194_I77@PURE_QUANTA.Q_RES(CHIPS)':
 'B': CDS_PINID='B';
NET_NAME
'USB2_3_DN'
 '@S9S_MB_2U_LIB.S9S_MB_2U(SCH_1):USB2_3_DN':
 C_SIGNAL='@s9s_mb_2u_lib.s9s_mb_2u(sch_1):usb2_3_dn';
NODE_NAME     U4 AN42
 '@S9S_MB_2U_LIB.S9S_MB_2U(SCH_1):PAGE172_I11@PURE_QUANTA.EMMITSBURG_REV0P9(CHIPS)':
 'USB2N_3': CDS_PINID='USB2N_3';
NODE_NAME     R444 2
 '@S9S_MB_2U_LIB.S9S_MB_2U(SCH_1):PAGE150_I118@PURE_QUANTA.Q_RES(CHIPS)':
 'B': CDS_PINID='B';
NET_NAME
'USB2_3_DP'
 '@S9S_MB_2U_LIB.S9S_MB_2U(SCH_1):USB2_3_DP':
 C_SIGNAL='@s9s_mb_2u_lib.s9s_mb_2u(sch_1):usb2_3_dp';
NODE_NAME     U4 AN40
 '@S9S_MB_2U_LIB.S9S_MB_2U(SCH_1):PAGE172_I11@PURE_QUANTA.EMMITSBURG_REV0P9(CHIPS)':
 'USB2P_3': CDS_PINID='USB2P_3';
NODE_NAME     R445 2
 '@S9S_MB_2U_LIB.S9S_MB_2U(SCH_1):PAGE150_I119@PURE_QUANTA.Q_RES(CHIPS)':
 'B': CDS_PINID='B';
NET_NAME
'USB2_5_DN'
 '@S9S_MB_2U_LIB.S9S_MB_2U(SCH_1):USB2_5_DN':
 C_SIGNAL='@s9s_mb_2u_lib.s9s_mb_2u(sch_1):usb2_5_dn';
NODE_NAME     U4 AL43
 '@S9S_MB_2U_LIB.S9S_MB_2U(SCH_1):PAGE172_I11@PURE_QUANTA.EMMITSBURG_REV0P9(CHIPS)':
 'USB2N_5': CDS_PINID='USB2N_5';
NODE_NAME     R3177 2
 '@S9S_MB_2U_LIB.S9S_MB_2U(SCH_1):PAGE146_I148@PURE_QUANTA.Q_RES(CHIPS)':
 'B': CDS_PINID='B';
NET_NAME
'USB2_5_DP'
 '@S9S_MB_2U_LIB.S9S_MB_2U(SCH_1):USB2_5_DP':
 C_SIGNAL='@s9s_mb_2u_lib.s9s_mb_2u(sch_1):usb2_5_dp';
NODE_NAME     U4 AL41
 '@S9S_MB_2U_LIB.S9S_MB_2U(SCH_1):PAGE172_I11@PURE_QUANTA.EMMITSBURG_REV0P9(CHIPS)':
 'USB2P_5': CDS_PINID='USB2P_5';
NODE_NAME     R3178 2
 '@S9S_MB_2U_LIB.S9S_MB_2U(SCH_1):PAGE146_I147@PURE_QUANTA.Q_RES(CHIPS)':
 'B': CDS_PINID='B';
NET_NAME
'USB2_5_R1_DN'
 '@S9S_MB_2U_LIB.S9S_MB_2U(SCH_1):USB2_5_R1_DN':
 C_SIGNAL='@s9s_mb_2u_lib.s9s_mb_2u(sch_1):usb2_5_r1_dn';
NODE_NAME     R3177 1
 '@S9S_MB_2U_LIB.S9S_MB_2U(SCH_1):PAGE146_I148@PURE_QUANTA.Q_RES(CHIPS)':
 'A': CDS_PINID='A';
NODE_NAME     J35 A68
 '@S9S_MB_2U_LIB.S9S_MB_2U(SCH_1):PAGE146_I303@PURE_QUANTA.SCONN168_ME1016810202011(CHIPS)':
 'USB_DATN': CDS_PINID='USB_DATN';
NET_NAME
'USB2_5_R1_DP'
 '@S9S_MB_2U_LIB.S9S_MB_2U(SCH_1):USB2_5_R1_DP':
 C_SIGNAL='@s9s_mb_2u_lib.s9s_mb_2u(sch_1):usb2_5_r1_dp';
NODE_NAME     R3178 1
 '@S9S_MB_2U_LIB.S9S_MB_2U(SCH_1):PAGE146_I147@PURE_QUANTA.Q_RES(CHIPS)':
 'A': CDS_PINID='A';
NODE_NAME     J35 A69
 '@S9S_MB_2U_LIB.S9S_MB_2U(SCH_1):PAGE146_I303@PURE_QUANTA.SCONN168_ME1016810202011(CHIPS)':
 'USB_DATP': CDS_PINID='USB_DATP';
NET_NAME
'USB2_7_DN'
 '@S9S_MB_2U_LIB.S9S_MB_2U(SCH_1):USB2_7_DN':
 C_SIGNAL='@s9s_mb_2u_lib.s9s_mb_2u(sch_1):usb2_7_dn';
NODE_NAME     U4 AK42
 '@S9S_MB_2U_LIB.S9S_MB_2U(SCH_1):PAGE172_I11@PURE_QUANTA.EMMITSBURG_REV0P9(CHIPS)':
 'USB2N_7': CDS_PINID='USB2N_7';
NODE_NAME     R2257 2
 '@S9S_MB_2U_LIB.S9S_MB_2U(SCH_1):PAGE227_I164@PURE_QUANTA.Q_RES(CHIPS)':
 'B': CDS_PINID='B';
NET_NAME
'USB2_7_DP'
 '@S9S_MB_2U_LIB.S9S_MB_2U(SCH_1):USB2_7_DP':
 C_SIGNAL='@s9s_mb_2u_lib.s9s_mb_2u(sch_1):usb2_7_dp';
NODE_NAME     U4 AK40
 '@S9S_MB_2U_LIB.S9S_MB_2U(SCH_1):PAGE172_I11@PURE_QUANTA.EMMITSBURG_REV0P9(CHIPS)':
 'USB2P_7': CDS_PINID='USB2P_7';
NODE_NAME     R2256 2
 '@S9S_MB_2U_LIB.S9S_MB_2U(SCH_1):PAGE227_I167@PURE_QUANTA.Q_RES(CHIPS)':
 'B': CDS_PINID='B';
NET_NAME
'USB2_7_R_DN'
 '@S9S_MB_2U_LIB.S9S_MB_2U(SCH_1):USB2_7_R_DN':
 C_SIGNAL='@s9s_mb_2u_lib.s9s_mb_2u(sch_1):usb2_7_r_dn';
NODE_NAME     R2257 1
 '@S9S_MB_2U_LIB.S9S_MB_2U(SCH_1):PAGE227_I164@PURE_QUANTA.Q_RES(CHIPS)':
 'A': CDS_PINID='A';
NODE_NAME     J41 OB9
 '@S9S_MB_2U_LIB.S9S_MB_2U(SCH_1):PAGE227_I173@PURE_QUANTA.SCONN168_ME1016810202011(CHIPS)':
 'RBT_RXD0': CDS_PINID='RBT_RXD0';
NET_NAME
'USB2_7_R_DP'
 '@S9S_MB_2U_LIB.S9S_MB_2U(SCH_1):USB2_7_R_DP':
 C_SIGNAL='@s9s_mb_2u_lib.s9s_mb_2u(sch_1):usb2_7_r_dp';
NODE_NAME     R2256 1
 '@S9S_MB_2U_LIB.S9S_MB_2U(SCH_1):PAGE227_I167@PURE_QUANTA.Q_RES(CHIPS)':
 'A': CDS_PINID='A';
NODE_NAME     J41 OB8
 '@S9S_MB_2U_LIB.S9S_MB_2U(SCH_1):PAGE227_I173@PURE_QUANTA.SCONN168_ME1016810202011(CHIPS)':
 'RBT_RXD1': CDS_PINID='RBT_RXD1';
NET_NAME
'USB2_8_DN'
 '@S9S_MB_2U_LIB.S9S_MB_2U(SCH_1):USB2_8_DN':
 C_SIGNAL='@s9s_mb_2u_lib.s9s_mb_2u(sch_1):usb2_8_dn';
NODE_NAME     U4 AW42
 '@S9S_MB_2U_LIB.S9S_MB_2U(SCH_1):PAGE172_I11@PURE_QUANTA.EMMITSBURG_REV0P9(CHIPS)':
 'USB2N_8': CDS_PINID='USB2N_8';
NODE_NAME     J41 B54
 '@S9S_MB_2U_LIB.S9S_MB_2U(SCH_1):PAGE227_I173@PURE_QUANTA.SCONN168_ME1016810202011(CHIPS)':
 'PETP11': CDS_PINID='PETP11';
NET_NAME
'USB2_8_DP'
 '@S9S_MB_2U_LIB.S9S_MB_2U(SCH_1):USB2_8_DP':
 C_SIGNAL='@s9s_mb_2u_lib.s9s_mb_2u(sch_1):usb2_8_dp';
NODE_NAME     U4 AW40
 '@S9S_MB_2U_LIB.S9S_MB_2U(SCH_1):PAGE172_I11@PURE_QUANTA.EMMITSBURG_REV0P9(CHIPS)':
 'USB2P_8': CDS_PINID='USB2P_8';
NODE_NAME     J41 B53
 '@S9S_MB_2U_LIB.S9S_MB_2U(SCH_1):PAGE227_I173@PURE_QUANTA.SCONN168_ME1016810202011(CHIPS)':
 'PETN11': CDS_PINID='PETN11';
NET_NAME
'USB2_HOST_BMC_B_BUF_DN'
 '@S9S_MB_2U_LIB.S9S_MB_2U(SCH_1):USB2_HOST_BMC_B_BUF_DN':
 C_SIGNAL='@s9s_mb_2u_lib.s9s_mb_2u(sch_1):usb2_host_bmc_b_buf_dn';
NODE_NAME     R2791 2
 '@S9S_MB_2U_LIB.S9S_MB_2U(SCH_1):PAGE155_I97@PURE_QUANTA.Q_RES(CHIPS)':
 'B': CDS_PINID='B';
NODE_NAME     R2789 1
 '@S9S_MB_2U_LIB.S9S_MB_2U(SCH_1):PAGE155_I98@PURE_QUANTA.Q_RES(CHIPS)':
 'A': CDS_PINID='A';
NODE_NAME     R4483 1
 '@S9S_MB_2U_LIB.S9S_MB_2U(SCH_1):PAGE155_I206@PURE_QUANTA.Q_RES(CHIPS)':
 'A': CDS_PINID='A';
NET_NAME
'USB2_HOST_BMC_B_BUF_DP'
 '@S9S_MB_2U_LIB.S9S_MB_2U(SCH_1):USB2_HOST_BMC_B_BUF_DP':
 C_SIGNAL='@s9s_mb_2u_lib.s9s_mb_2u(sch_1):usb2_host_bmc_b_buf_dp';
NODE_NAME     R2790 2
 '@S9S_MB_2U_LIB.S9S_MB_2U(SCH_1):PAGE155_I96@PURE_QUANTA.Q_RES(CHIPS)':
 'B': CDS_PINID='B';
NODE_NAME     R2788 1
 '@S9S_MB_2U_LIB.S9S_MB_2U(SCH_1):PAGE155_I99@PURE_QUANTA.Q_RES(CHIPS)':
 'A': CDS_PINID='A';
NODE_NAME     R4482 1
 '@S9S_MB_2U_LIB.S9S_MB_2U(SCH_1):PAGE155_I208@PURE_QUANTA.Q_RES(CHIPS)':
 'A': CDS_PINID='A';
NET_NAME
'USB2_HOST_BMC_B_DN'
 '@S9S_MB_2U_LIB.S9S_MB_2U(SCH_1):USB2_HOST_BMC_B_DN':
 C_SIGNAL='@s9s_mb_2u_lib.s9s_mb_2u(sch_1):usb2_host_bmc_b_dn';
NODE_NAME     R2791 1
 '@S9S_MB_2U_LIB.S9S_MB_2U(SCH_1):PAGE155_I97@PURE_QUANTA.Q_RES(CHIPS)':
 'A': CDS_PINID='A';
NODE_NAME     R3652 2
 '@S9S_MB_2U_LIB.S9S_MB_2U(SCH_1):PAGE155_I137@PURE_QUANTA.Q_RES(CHIPS)':
 'B': CDS_PINID='B';
NODE_NAME     R4420 1
 '@S9S_MB_2U_LIB.S9S_MB_2U(SCH_1):PAGE155_I202@PURE_QUANTA.Q_RES(CHIPS)':
 'A': CDS_PINID='A';
NODE_NAME     J41 B51
 '@S9S_MB_2U_LIB.S9S_MB_2U(SCH_1):PAGE227_I173@PURE_QUANTA.SCONN168_ME1016810202011(CHIPS)':
 'PETP10': CDS_PINID='PETP10';
NET_NAME
'USB2_HOST_BMC_B_DP'
 '@S9S_MB_2U_LIB.S9S_MB_2U(SCH_1):USB2_HOST_BMC_B_DP':
 C_SIGNAL='@s9s_mb_2u_lib.s9s_mb_2u(sch_1):usb2_host_bmc_b_dp';
NODE_NAME     R2790 1
 '@S9S_MB_2U_LIB.S9S_MB_2U(SCH_1):PAGE155_I96@PURE_QUANTA.Q_RES(CHIPS)':
 'A': CDS_PINID='A';
NODE_NAME     R3651 2
 '@S9S_MB_2U_LIB.S9S_MB_2U(SCH_1):PAGE155_I138@PURE_QUANTA.Q_RES(CHIPS)':
 'B': CDS_PINID='B';
NODE_NAME     R4419 1
 '@S9S_MB_2U_LIB.S9S_MB_2U(SCH_1):PAGE155_I203@PURE_QUANTA.Q_RES(CHIPS)':
 'A': CDS_PINID='A';
NODE_NAME     J41 B50
 '@S9S_MB_2U_LIB.S9S_MB_2U(SCH_1):PAGE227_I173@PURE_QUANTA.SCONN168_ME1016810202011(CHIPS)':
 'PETN10': CDS_PINID='PETN10';
NET_NAME
'USB2_HOST_PCH_0_DN'
 '@S9S_MB_2U_LIB.S9S_MB_2U(SCH_1):USB2_HOST_PCH_0_DN':
 C_SIGNAL='@s9s_mb_2u_lib.s9s_mb_2u(sch_1):usb2_host_pch_0_dn';
NODE_NAME     R4461 1
 '@S9S_MB_2U_LIB.S9S_MB_2U(SCH_1):PAGE194_I19@PURE_QUANTA.Q_RES(CHIPS)':
 'A': CDS_PINID='A';
NODE_NAME     R4474 2
 '@S9S_MB_2U_LIB.S9S_MB_2U(SCH_1):PAGE194_I72@PURE_QUANTA.Q_RES(CHIPS)':
 'B': CDS_PINID='B';
NODE_NAME     R4487 1
 '@S9S_MB_2U_LIB.S9S_MB_2U(SCH_1):PAGE194_I88@PURE_QUANTA.Q_RES(CHIPS)':
 'A': CDS_PINID='A';
NET_NAME
'USB2_HOST_PCH_0_DP'
 '@S9S_MB_2U_LIB.S9S_MB_2U(SCH_1):USB2_HOST_PCH_0_DP':
 C_SIGNAL='@s9s_mb_2u_lib.s9s_mb_2u(sch_1):usb2_host_pch_0_dp';
NODE_NAME     R4460 1
 '@S9S_MB_2U_LIB.S9S_MB_2U(SCH_1):PAGE194_I18@PURE_QUANTA.Q_RES(CHIPS)':
 'A': CDS_PINID='A';
NODE_NAME     R4473 2
 '@S9S_MB_2U_LIB.S9S_MB_2U(SCH_1):PAGE194_I73@PURE_QUANTA.Q_RES(CHIPS)':
 'B': CDS_PINID='B';
NODE_NAME     R4486 1
 '@S9S_MB_2U_LIB.S9S_MB_2U(SCH_1):PAGE194_I90@PURE_QUANTA.Q_RES(CHIPS)':
 'A': CDS_PINID='A';
NET_NAME
'USB2_HUB_2_BUF_EXT_DN'
 '@S9S_MB_2U_LIB.S9S_MB_2U(SCH_1):USB2_HUB_2_BUF_EXT_DN':
 C_SIGNAL='@s9s_mb_2u_lib.s9s_mb_2u(sch_1):usb2_hub_2_buf_ext_dn';
NODE_NAME     R4468 2
 '@S9S_MB_2U_LIB.S9S_MB_2U(SCH_1):PAGE194_I60@PURE_QUANTA.Q_RES(CHIPS)':
 'B': CDS_PINID='B';
NODE_NAME     J41 B57
 '@S9S_MB_2U_LIB.S9S_MB_2U(SCH_1):PAGE227_I173@PURE_QUANTA.SCONN168_ME1016810202011(CHIPS)':
 'PETP12': CDS_PINID='PETP12';
NET_NAME
'USB2_HUB_2_BUF_EXT_DP'
 '@S9S_MB_2U_LIB.S9S_MB_2U(SCH_1):USB2_HUB_2_BUF_EXT_DP':
 C_SIGNAL='@s9s_mb_2u_lib.s9s_mb_2u(sch_1):usb2_hub_2_buf_ext_dp';
NODE_NAME     R4467 2
 '@S9S_MB_2U_LIB.S9S_MB_2U(SCH_1):PAGE194_I61@PURE_QUANTA.Q_RES(CHIPS)':
 'B': CDS_PINID='B';
NODE_NAME     J41 B56
 '@S9S_MB_2U_LIB.S9S_MB_2U(SCH_1):PAGE227_I173@PURE_QUANTA.SCONN168_ME1016810202011(CHIPS)':
 'PETN12': CDS_PINID='PETN12';
NET_NAME
'USB2_HUB_2_BUF_EXT_R_DN'
 '@S9S_MB_2U_LIB.S9S_MB_2U(SCH_1):USB2_HUB_2_BUF_EXT_R_DN':
 C_SIGNAL='@s9s_mb_2u_lib.s9s_mb_2u(sch_1):usb2_hub_2_buf_ext_r_dn';
NODE_NAME     R4455 2
 '@S9S_MB_2U_LIB.S9S_MB_2U(SCH_1):PAGE194_I16@PURE_QUANTA.Q_RES(CHIPS)':
 'B': CDS_PINID='B';
NODE_NAME     R4461 2
 '@S9S_MB_2U_LIB.S9S_MB_2U(SCH_1):PAGE194_I19@PURE_QUANTA.Q_RES(CHIPS)':
 'B': CDS_PINID='B';
NODE_NAME     U312 1
 '@S9S_MB_2U_LIB.S9S_MB_2U(SCH_1):PAGE194_I20@PURE_QUANTA.TUSB211IRWBR(CHIPS)':
 'D1M': CDS_PINID='D1M';
NODE_NAME     U312 8
 '@S9S_MB_2U_LIB.S9S_MB_2U(SCH_1):PAGE194_I20@PURE_QUANTA.TUSB211IRWBR(CHIPS)':
 'D2M': CDS_PINID='D2M';
NODE_NAME     R4468 1
 '@S9S_MB_2U_LIB.S9S_MB_2U(SCH_1):PAGE194_I60@PURE_QUANTA.Q_RES(CHIPS)':
 'A': CDS_PINID='A';
NET_NAME
'USB2_HUB_2_BUF_EXT_R_DP'
 '@S9S_MB_2U_LIB.S9S_MB_2U(SCH_1):USB2_HUB_2_BUF_EXT_R_DP':
 C_SIGNAL='@s9s_mb_2u_lib.s9s_mb_2u(sch_1):usb2_hub_2_buf_ext_r_dp';
NODE_NAME     R4454 2
 '@S9S_MB_2U_LIB.S9S_MB_2U(SCH_1):PAGE194_I17@PURE_QUANTA.Q_RES(CHIPS)':
 'B': CDS_PINID='B';
NODE_NAME     R4460 2
 '@S9S_MB_2U_LIB.S9S_MB_2U(SCH_1):PAGE194_I18@PURE_QUANTA.Q_RES(CHIPS)':
 'B': CDS_PINID='B';
NODE_NAME     U312 2
 '@S9S_MB_2U_LIB.S9S_MB_2U(SCH_1):PAGE194_I20@PURE_QUANTA.TUSB211IRWBR(CHIPS)':
 'D1P': CDS_PINID='D1P';
NODE_NAME     U312 7
 '@S9S_MB_2U_LIB.S9S_MB_2U(SCH_1):PAGE194_I20@PURE_QUANTA.TUSB211IRWBR(CHIPS)':
 'D2P': CDS_PINID='D2P';
NODE_NAME     R4467 1
 '@S9S_MB_2U_LIB.S9S_MB_2U(SCH_1):PAGE194_I61@PURE_QUANTA.Q_RES(CHIPS)':
 'A': CDS_PINID='A';
NET_NAME
'USB2_HUB_2_EXT_DN'
 '@S9S_MB_2U_LIB.S9S_MB_2U(SCH_1):USB2_HUB_2_EXT_DN':
 C_SIGNAL='@s9s_mb_2u_lib.s9s_mb_2u(sch_1):usb2_hub_2_ext_dn';
NODE_NAME     R4455 1
 '@S9S_MB_2U_LIB.S9S_MB_2U(SCH_1):PAGE194_I16@PURE_QUANTA.Q_RES(CHIPS)':
 'A': CDS_PINID='A';
NODE_NAME     U313 3
 '@S9S_MB_2U_LIB.S9S_MB_2U(SCH_1):PAGE194_I40@PURE_QUANTA.GL852GOHY60(CHIPS)':
 'DM1': CDS_PINID='DM1';
NET_NAME
'USB2_HUB_2_EXT_DP'
 '@S9S_MB_2U_LIB.S9S_MB_2U(SCH_1):USB2_HUB_2_EXT_DP':
 C_SIGNAL='@s9s_mb_2u_lib.s9s_mb_2u(sch_1):usb2_hub_2_ext_dp';
NODE_NAME     R4454 1
 '@S9S_MB_2U_LIB.S9S_MB_2U(SCH_1):PAGE194_I17@PURE_QUANTA.Q_RES(CHIPS)':
 'A': CDS_PINID='A';
NODE_NAME     U313 4
 '@S9S_MB_2U_LIB.S9S_MB_2U(SCH_1):PAGE194_I40@PURE_QUANTA.GL852GOHY60(CHIPS)':
 'DP1': CDS_PINID='DP1';
NET_NAME
'USB2_HUB_BUF_SWB_DN'
 '@S9S_MB_2U_LIB.S9S_MB_2U(SCH_1):USB2_HUB_BUF_SWB_DN':
 C_SIGNAL='@s9s_mb_2u_lib.s9s_mb_2u(sch_1):usb2_hub_buf_swb_dn';
NODE_NAME     J112 R1
 '@S9S_MB_2U_LIB.S9S_MB_2U(SCH_1):PAGE149_I76@PURE_QUANTA.CONN160_10131762101LF(CHIPS)':
 'R1': CDS_PINID='R1';
NODE_NAME     R5236 2
 '@S9S_MB_2U_LIB.S9S_MB_2U(SCH_1):PAGE155_I90@PURE_QUANTA.Q_RES(CHIPS)':
 'B': CDS_PINID='B';
NET_NAME
'USB2_HUB_BUF_SWB_DP'
 '@S9S_MB_2U_LIB.S9S_MB_2U(SCH_1):USB2_HUB_BUF_SWB_DP':
 C_SIGNAL='@s9s_mb_2u_lib.s9s_mb_2u(sch_1):usb2_hub_buf_swb_dp';
NODE_NAME     J112 S1
 '@S9S_MB_2U_LIB.S9S_MB_2U(SCH_1):PAGE149_I76@PURE_QUANTA.CONN160_10131762101LF(CHIPS)':
 'S1': CDS_PINID='S1';
NODE_NAME     R5234 2
 '@S9S_MB_2U_LIB.S9S_MB_2U(SCH_1):PAGE155_I91@PURE_QUANTA.Q_RES(CHIPS)':
 'B': CDS_PINID='B';
NET_NAME
'USB2_HUB_BUF_SWB_R_DN'
 '@S9S_MB_2U_LIB.S9S_MB_2U(SCH_1):USB2_HUB_BUF_SWB_R_DN':
 C_SIGNAL='@s9s_mb_2u_lib.s9s_mb_2u(sch_1):usb2_hub_buf_swb_r_dn';
NODE_NAME     R2787 2
 '@S9S_MB_2U_LIB.S9S_MB_2U(SCH_1):PAGE155_I78@PURE_QUANTA.Q_RES(CHIPS)':
 'B': CDS_PINID='B';
NODE_NAME     U5201 1
 '@S9S_MB_2U_LIB.S9S_MB_2U(SCH_1):PAGE155_I84@PURE_QUANTA.TUSB211IRWBR(CHIPS)':
 'D1M': CDS_PINID='D1M';
NODE_NAME     U5201 8
 '@S9S_MB_2U_LIB.S9S_MB_2U(SCH_1):PAGE155_I84@PURE_QUANTA.TUSB211IRWBR(CHIPS)':
 'D2M': CDS_PINID='D2M';
NODE_NAME     R5236 1
 '@S9S_MB_2U_LIB.S9S_MB_2U(SCH_1):PAGE155_I90@PURE_QUANTA.Q_RES(CHIPS)':
 'A': CDS_PINID='A';
NODE_NAME     R2789 2
 '@S9S_MB_2U_LIB.S9S_MB_2U(SCH_1):PAGE155_I98@PURE_QUANTA.Q_RES(CHIPS)':
 'B': CDS_PINID='B';
NET_NAME
'USB2_HUB_BUF_SWB_R_DP'
 '@S9S_MB_2U_LIB.S9S_MB_2U(SCH_1):USB2_HUB_BUF_SWB_R_DP':
 C_SIGNAL='@s9s_mb_2u_lib.s9s_mb_2u(sch_1):usb2_hub_buf_swb_r_dp';
NODE_NAME     R2786 2
 '@S9S_MB_2U_LIB.S9S_MB_2U(SCH_1):PAGE155_I79@PURE_QUANTA.Q_RES(CHIPS)':
 'B': CDS_PINID='B';
NODE_NAME     U5201 2
 '@S9S_MB_2U_LIB.S9S_MB_2U(SCH_1):PAGE155_I84@PURE_QUANTA.TUSB211IRWBR(CHIPS)':
 'D1P': CDS_PINID='D1P';
NODE_NAME     U5201 7
 '@S9S_MB_2U_LIB.S9S_MB_2U(SCH_1):PAGE155_I84@PURE_QUANTA.TUSB211IRWBR(CHIPS)':
 'D2P': CDS_PINID='D2P';
NODE_NAME     R5234 1
 '@S9S_MB_2U_LIB.S9S_MB_2U(SCH_1):PAGE155_I91@PURE_QUANTA.Q_RES(CHIPS)':
 'A': CDS_PINID='A';
NODE_NAME     R2788 2
 '@S9S_MB_2U_LIB.S9S_MB_2U(SCH_1):PAGE155_I99@PURE_QUANTA.Q_RES(CHIPS)':
 'B': CDS_PINID='B';
NET_NAME
'USB2_HUB_SWB_DN'
 '@S9S_MB_2U_LIB.S9S_MB_2U(SCH_1):USB2_HUB_SWB_DN':
 C_SIGNAL='@s9s_mb_2u_lib.s9s_mb_2u(sch_1):usb2_hub_swb_dn';
NODE_NAME     R2787 1
 '@S9S_MB_2U_LIB.S9S_MB_2U(SCH_1):PAGE155_I78@PURE_QUANTA.Q_RES(CHIPS)':
 'A': CDS_PINID='A';
NODE_NAME     U268 3
 '@S9S_MB_2U_LIB.S9S_MB_2U(SCH_1):PAGE155_I100@PURE_QUANTA.GL852GOHY60(CHIPS)':
 'DM1': CDS_PINID='DM1';
NET_NAME
'USB2_HUB_SWB_DP'
 '@S9S_MB_2U_LIB.S9S_MB_2U(SCH_1):USB2_HUB_SWB_DP':
 C_SIGNAL='@s9s_mb_2u_lib.s9s_mb_2u(sch_1):usb2_hub_swb_dp';
NODE_NAME     R2786 1
 '@S9S_MB_2U_LIB.S9S_MB_2U(SCH_1):PAGE155_I79@PURE_QUANTA.Q_RES(CHIPS)':
 'A': CDS_PINID='A';
NODE_NAME     U268 4
 '@S9S_MB_2U_LIB.S9S_MB_2U(SCH_1):PAGE155_I100@PURE_QUANTA.GL852GOHY60(CHIPS)':
 'DP1': CDS_PINID='DP1';
NET_NAME
'USB2_P0_R_DN'
 '@S9S_MB_2U_LIB.S9S_MB_2U(SCH_1):USB2_P0_R_DN':
 C_SIGNAL='@s9s_mb_2u_lib.s9s_mb_2u(sch_1):usb2_p0_r_dn';
NODE_NAME     U268 1
 '@S9S_MB_2U_LIB.S9S_MB_2U(SCH_1):PAGE155_I100@PURE_QUANTA.GL852GOHY60(CHIPS)':
 'DM0': CDS_PINID='DM0';
NODE_NAME     R3652 1
 '@S9S_MB_2U_LIB.S9S_MB_2U(SCH_1):PAGE155_I137@PURE_QUANTA.Q_RES(CHIPS)':
 'A': CDS_PINID='A';
NET_NAME
'USB2_P0_R_DP'
 '@S9S_MB_2U_LIB.S9S_MB_2U(SCH_1):USB2_P0_R_DP':
 C_SIGNAL='@s9s_mb_2u_lib.s9s_mb_2u(sch_1):usb2_p0_r_dp';
NODE_NAME     U268 2
 '@S9S_MB_2U_LIB.S9S_MB_2U(SCH_1):PAGE155_I100@PURE_QUANTA.GL852GOHY60(CHIPS)':
 'DP0': CDS_PINID='DP0';
NODE_NAME     R3651 1
 '@S9S_MB_2U_LIB.S9S_MB_2U(SCH_1):PAGE155_I138@PURE_QUANTA.Q_RES(CHIPS)':
 'A': CDS_PINID='A';
NET_NAME
'USB2_PCH_0_R_DN'
 '@S9S_MB_2U_LIB.S9S_MB_2U(SCH_1):USB2_PCH_0_R_DN':
 C_SIGNAL='@s9s_mb_2u_lib.s9s_mb_2u(sch_1):usb2_pch_0_r_dn';
NODE_NAME     U313 1
 '@S9S_MB_2U_LIB.S9S_MB_2U(SCH_1):PAGE194_I40@PURE_QUANTA.GL852GOHY60(CHIPS)':
 'DM0': CDS_PINID='DM0';
NODE_NAME     R4472 1
 '@S9S_MB_2U_LIB.S9S_MB_2U(SCH_1):PAGE194_I78@PURE_QUANTA.Q_RES(CHIPS)':
 'A': CDS_PINID='A';
NET_NAME
'USB2_PCH_0_R_DP'
 '@S9S_MB_2U_LIB.S9S_MB_2U(SCH_1):USB2_PCH_0_R_DP':
 C_SIGNAL='@s9s_mb_2u_lib.s9s_mb_2u(sch_1):usb2_pch_0_r_dp';
NODE_NAME     U313 2
 '@S9S_MB_2U_LIB.S9S_MB_2U(SCH_1):PAGE194_I40@PURE_QUANTA.GL852GOHY60(CHIPS)':
 'DP0': CDS_PINID='DP0';
NODE_NAME     R4471 1
 '@S9S_MB_2U_LIB.S9S_MB_2U(SCH_1):PAGE194_I77@PURE_QUANTA.Q_RES(CHIPS)':
 'A': CDS_PINID='A';
NET_NAME
'USB3_PCH_RX_BUF_C_DN<4>'
 '@S9S_MB_2U_LIB.S9S_MB_2U(SCH_1):USB3_PCH_RX_BUF_C_DN'<4>:
 C_SIGNAL='@s9s_mb_2u_lib.s9s_mb_2u(sch_1):usb3_pch_rx_buf_c_dn(4)';
NODE_NAME     U309 11
 '@S9S_MB_2U_LIB.S9S_MB_2U(SCH_1):PAGE162_I43@PURE_QUANTA.PI3EQX1002EZREX(CHIPS)':
 'BON': CDS_PINID='BON';
NODE_NAME     C2292 1
 '@S9S_MB_2U_LIB.S9S_MB_2U(SCH_1):PAGE162_I54@PURE_QUANTA.Q_CAP(CHIPS)':
 'A': CDS_PINID='A';
NET_NAME
'USB3_PCH_RX_BUF_C_DP<4>'
 '@S9S_MB_2U_LIB.S9S_MB_2U(SCH_1):USB3_PCH_RX_BUF_C_DP'<4>:
 C_SIGNAL='@s9s_mb_2u_lib.s9s_mb_2u(sch_1):usb3_pch_rx_buf_c_dp(4)';
NODE_NAME     U309 12
 '@S9S_MB_2U_LIB.S9S_MB_2U(SCH_1):PAGE162_I43@PURE_QUANTA.PI3EQX1002EZREX(CHIPS)':
 'BOP': CDS_PINID='BOP';
NODE_NAME     C2291 1
 '@S9S_MB_2U_LIB.S9S_MB_2U(SCH_1):PAGE162_I55@PURE_QUANTA.Q_CAP(CHIPS)':
 'A': CDS_PINID='A';
NET_NAME
'USB3_PCH_RX_BUF_DN<4>'
 '@S9S_MB_2U_LIB.S9S_MB_2U(SCH_1):USB3_PCH_RX_BUF_DN'<4>:
 C_SIGNAL='@s9s_mb_2u_lib.s9s_mb_2u(sch_1):usb3_pch_rx_buf_dn(4)';
NODE_NAME     C2292 2
 '@S9S_MB_2U_LIB.S9S_MB_2U(SCH_1):PAGE162_I54@PURE_QUANTA.Q_CAP(CHIPS)':
 'B': CDS_PINID='B';
NODE_NAME     U4 R40
 '@S9S_MB_2U_LIB.S9S_MB_2U(SCH_1):PAGE173_I110@PURE_QUANTA.EMMITSBURG_REV0P9(CHIPS)':
 'SATA_9_PCIE3_9_USB3_9_RXN': CDS_PINID='SATA_9_PCIE3_9_USB3_9_RXN';
NET_NAME
'USB3_PCH_RX_BUF_DP<4>'
 '@S9S_MB_2U_LIB.S9S_MB_2U(SCH_1):USB3_PCH_RX_BUF_DP'<4>:
 C_SIGNAL='@s9s_mb_2u_lib.s9s_mb_2u(sch_1):usb3_pch_rx_buf_dp(4)';
NODE_NAME     C2291 2
 '@S9S_MB_2U_LIB.S9S_MB_2U(SCH_1):PAGE162_I55@PURE_QUANTA.Q_CAP(CHIPS)':
 'B': CDS_PINID='B';
NODE_NAME     U4 R42
 '@S9S_MB_2U_LIB.S9S_MB_2U(SCH_1):PAGE173_I110@PURE_QUANTA.EMMITSBURG_REV0P9(CHIPS)':
 'SATA_9_PCIE3_9_USB3_9_RXP': CDS_PINID='SATA_9_PCIE3_9_USB3_9_RXP';
NET_NAME
'USB3_PCH_RX_C_DN<4>'
 '@S9S_MB_2U_LIB.S9S_MB_2U(SCH_1):USB3_PCH_RX_C_DN'<4>:
 C_SIGNAL='@s9s_mb_2u_lib.s9s_mb_2u(sch_1):usb3_pch_rx_c_dn(4)';
NODE_NAME     C2350 2
 '@S9S_MB_2U_LIB.S9S_MB_2U(SCH_1):PAGE162_I25@PURE_QUANTA.Q_CAP_DIFFBUS(CHIPS)':
 '2': CDS_PINID='\2\';
NODE_NAME     U309 19
 '@S9S_MB_2U_LIB.S9S_MB_2U(SCH_1):PAGE162_I43@PURE_QUANTA.PI3EQX1002EZREX(CHIPS)':
 'BIN': CDS_PINID='BIN';
NET_NAME
'USB3_PCH_RX_C_DP<4>'
 '@S9S_MB_2U_LIB.S9S_MB_2U(SCH_1):USB3_PCH_RX_C_DP'<4>:
 C_SIGNAL='@s9s_mb_2u_lib.s9s_mb_2u(sch_1):usb3_pch_rx_c_dp(4)';
NODE_NAME     C2349 2
 '@S9S_MB_2U_LIB.S9S_MB_2U(SCH_1):PAGE162_I26@PURE_QUANTA.Q_CAP_DIFFBUS(CHIPS)':
 '2': CDS_PINID='\2\';
NODE_NAME     U309 18
 '@S9S_MB_2U_LIB.S9S_MB_2U(SCH_1):PAGE162_I43@PURE_QUANTA.PI3EQX1002EZREX(CHIPS)':
 'BIP': CDS_PINID='BIP';
NET_NAME
'USB3_PCH_RX_DN<4>'
 '@S9S_MB_2U_LIB.S9S_MB_2U(SCH_1):USB3_PCH_RX_DN'<4>:
 C_SIGNAL='@s9s_mb_2u_lib.s9s_mb_2u(sch_1):usb3_pch_rx_dn(4)';
NODE_NAME     R4637 1
 '@S9S_MB_2U_LIB.S9S_MB_2U(SCH_1):PAGE162_I24@PURE_QUANTA.Q_RES(CHIPS)':
 'A': CDS_PINID='A';
NODE_NAME     C2350 1
 '@S9S_MB_2U_LIB.S9S_MB_2U(SCH_1):PAGE162_I25@PURE_QUANTA.Q_CAP_DIFFBUS(CHIPS)':
 '1': CDS_PINID='\1\';
NODE_NAME     J41 A60
 '@S9S_MB_2U_LIB.S9S_MB_2U(SCH_1):PAGE227_I173@PURE_QUANTA.SCONN168_ME1016810202011(CHIPS)':
 'PERP13': CDS_PINID='PERP13';
NET_NAME
'USB3_PCH_RX_DP<4>'
 '@S9S_MB_2U_LIB.S9S_MB_2U(SCH_1):USB3_PCH_RX_DP'<4>:
 C_SIGNAL='@s9s_mb_2u_lib.s9s_mb_2u(sch_1):usb3_pch_rx_dp(4)';
NODE_NAME     R4636 1
 '@S9S_MB_2U_LIB.S9S_MB_2U(SCH_1):PAGE162_I23@PURE_QUANTA.Q_RES(CHIPS)':
 'A': CDS_PINID='A';
NODE_NAME     C2349 1
 '@S9S_MB_2U_LIB.S9S_MB_2U(SCH_1):PAGE162_I26@PURE_QUANTA.Q_CAP_DIFFBUS(CHIPS)':
 '1': CDS_PINID='\1\';
NODE_NAME     J41 A59
 '@S9S_MB_2U_LIB.S9S_MB_2U(SCH_1):PAGE227_I173@PURE_QUANTA.SCONN168_ME1016810202011(CHIPS)':
 'PERN13': CDS_PINID='PERN13';
NET_NAME
'USB3_PCH_TX_BUF_C_DN<4>'
 '@S9S_MB_2U_LIB.S9S_MB_2U(SCH_1):USB3_PCH_TX_BUF_C_DN'<4>:
 C_SIGNAL='@s9s_mb_2u_lib.s9s_mb_2u(sch_1):usb3_pch_tx_buf_c_dn(4)';
NODE_NAME     C2290 2
 '@S9S_MB_2U_LIB.S9S_MB_2U(SCH_1):PAGE162_I56@PURE_QUANTA.Q_CAP(CHIPS)':
 'B': CDS_PINID='B';
NODE_NAME     J41 B60
 '@S9S_MB_2U_LIB.S9S_MB_2U(SCH_1):PAGE227_I173@PURE_QUANTA.SCONN168_ME1016810202011(CHIPS)':
 'PETP13': CDS_PINID='PETP13';
NET_NAME
'USB3_PCH_TX_BUF_C_DP<4>'
 '@S9S_MB_2U_LIB.S9S_MB_2U(SCH_1):USB3_PCH_TX_BUF_C_DP'<4>:
 C_SIGNAL='@s9s_mb_2u_lib.s9s_mb_2u(sch_1):usb3_pch_tx_buf_c_dp(4)';
NODE_NAME     C2289 2
 '@S9S_MB_2U_LIB.S9S_MB_2U(SCH_1):PAGE162_I57@PURE_QUANTA.Q_CAP(CHIPS)':
 'B': CDS_PINID='B';
NODE_NAME     J41 B59
 '@S9S_MB_2U_LIB.S9S_MB_2U(SCH_1):PAGE227_I173@PURE_QUANTA.SCONN168_ME1016810202011(CHIPS)':
 'PETN13': CDS_PINID='PETN13';
NET_NAME
'USB3_PCH_TX_BUF_DN<4>'
 '@S9S_MB_2U_LIB.S9S_MB_2U(SCH_1):USB3_PCH_TX_BUF_DN'<4>:
 C_SIGNAL='@s9s_mb_2u_lib.s9s_mb_2u(sch_1):usb3_pch_tx_buf_dn(4)';
NODE_NAME     U309 23
 '@S9S_MB_2U_LIB.S9S_MB_2U(SCH_1):PAGE162_I43@PURE_QUANTA.PI3EQX1002EZREX(CHIPS)':
 'AON': CDS_PINID='AON';
NODE_NAME     C2290 1
 '@S9S_MB_2U_LIB.S9S_MB_2U(SCH_1):PAGE162_I56@PURE_QUANTA.Q_CAP(CHIPS)':
 'A': CDS_PINID='A';
NET_NAME
'USB3_PCH_TX_BUF_DP<4>'
 '@S9S_MB_2U_LIB.S9S_MB_2U(SCH_1):USB3_PCH_TX_BUF_DP'<4>:
 C_SIGNAL='@s9s_mb_2u_lib.s9s_mb_2u(sch_1):usb3_pch_tx_buf_dp(4)';
NODE_NAME     U309 24
 '@S9S_MB_2U_LIB.S9S_MB_2U(SCH_1):PAGE162_I43@PURE_QUANTA.PI3EQX1002EZREX(CHIPS)':
 'AOP': CDS_PINID='AOP';
NODE_NAME     C2289 1
 '@S9S_MB_2U_LIB.S9S_MB_2U(SCH_1):PAGE162_I57@PURE_QUANTA.Q_CAP(CHIPS)':
 'A': CDS_PINID='A';
NET_NAME
'USB3_PCH_TX_C_DN<4>'
 '@S9S_MB_2U_LIB.S9S_MB_2U(SCH_1):USB3_PCH_TX_C_DN'<4>:
 C_SIGNAL='@s9s_mb_2u_lib.s9s_mb_2u(sch_1):usb3_pch_tx_c_dn(4)';
NODE_NAME     U309 7
 '@S9S_MB_2U_LIB.S9S_MB_2U(SCH_1):PAGE162_I43@PURE_QUANTA.PI3EQX1002EZREX(CHIPS)':
 'AIN': CDS_PINID='AIN';
NODE_NAME     C1097 2
 '@S9S_MB_2U_LIB.S9S_MB_2U(SCH_1):PAGE173_I78@PURE_QUANTA.Q_CAP(CHIPS)':
 'B': CDS_PINID='B';
NET_NAME
'USB3_PCH_TX_C_DP<4>'
 '@S9S_MB_2U_LIB.S9S_MB_2U(SCH_1):USB3_PCH_TX_C_DP'<4>:
 C_SIGNAL='@s9s_mb_2u_lib.s9s_mb_2u(sch_1):usb3_pch_tx_c_dp(4)';
NODE_NAME     U309 6
 '@S9S_MB_2U_LIB.S9S_MB_2U(SCH_1):PAGE162_I43@PURE_QUANTA.PI3EQX1002EZREX(CHIPS)':
 'AIP': CDS_PINID='AIP';
NODE_NAME     C1096 2
 '@S9S_MB_2U_LIB.S9S_MB_2U(SCH_1):PAGE173_I80@PURE_QUANTA.Q_CAP(CHIPS)':
 'B': CDS_PINID='B';
NET_NAME
'USB3_PCH_TX_DN<4>'
 '@S9S_MB_2U_LIB.S9S_MB_2U(SCH_1):USB3_PCH_TX_DN'<4>:
 C_SIGNAL='@s9s_mb_2u_lib.s9s_mb_2u(sch_1):usb3_pch_tx_dn(4)';
NODE_NAME     C1097 1
 '@S9S_MB_2U_LIB.S9S_MB_2U(SCH_1):PAGE173_I78@PURE_QUANTA.Q_CAP(CHIPS)':
 'A': CDS_PINID='A';
NODE_NAME     U4 AE32
 '@S9S_MB_2U_LIB.S9S_MB_2U(SCH_1):PAGE173_I110@PURE_QUANTA.EMMITSBURG_REV0P9(CHIPS)':
 'SATA_9_PCIE3_9_USB3_9_TXN': CDS_PINID='SATA_9_PCIE3_9_USB3_9_TXN';
NET_NAME
'USB3_PCH_TX_DP<4>'
 '@S9S_MB_2U_LIB.S9S_MB_2U(SCH_1):USB3_PCH_TX_DP'<4>:
 C_SIGNAL='@s9s_mb_2u_lib.s9s_mb_2u(sch_1):usb3_pch_tx_dp(4)';
NODE_NAME     C1096 1
 '@S9S_MB_2U_LIB.S9S_MB_2U(SCH_1):PAGE173_I80@PURE_QUANTA.Q_CAP(CHIPS)':
 'A': CDS_PINID='A';
NODE_NAME     U4 AG32
 '@S9S_MB_2U_LIB.S9S_MB_2U(SCH_1):PAGE173_I110@PURE_QUANTA.EMMITSBURG_REV0P9(CHIPS)':
 'SATA_9_PCIE3_9_USB3_9_TXP': CDS_PINID='SATA_9_PCIE3_9_USB3_9_TXP';
NET_NAME
'USB_HUB_2_DVDD'
 '@S9S_MB_2U_LIB.S9S_MB_2U(SCH_1):USB_HUB_2_DVDD':
 C_SIGNAL='@s9s_mb_2u_lib.s9s_mb_2u(sch_1):usb_hub_2_dvdd';
NODE_NAME     U313 21
 '@S9S_MB_2U_LIB.S9S_MB_2U(SCH_1):PAGE194_I40@PURE_QUANTA.GL852GOHY60(CHIPS)':
 'DVDD': CDS_PINID='DVDD';
NODE_NAME     R4462 2
 '@S9S_MB_2U_LIB.S9S_MB_2U(SCH_1):PAGE194_I50@PURE_QUANTA.Q_RES(CHIPS)':
 'B': CDS_PINID='B';
NET_NAME
'USB_HUB_2_OVCUR1'
 '@S9S_MB_2U_LIB.S9S_MB_2U(SCH_1):USB_HUB_2_OVCUR1':
 C_SIGNAL='@s9s_mb_2u_lib.s9s_mb_2u(sch_1):usb_hub_2_ovcur1';
NODE_NAME     R4456 2
 '@S9S_MB_2U_LIB.S9S_MB_2U(SCH_1):PAGE194_I25@PURE_QUANTA.Q_RES(CHIPS)':
 'B': CDS_PINID='B';
NODE_NAME     U313 25
 '@S9S_MB_2U_LIB.S9S_MB_2U(SCH_1):PAGE194_I40@PURE_QUANTA.GL852GOHY60(CHIPS)':
 'OVCUR1#||SMC': CDS_PINID='\ovcur1#||smc\';
NET_NAME
'USB_HUB_2_OVCUR2'
 '@S9S_MB_2U_LIB.S9S_MB_2U(SCH_1):USB_HUB_2_OVCUR2':
 C_SIGNAL='@s9s_mb_2u_lib.s9s_mb_2u(sch_1):usb_hub_2_ovcur2';
NODE_NAME     R4457 2
 '@S9S_MB_2U_LIB.S9S_MB_2U(SCH_1):PAGE194_I24@PURE_QUANTA.Q_RES(CHIPS)':
 'B': CDS_PINID='B';
NODE_NAME     U313 24
 '@S9S_MB_2U_LIB.S9S_MB_2U(SCH_1):PAGE194_I40@PURE_QUANTA.GL852GOHY60(CHIPS)':
 'OVCUR2#||SMD': CDS_PINID='\ovcur2#||smd\';
NET_NAME
'USB_HUB_2_OVCUR3'
 '@S9S_MB_2U_LIB.S9S_MB_2U(SCH_1):USB_HUB_2_OVCUR3':
 C_SIGNAL='@s9s_mb_2u_lib.s9s_mb_2u(sch_1):usb_hub_2_ovcur3';
NODE_NAME     R4458 2
 '@S9S_MB_2U_LIB.S9S_MB_2U(SCH_1):PAGE194_I23@PURE_QUANTA.Q_RES(CHIPS)':
 'B': CDS_PINID='B';
NODE_NAME     U313 20
 '@S9S_MB_2U_LIB.S9S_MB_2U(SCH_1):PAGE194_I40@PURE_QUANTA.GL852GOHY60(CHIPS)':
 'OVCUR3#': CDS_PINID='\ovcur3#\';
NET_NAME
'USB_HUB_2_OVCUR4'
 '@S9S_MB_2U_LIB.S9S_MB_2U(SCH_1):USB_HUB_2_OVCUR4':
 C_SIGNAL='@s9s_mb_2u_lib.s9s_mb_2u(sch_1):usb_hub_2_ovcur4';
NODE_NAME     R4459 2
 '@S9S_MB_2U_LIB.S9S_MB_2U(SCH_1):PAGE194_I22@PURE_QUANTA.Q_RES(CHIPS)':
 'B': CDS_PINID='B';
NODE_NAME     U313 19
 '@S9S_MB_2U_LIB.S9S_MB_2U(SCH_1):PAGE194_I40@PURE_QUANTA.GL852GOHY60(CHIPS)':
 'OVCUR4#': CDS_PINID='\ovcur4#\';
NET_NAME
'USB_HUB_2_PGANG'
 '@S9S_MB_2U_LIB.S9S_MB_2U(SCH_1):USB_HUB_2_PGANG':
 C_SIGNAL='@s9s_mb_2u_lib.s9s_mb_2u(sch_1):usb_hub_2_pgang';
NODE_NAME     R4464 1
 '@S9S_MB_2U_LIB.S9S_MB_2U(SCH_1):PAGE194_I38@PURE_QUANTA.Q_RES(CHIPS)':
 'A': CDS_PINID='A';
NODE_NAME     U313 23
 '@S9S_MB_2U_LIB.S9S_MB_2U(SCH_1):PAGE194_I40@PURE_QUANTA.GL852GOHY60(CHIPS)':
 'PGANG': CDS_PINID='PGANG';
NET_NAME
'USB_HUB_2_PSELF'
 '@S9S_MB_2U_LIB.S9S_MB_2U(SCH_1):USB_HUB_2_PSELF':
 C_SIGNAL='@s9s_mb_2u_lib.s9s_mb_2u(sch_1):usb_hub_2_pself';
NODE_NAME     R4449 1
 '@S9S_MB_2U_LIB.S9S_MB_2U(SCH_1):PAGE194_I8@PURE_QUANTA.Q_RES(CHIPS)':
 'A': CDS_PINID='A';
NODE_NAME     R4448 2
 '@S9S_MB_2U_LIB.S9S_MB_2U(SCH_1):PAGE194_I9@PURE_QUANTA.Q_RES(CHIPS)':
 'B': CDS_PINID='B';
NODE_NAME     U313 22
 '@S9S_MB_2U_LIB.S9S_MB_2U(SCH_1):PAGE194_I40@PURE_QUANTA.GL852GOHY60(CHIPS)':
 'PSELF': CDS_PINID='PSELF';
NET_NAME
'USB_HUB_2_RREF'
 '@S9S_MB_2U_LIB.S9S_MB_2U(SCH_1):USB_HUB_2_RREF':
 C_SIGNAL='@s9s_mb_2u_lib.s9s_mb_2u(sch_1):usb_hub_2_rref';
NODE_NAME     R4463 1
 '@S9S_MB_2U_LIB.S9S_MB_2U(SCH_1):PAGE194_I37@PURE_QUANTA.Q_RES(CHIPS)':
 'A': CDS_PINID='A';
NODE_NAME     U313 8
 '@S9S_MB_2U_LIB.S9S_MB_2U(SCH_1):PAGE194_I40@PURE_QUANTA.GL852GOHY60(CHIPS)':
 'RREF': CDS_PINID='RREF';
NET_NAME
'USB_HUB_2_TEST'
 '@S9S_MB_2U_LIB.S9S_MB_2U(SCH_1):USB_HUB_2_TEST':
 C_SIGNAL='@s9s_mb_2u_lib.s9s_mb_2u(sch_1):usb_hub_2_test';
NODE_NAME     U313 18
 '@S9S_MB_2U_LIB.S9S_MB_2U(SCH_1):PAGE194_I40@PURE_QUANTA.GL852GOHY60(CHIPS)':
 'TEST||SCL': CDS_PINID='\test||scl\';
NODE_NAME     R4466 1
 '@S9S_MB_2U_LIB.S9S_MB_2U(SCH_1):PAGE194_I75@PURE_QUANTA.Q_RES(CHIPS)':
 'A': CDS_PINID='A';
NET_NAME
'USB_HUB_2_XTAL_IN'
 '@S9S_MB_2U_LIB.S9S_MB_2U(SCH_1):USB_HUB_2_XTAL_IN':
 C_SIGNAL='@s9s_mb_2u_lib.s9s_mb_2u(sch_1):usb_hub_2_xtal_in';
NODE_NAME     U313 10
 '@S9S_MB_2U_LIB.S9S_MB_2U(SCH_1):PAGE194_I40@PURE_QUANTA.GL852GOHY60(CHIPS)':
 'X1': CDS_PINID='X1';
NODE_NAME     C2326 1
 '@S9S_MB_2U_LIB.S9S_MB_2U(SCH_1):PAGE194_I81@PURE_QUANTA.Q_CAP(CHIPS)':
 'A': CDS_PINID='A';
NODE_NAME     Y9 1
 '@S9S_MB_2U_LIB.S9S_MB_2U(SCH_1):PAGE194_I83@PURE_QUANTA.Q_XTAL_4P_13BI_24GND(CHIPS)':
 'X1': CDS_PINID='X1';
NET_NAME
'USB_HUB_2_XTAL_OUT'
 '@S9S_MB_2U_LIB.S9S_MB_2U(SCH_1):USB_HUB_2_XTAL_OUT':
 C_SIGNAL='@s9s_mb_2u_lib.s9s_mb_2u(sch_1):usb_hub_2_xtal_out';
NODE_NAME     U313 11
 '@S9S_MB_2U_LIB.S9S_MB_2U(SCH_1):PAGE194_I40@PURE_QUANTA.GL852GOHY60(CHIPS)':
 'X2': CDS_PINID='X2';
NODE_NAME     Y9 3
 '@S9S_MB_2U_LIB.S9S_MB_2U(SCH_1):PAGE194_I83@PURE_QUANTA.Q_XTAL_4P_13BI_24GND(CHIPS)':
 'X2': CDS_PINID='X2';
NODE_NAME     C2327 1
 '@S9S_MB_2U_LIB.S9S_MB_2U(SCH_1):PAGE194_I85@PURE_QUANTA.Q_CAP(CHIPS)':
 'A': CDS_PINID='A';
NET_NAME
'USB_HUB_DVDD'
 '@S9S_MB_2U_LIB.S9S_MB_2U(SCH_1):USB_HUB_DVDD':
 C_SIGNAL='@s9s_mb_2u_lib.s9s_mb_2u(sch_1):usb_hub_dvdd';
NODE_NAME     U268 21
 '@S9S_MB_2U_LIB.S9S_MB_2U(SCH_1):PAGE155_I100@PURE_QUANTA.GL852GOHY60(CHIPS)':
 'DVDD': CDS_PINID='DVDD';
NODE_NAME     R3662 2
 '@S9S_MB_2U_LIB.S9S_MB_2U(SCH_1):PAGE155_I167@PURE_QUANTA.Q_RES(CHIPS)':
 'B': CDS_PINID='B';
NET_NAME
'USB_HUB_OVCUR1'
 '@S9S_MB_2U_LIB.S9S_MB_2U(SCH_1):USB_HUB_OVCUR1':
 C_SIGNAL='@s9s_mb_2u_lib.s9s_mb_2u(sch_1):usb_hub_ovcur1';
NODE_NAME     U268 25
 '@S9S_MB_2U_LIB.S9S_MB_2U(SCH_1):PAGE155_I100@PURE_QUANTA.GL852GOHY60(CHIPS)':
 'OVCUR1#||SMC': CDS_PINID='\ovcur1#||smc\';
NODE_NAME     R3656 2
 '@S9S_MB_2U_LIB.S9S_MB_2U(SCH_1):PAGE155_I194@PURE_QUANTA.Q_RES(CHIPS)':
 'B': CDS_PINID='B';
NET_NAME
'USB_HUB_OVCUR2'
 '@S9S_MB_2U_LIB.S9S_MB_2U(SCH_1):USB_HUB_OVCUR2':
 C_SIGNAL='@s9s_mb_2u_lib.s9s_mb_2u(sch_1):usb_hub_ovcur2';
NODE_NAME     U268 24
 '@S9S_MB_2U_LIB.S9S_MB_2U(SCH_1):PAGE155_I100@PURE_QUANTA.GL852GOHY60(CHIPS)':
 'OVCUR2#||SMD': CDS_PINID='\ovcur2#||smd\';
NODE_NAME     R3657 2
 '@S9S_MB_2U_LIB.S9S_MB_2U(SCH_1):PAGE155_I195@PURE_QUANTA.Q_RES(CHIPS)':
 'B': CDS_PINID='B';
NET_NAME
'USB_HUB_OVCUR3'
 '@S9S_MB_2U_LIB.S9S_MB_2U(SCH_1):USB_HUB_OVCUR3':
 C_SIGNAL='@s9s_mb_2u_lib.s9s_mb_2u(sch_1):usb_hub_ovcur3';
NODE_NAME     U268 20
 '@S9S_MB_2U_LIB.S9S_MB_2U(SCH_1):PAGE155_I100@PURE_QUANTA.GL852GOHY60(CHIPS)':
 'OVCUR3#': CDS_PINID='\ovcur3#\';
NODE_NAME     R3658 2
 '@S9S_MB_2U_LIB.S9S_MB_2U(SCH_1):PAGE155_I196@PURE_QUANTA.Q_RES(CHIPS)':
 'B': CDS_PINID='B';
NET_NAME
'USB_HUB_OVCUR4'
 '@S9S_MB_2U_LIB.S9S_MB_2U(SCH_1):USB_HUB_OVCUR4':
 C_SIGNAL='@s9s_mb_2u_lib.s9s_mb_2u(sch_1):usb_hub_ovcur4';
NODE_NAME     U268 19
 '@S9S_MB_2U_LIB.S9S_MB_2U(SCH_1):PAGE155_I100@PURE_QUANTA.GL852GOHY60(CHIPS)':
 'OVCUR4#': CDS_PINID='\ovcur4#\';
NODE_NAME     R3659 2
 '@S9S_MB_2U_LIB.S9S_MB_2U(SCH_1):PAGE155_I198@PURE_QUANTA.Q_RES(CHIPS)':
 'B': CDS_PINID='B';
NET_NAME
'USB_HUB_PGANG'
 '@S9S_MB_2U_LIB.S9S_MB_2U(SCH_1):USB_HUB_PGANG':
 C_SIGNAL='@s9s_mb_2u_lib.s9s_mb_2u(sch_1):usb_hub_pgang';
NODE_NAME     U268 23
 '@S9S_MB_2U_LIB.S9S_MB_2U(SCH_1):PAGE155_I100@PURE_QUANTA.GL852GOHY60(CHIPS)':
 'PGANG': CDS_PINID='PGANG';
NODE_NAME     R3665 1
 '@S9S_MB_2U_LIB.S9S_MB_2U(SCH_1):PAGE155_I182@PURE_QUANTA.Q_RES(CHIPS)':
 'A': CDS_PINID='A';
NET_NAME
'USB_HUB_PSELF'
 '@S9S_MB_2U_LIB.S9S_MB_2U(SCH_1):USB_HUB_PSELF':
 C_SIGNAL='@s9s_mb_2u_lib.s9s_mb_2u(sch_1):usb_hub_pself';
NODE_NAME     U268 22
 '@S9S_MB_2U_LIB.S9S_MB_2U(SCH_1):PAGE155_I100@PURE_QUANTA.GL852GOHY60(CHIPS)':
 'PSELF': CDS_PINID='PSELF';
NODE_NAME     R3663 2
 '@S9S_MB_2U_LIB.S9S_MB_2U(SCH_1):PAGE155_I186@PURE_QUANTA.Q_RES(CHIPS)':
 'B': CDS_PINID='B';
NODE_NAME     R3664 1
 '@S9S_MB_2U_LIB.S9S_MB_2U(SCH_1):PAGE155_I187@PURE_QUANTA.Q_RES(CHIPS)':
 'A': CDS_PINID='A';
NET_NAME
'USB_HUB_RREF'
 '@S9S_MB_2U_LIB.S9S_MB_2U(SCH_1):USB_HUB_RREF':
 C_SIGNAL='@s9s_mb_2u_lib.s9s_mb_2u(sch_1):usb_hub_rref';
NODE_NAME     U268 8
 '@S9S_MB_2U_LIB.S9S_MB_2U(SCH_1):PAGE155_I100@PURE_QUANTA.GL852GOHY60(CHIPS)':
 'RREF': CDS_PINID='RREF';
NODE_NAME     R3653 1
 '@S9S_MB_2U_LIB.S9S_MB_2U(SCH_1):PAGE155_I139@PURE_QUANTA.Q_RES(CHIPS)':
 'A': CDS_PINID='A';
NET_NAME
'USB_HUB_TEST'
 '@S9S_MB_2U_LIB.S9S_MB_2U(SCH_1):USB_HUB_TEST':
 C_SIGNAL='@s9s_mb_2u_lib.s9s_mb_2u(sch_1):usb_hub_test';
NODE_NAME     U268 18
 '@S9S_MB_2U_LIB.S9S_MB_2U(SCH_1):PAGE155_I100@PURE_QUANTA.GL852GOHY60(CHIPS)':
 'TEST||SCL': CDS_PINID='\test||scl\';
NODE_NAME     R3666 1
 '@S9S_MB_2U_LIB.S9S_MB_2U(SCH_1):PAGE155_I199@PURE_QUANTA.Q_RES(CHIPS)':
 'A': CDS_PINID='A';
NET_NAME
'USB_HUB_XTAL_IN'
 '@S9S_MB_2U_LIB.S9S_MB_2U(SCH_1):USB_HUB_XTAL_IN':
 C_SIGNAL='@s9s_mb_2u_lib.s9s_mb_2u(sch_1):usb_hub_xtal_in';
NODE_NAME     U268 10
 '@S9S_MB_2U_LIB.S9S_MB_2U(SCH_1):PAGE155_I100@PURE_QUANTA.GL852GOHY60(CHIPS)':
 'X1': CDS_PINID='X1';
NODE_NAME     Y4 1
 '@S9S_MB_2U_LIB.S9S_MB_2U(SCH_1):PAGE155_I200@PURE_QUANTA.Q_XTAL_4P_13BI_24GND(CHIPS)':
 'X1': CDS_PINID='X1';
NODE_NAME     C2029 1
 '@S9S_MB_2U_LIB.S9S_MB_2U(SCH_1):PAGE155_I210@PURE_QUANTA.Q_CAP(CHIPS)':
 'A': CDS_PINID='A';
NET_NAME
'USB_HUB_XTAL_OUT'
 '@S9S_MB_2U_LIB.S9S_MB_2U(SCH_1):USB_HUB_XTAL_OUT':
 C_SIGNAL='@s9s_mb_2u_lib.s9s_mb_2u(sch_1):usb_hub_xtal_out';
NODE_NAME     U268 11
 '@S9S_MB_2U_LIB.S9S_MB_2U(SCH_1):PAGE155_I100@PURE_QUANTA.GL852GOHY60(CHIPS)':
 'X2': CDS_PINID='X2';
NODE_NAME     Y4 3
 '@S9S_MB_2U_LIB.S9S_MB_2U(SCH_1):PAGE155_I200@PURE_QUANTA.Q_XTAL_4P_13BI_24GND(CHIPS)':
 'X2': CDS_PINID='X2';
NODE_NAME     C2030 1
 '@S9S_MB_2U_LIB.S9S_MB_2U(SCH_1):PAGE155_I211@PURE_QUANTA.Q_CAP(CHIPS)':
 'A': CDS_PINID='A';
NET_NAME
'USB_OC1_REAR_N'
 '@S9S_MB_2U_LIB.S9S_MB_2U(SCH_1):USB_OC1_REAR_N':
 C_SIGNAL='@s9s_mb_2u_lib.s9s_mb_2u(sch_1):usb_oc1_rear_n';
NODE_NAME     R1827 2
 '@S9S_MB_2U_LIB.S9S_MB_2U(SCH_1):PAGE175_I193@PURE_QUANTA.Q_RES(CHIPS)':
 'B': CDS_PINID='B';
NODE_NAME     U249 W9
 '@S9S_MB_2U_LIB.S9S_MB_2U(SCH_1):PAGE312_I1@PURE_QUANTA.LCMXO3LF9400C5BG484C(CHIPS)':
 'PB18D': CDS_PINID='PB18D';
NET_NAME
'USB_OC1_REAR_R_N'
 '@S9S_MB_2U_LIB.S9S_MB_2U(SCH_1):USB_OC1_REAR_R_N':
 C_SIGNAL='@s9s_mb_2u_lib.s9s_mb_2u(sch_1):usb_oc1_rear_r_n';
NODE_NAME     U4 BG32
 '@S9S_MB_2U_LIB.S9S_MB_2U(SCH_1):PAGE175_I93@PURE_QUANTA.EMMITSBURG_REV0P9(CHIPS)':
 'GPPC_B_6_USB2_OCB_1': CDS_PINID='GPPC_B_6_USB2_OCB_1';
NODE_NAME     R1828 1
 '@S9S_MB_2U_LIB.S9S_MB_2U(SCH_1):PAGE175_I188@PURE_QUANTA.Q_RES(CHIPS)':
 'A': CDS_PINID='A';
NODE_NAME     R1827 1
 '@S9S_MB_2U_LIB.S9S_MB_2U(SCH_1):PAGE175_I193@PURE_QUANTA.Q_RES(CHIPS)':
 'A': CDS_PINID='A';
NET_NAME
'UV_ADR_P2V5_COMP'
 '@S9S_MB_2U_LIB.S9S_MB_2U(SCH_1):UV_ADR_P2V5_COMP':
 C_SIGNAL='@s9s_mb_2u_lib.s9s_mb_2u(sch_1):uv_adr_p2v5_comp';
NODE_NAME     C2379 1
 '@S9S_MB_2U_LIB.S9S_MB_2U(SCH_1):PAGE329_I1@PURE_QUANTA.Q_CAP(CHIPS)':
 'A': CDS_PINID='A';
NODE_NAME     U337 1
 '@S9S_MB_2U_LIB.S9S_MB_2U(SCH_1):PAGE329_I3@PURE_QUANTA.LM4040AIM3X25NOPB(CHIPS)':
 '1+': CDS_PINID='\1+\';
NODE_NAME     U339 1
 '@S9S_MB_2U_LIB.S9S_MB_2U(SCH_1):PAGE329_I12@PURE_QUANTA.AP331AWG7(CHIPS)':
 'IN-': CDS_PINID='\in-\';
NODE_NAME     R4772 2
 '@S9S_MB_2U_LIB.S9S_MB_2U(SCH_1):PAGE329_I21@PURE_QUANTA.Q_RES(CHIPS)':
 'B': CDS_PINID='B';
NET_NAME
'UV_P2V5_COMP'
 '@S9S_MB_2U_LIB.S9S_MB_2U(SCH_1):UV_P2V5_COMP':
 C_SIGNAL='@s9s_mb_2u_lib.s9s_mb_2u(sch_1):uv_p2v5_comp';
NODE_NAME     U340 1
 '@S9S_MB_2U_LIB.S9S_MB_2U(SCH_1):PAGE329_I23@PURE_QUANTA.AP331AWG7(CHIPS)':
 'IN-': CDS_PINID='\in-\';
NODE_NAME     C2380 1
 '@S9S_MB_2U_LIB.S9S_MB_2U(SCH_1):PAGE329_I35@PURE_QUANTA.Q_CAP(CHIPS)':
 'A': CDS_PINID='A';
NODE_NAME     R4773 2
 '@S9S_MB_2U_LIB.S9S_MB_2U(SCH_1):PAGE329_I42@PURE_QUANTA.Q_RES(CHIPS)':
 'B': CDS_PINID='B';
NODE_NAME     U338 1
 '@S9S_MB_2U_LIB.S9S_MB_2U(SCH_1):PAGE329_I43@PURE_QUANTA.LM4040AIM3X25NOPB(CHIPS)':
 '1+': CDS_PINID='\1+\';
NET_NAME
'VCC_PLD_CORE'
 '@S9S_MB_2U_LIB.S9S_MB_2U(SCH_1):VCC_PLD_CORE':
 C_SIGNAL='@s9s_mb_2u_lib.s9s_mb_2u(sch_1):vcc_pld_core',
 CDS_GLOBAL_NET='TRUE';
NODE_NAME     C1154 1
 '@S9S_MB_2U_LIB.S9S_MB_2U(SCH_1):PAGE202_I3@PURE_QUANTA.Q_CAP(CHIPS)':
 'A': CDS_PINID='A';
NODE_NAME     C1152 1
 '@S9S_MB_2U_LIB.S9S_MB_2U(SCH_1):PAGE202_I5@PURE_QUANTA.Q_CAP(CHIPS)':
 'A': CDS_PINID='A';
NODE_NAME     C1931 1
 '@S9S_MB_2U_LIB.S9S_MB_2U(SCH_1):PAGE202_I21@PURE_QUANTA.Q_CAP(CHIPS)':
 'A': CDS_PINID='A';
NODE_NAME     C1928 1
 '@S9S_MB_2U_LIB.S9S_MB_2U(SCH_1):PAGE202_I22@PURE_QUANTA.Q_CAP(CHIPS)':
 'A': CDS_PINID='A';
NODE_NAME     C1919 1
 '@S9S_MB_2U_LIB.S9S_MB_2U(SCH_1):PAGE202_I23@PURE_QUANTA.Q_CAP(CHIPS)':
 'A': CDS_PINID='A';
NODE_NAME     C1916 1
 '@S9S_MB_2U_LIB.S9S_MB_2U(SCH_1):PAGE202_I24@PURE_QUANTA.Q_CAP(CHIPS)':
 'A': CDS_PINID='A';
NODE_NAME     C1907 1
 '@S9S_MB_2U_LIB.S9S_MB_2U(SCH_1):PAGE202_I25@PURE_QUANTA.Q_CAP(CHIPS)':
 'A': CDS_PINID='A';
NODE_NAME     C1903 1
 '@S9S_MB_2U_LIB.S9S_MB_2U(SCH_1):PAGE202_I26@PURE_QUANTA.Q_CAP(CHIPS)':
 'A': CDS_PINID='A';
NODE_NAME     C1897 1
 '@S9S_MB_2U_LIB.S9S_MB_2U(SCH_1):PAGE202_I27@PURE_QUANTA.Q_CAP(CHIPS)':
 'A': CDS_PINID='A';
NODE_NAME     C1912 1
 '@S9S_MB_2U_LIB.S9S_MB_2U(SCH_1):PAGE202_I28@PURE_QUANTA.Q_CAP(CHIPS)':
 'A': CDS_PINID='A';
NODE_NAME     C1943 1
 '@S9S_MB_2U_LIB.S9S_MB_2U(SCH_1):PAGE202_I29@PURE_QUANTA.Q_CAP(CHIPS)':
 'A': CDS_PINID='A';
NODE_NAME     C1936 1
 '@S9S_MB_2U_LIB.S9S_MB_2U(SCH_1):PAGE202_I30@PURE_QUANTA.Q_CAP(CHIPS)':
 'A': CDS_PINID='A';
NODE_NAME     U249 K10
 '@S9S_MB_2U_LIB.S9S_MB_2U(SCH_1):PAGE202_I102@PURE_QUANTA.LCMXO3LF9400C5BG484C(CHIPS)':
 'VCC1': CDS_PINID='VCC1';
NODE_NAME     U249 K11
 '@S9S_MB_2U_LIB.S9S_MB_2U(SCH_1):PAGE202_I102@PURE_QUANTA.LCMXO3LF9400C5BG484C(CHIPS)':
 'VCC2': CDS_PINID='VCC2';
NODE_NAME     U249 K12
 '@S9S_MB_2U_LIB.S9S_MB_2U(SCH_1):PAGE202_I102@PURE_QUANTA.LCMXO3LF9400C5BG484C(CHIPS)':
 'VCC3': CDS_PINID='VCC3';
NODE_NAME     U249 K13
 '@S9S_MB_2U_LIB.S9S_MB_2U(SCH_1):PAGE202_I102@PURE_QUANTA.LCMXO3LF9400C5BG484C(CHIPS)':
 'VCC4': CDS_PINID='VCC4';
NODE_NAME     U249 L11
 '@S9S_MB_2U_LIB.S9S_MB_2U(SCH_1):PAGE202_I102@PURE_QUANTA.LCMXO3LF9400C5BG484C(CHIPS)':
 'VCC5': CDS_PINID='VCC5';
NODE_NAME     U249 L12
 '@S9S_MB_2U_LIB.S9S_MB_2U(SCH_1):PAGE202_I102@PURE_QUANTA.LCMXO3LF9400C5BG484C(CHIPS)':
 'VCC6': CDS_PINID='VCC6';
NODE_NAME     U249 M11
 '@S9S_MB_2U_LIB.S9S_MB_2U(SCH_1):PAGE202_I102@PURE_QUANTA.LCMXO3LF9400C5BG484C(CHIPS)':
 'VCC7': CDS_PINID='VCC7';
NODE_NAME     U249 M12
 '@S9S_MB_2U_LIB.S9S_MB_2U(SCH_1):PAGE202_I102@PURE_QUANTA.LCMXO3LF9400C5BG484C(CHIPS)':
 'VCC8': CDS_PINID='VCC8';
NODE_NAME     U249 N10
 '@S9S_MB_2U_LIB.S9S_MB_2U(SCH_1):PAGE202_I102@PURE_QUANTA.LCMXO3LF9400C5BG484C(CHIPS)':
 'VCC9': CDS_PINID='VCC9';
NODE_NAME     U249 N11
 '@S9S_MB_2U_LIB.S9S_MB_2U(SCH_1):PAGE202_I102@PURE_QUANTA.LCMXO3LF9400C5BG484C(CHIPS)':
 'VCC10': CDS_PINID='VCC10';
NODE_NAME     U249 N12
 '@S9S_MB_2U_LIB.S9S_MB_2U(SCH_1):PAGE202_I102@PURE_QUANTA.LCMXO3LF9400C5BG484C(CHIPS)':
 'VCC11': CDS_PINID='VCC11';
NODE_NAME     U249 N13
 '@S9S_MB_2U_LIB.S9S_MB_2U(SCH_1):PAGE202_I102@PURE_QUANTA.LCMXO3LF9400C5BG484C(CHIPS)':
 'VCC12': CDS_PINID='VCC12';
NODE_NAME     R3458 2
 '@S9S_MB_2U_LIB.S9S_MB_2U(SCH_1):PAGE202_I119@PURE_QUANTA.Q_RES(CHIPS)':
 'B': CDS_PINID='B';
NODE_NAME     C1934 1
 '@S9S_MB_2U_LIB.S9S_MB_2U(SCH_1):PAGE202_I120@PURE_QUANTA.Q_CAP(CHIPS)':
 'A': CDS_PINID='A';
NODE_NAME     C1150 1
 '@S9S_MB_2U_LIB.S9S_MB_2U(SCH_1):PAGE202_I121@PURE_QUANTA.Q_CAP(CHIPS)':
 'A': CDS_PINID='A';
NET_NAME
'VFG3P3_CLK_GEN'
 '@S9S_MB_2U_LIB.S9S_MB_2U(SCH_1):VFG3P3_CLK_GEN':
 C_SIGNAL='@s9s_mb_2u_lib.s9s_mb_2u(sch_1):vfg3p3_clk_gen',
 CDS_GLOBAL_NET='TRUE';
NODE_NAME     C1883 1
 '@S9S_MB_2U_LIB.S9S_MB_2U(SCH_1):PAGE201_I16@PURE_QUANTA.Q_CAP(CHIPS)':
 'A': CDS_PINID='A';
NODE_NAME     C1886 1
 '@S9S_MB_2U_LIB.S9S_MB_2U(SCH_1):PAGE201_I18@PURE_QUANTA.Q_CAP(CHIPS)':
 'A': CDS_PINID='A';
NODE_NAME     C1889 1
 '@S9S_MB_2U_LIB.S9S_MB_2U(SCH_1):PAGE201_I19@PURE_QUANTA.Q_CAP(CHIPS)':
 'A': CDS_PINID='A';
NODE_NAME     R4077 1
 '@S9S_MB_2U_LIB.S9S_MB_2U(SCH_1):PAGE201_I102@PURE_QUANTA.Q_RES(CHIPS)':
 'A': CDS_PINID='A';
NODE_NAME     C2257 1
 '@S9S_MB_2U_LIB.S9S_MB_2U(SCH_1):PAGE201_I104@PURE_QUANTA.Q_CAP(CHIPS)':
 'A': CDS_PINID='A';
NODE_NAME     C2258 1
 '@S9S_MB_2U_LIB.S9S_MB_2U(SCH_1):PAGE201_I105@PURE_QUANTA.Q_CAP(CHIPS)':
 'A': CDS_PINID='A';
NODE_NAME     L17 2
 '@S9S_MB_2U_LIB.S9S_MB_2U(SCH_1):PAGE201_I155@PURE_QUANTA.Q_INDUCTOR(CHIPS)':
 '2': CDS_PINID='\2\';
NODE_NAME     U247 11
 '@S9S_MB_2U_LIB.S9S_MB_2U(SCH_1):PAGE201_I167@PURE_QUANTA.9FGL0251DKILFT(CHIPS)':
 'VDD3.3_11': CDS_PINID='\vdd3.3_11\';
NODE_NAME     U247 20
 '@S9S_MB_2U_LIB.S9S_MB_2U(SCH_1):PAGE201_I167@PURE_QUANTA.9FGL0251DKILFT(CHIPS)':
 'VDD3.3_20': CDS_PINID='\vdd3.3_20\';
NODE_NAME     U247 7
 '@S9S_MB_2U_LIB.S9S_MB_2U(SCH_1):PAGE201_I167@PURE_QUANTA.9FGL0251DKILFT(CHIPS)':
 'VDDDIG3.3': CDS_PINID='\vdddig3.3\';
NODE_NAME     U247 3
 '@S9S_MB_2U_LIB.S9S_MB_2U(SCH_1):PAGE201_I167@PURE_QUANTA.9FGL0251DKILFT(CHIPS)':
 'VDDXTAL3.3': CDS_PINID='\vddxtal3.3\';
NET_NAME
'VFG_3P3A_CLK_GEN'
 '@S9S_MB_2U_LIB.S9S_MB_2U(SCH_1):VFG_3P3A_CLK_GEN':
 C_SIGNAL='@s9s_mb_2u_lib.s9s_mb_2u(sch_1):vfg_3p3a_clk_gen',
 CDS_GLOBAL_NET='TRUE';
NODE_NAME     R4077 2
 '@S9S_MB_2U_LIB.S9S_MB_2U(SCH_1):PAGE201_I102@PURE_QUANTA.Q_RES(CHIPS)':
 'B': CDS_PINID='B';
NODE_NAME     C1884 1
 '@S9S_MB_2U_LIB.S9S_MB_2U(SCH_1):PAGE201_I103@PURE_QUANTA.Q_CAP(CHIPS)':
 'A': CDS_PINID='A';
NODE_NAME     C2259 1
 '@S9S_MB_2U_LIB.S9S_MB_2U(SCH_1):PAGE201_I106@PURE_QUANTA.Q_CAP(CHIPS)':
 'A': CDS_PINID='A';
NODE_NAME     U247 16
 '@S9S_MB_2U_LIB.S9S_MB_2U(SCH_1):PAGE201_I167@PURE_QUANTA.9FGL0251DKILFT(CHIPS)':
 'VDDA3.3': CDS_PINID='\vdda3.3\';
NET_NAME
'VIRTUAL_RESEAT'
 '@S9S_MB_2U_LIB.S9S_MB_2U(SCH_1):VIRTUAL_RESEAT':
 C_SIGNAL='@s9s_mb_2u_lib.s9s_mb_2u(sch_1):virtual_reseat';
NODE_NAME     U249 AB16
 '@S9S_MB_2U_LIB.S9S_MB_2U(SCH_1):PAGE312_I1@PURE_QUANTA.LCMXO3LF9400C5BG484C(CHIPS)':
 'PB38A': CDS_PINID='PB38A';
NODE_NAME     J41 OA14
 '@S9S_MB_2U_LIB.S9S_MB_2U(SCH_1):PAGE227_I173@PURE_QUANTA.SCONN168_ME1016810202011(CHIPS)':
 'RBT_CLK_IN': CDS_PINID='RBT_CLK_IN';
NET_NAME
'VIRTUAL_RESEAT_FPGA_N'
 '@S9S_MB_2U_LIB.S9S_MB_2U(SCH_1):VIRTUAL_RESEAT_FPGA_N':
 C_SIGNAL='@s9s_mb_2u_lib.s9s_mb_2u(sch_1):virtual_reseat_fpga_n';
NODE_NAME     R3996 1
 '@S9S_MB_2U_LIB.S9S_MB_2U(SCH_1):PAGE229_I17@PURE_QUANTA.Q_RES(CHIPS)':
 'A': CDS_PINID='A';
NODE_NAME     R1853 2
 '@S9S_MB_2U_LIB.S9S_MB_2U(SCH_1):PAGE314_I138@PURE_QUANTA.Q_RES(CHIPS)':
 'B': CDS_PINID='B';
NET_NAME
'VIRTUAL_RESEAT_FPGA_R_N'
 '@S9S_MB_2U_LIB.S9S_MB_2U(SCH_1):VIRTUAL_RESEAT_FPGA_R_N':
 C_SIGNAL='@s9s_mb_2u_lib.s9s_mb_2u(sch_1):virtual_reseat_fpga_r_n';
NODE_NAME     R1853 1
 '@S9S_MB_2U_LIB.S9S_MB_2U(SCH_1):PAGE314_I138@PURE_QUANTA.Q_RES(CHIPS)':
 'A': CDS_PINID='A';
NODE_NAME     U249 D5
 '@S9S_MB_2U_LIB.S9S_MB_2U(SCH_1):PAGE314_I188@PURE_QUANTA.LCMXO3LF9400C5BG484C(CHIPS)':
 'PT12C': CDS_PINID='PT12C';
NET_NAME
'VR_P5V_EN'
 '@S9S_MB_2U_LIB.S9S_MB_2U(SCH_1):VR_P5V_EN':
 C_SIGNAL='@s9s_mb_2u_lib.s9s_mb_2u(sch_1):vr_p5v_en';
NODE_NAME     R1640 2
 '@S9S_MB_2U_LIB.S9S_MB_2U(SCH_1):PAGE246_I9@PURE_QUANTA.Q_RES(CHIPS)':
 'B': CDS_PINID='B';
NODE_NAME     R1607 2
 '@S9S_MB_2U_LIB.S9S_MB_2U(SCH_1):PAGE246_I10@PURE_QUANTA.Q_RES(CHIPS)':
 'B': CDS_PINID='B';
NODE_NAME     R1641 1
 '@S9S_MB_2U_LIB.S9S_MB_2U(SCH_1):PAGE246_I14@PURE_QUANTA.Q_RES(CHIPS)':
 'A': CDS_PINID='A';
NODE_NAME     Q37 2
 '@S9S_MB_2U_LIB.S9S_MB_2U(SCH_1):PAGE246_I69@PURE_QUANTA.MOSFET_NCH_DUAL(CHIPS)':
 'G1': CDS_PINID='G1';
NET_NAME
'VR_P5V_EN_D'
 '@S9S_MB_2U_LIB.S9S_MB_2U(SCH_1):VR_P5V_EN_D':
 C_SIGNAL='@s9s_mb_2u_lib.s9s_mb_2u(sch_1):vr_p5v_en_d';
NODE_NAME     U324 D
 '@S9S_MB_2U_LIB.S9S_MB_2U(SCH_1):PAGE246_I67@PURE_QUANTA.MOSFET_NCH_GDS_ESD_PROTECTED(CHIPS)':
 'D': CDS_PINID='D';
NODE_NAME     R4638 2
 '@S9S_MB_2U_LIB.S9S_MB_2U(SCH_1):PAGE246_I77@PURE_QUANTA.Q_RES(CHIPS)':
 'B': CDS_PINID='B';
NODE_NAME     R4639 2
 '@S9S_MB_2U_LIB.S9S_MB_2U(SCH_1):PAGE246_I78@PURE_QUANTA.Q_RES(CHIPS)':
 'B': CDS_PINID='B';
NODE_NAME     R4640 2
 '@S9S_MB_2U_LIB.S9S_MB_2U(SCH_1):PAGE246_I79@PURE_QUANTA.Q_RES(CHIPS)':
 'B': CDS_PINID='B';
NODE_NAME     R4641 2
 '@S9S_MB_2U_LIB.S9S_MB_2U(SCH_1):PAGE246_I80@PURE_QUANTA.Q_RES(CHIPS)':
 'B': CDS_PINID='B';
NET_NAME
'VR_P5V_EN_D_R'
 '@S9S_MB_2U_LIB.S9S_MB_2U(SCH_1):VR_P5V_EN_D_R':
 C_SIGNAL='@s9s_mb_2u_lib.s9s_mb_2u(sch_1):vr_p5v_en_d_r';
NODE_NAME     R1642 2
 '@S9S_MB_2U_LIB.S9S_MB_2U(SCH_1):PAGE246_I22@PURE_QUANTA.Q_RES(CHIPS)':
 'B': CDS_PINID='B';
NODE_NAME     R1654 1
 '@S9S_MB_2U_LIB.S9S_MB_2U(SCH_1):PAGE246_I27@PURE_QUANTA.Q_RES(CHIPS)':
 'A': CDS_PINID='A';
NODE_NAME     Q57 4
 '@S9S_MB_2U_LIB.S9S_MB_2U(SCH_1):PAGE246_I30@PURE_QUANTA.MOSFET_NCH_1D3S(CHIPS)':
 '4': CDS_PINID='\4\';
NODE_NAME     C1226 1
 '@S9S_MB_2U_LIB.S9S_MB_2U(SCH_1):PAGE246_I68@PURE_QUANTA.Q_CAP(CHIPS)':
 'A': CDS_PINID='A';
NET_NAME
'VR_P5V_EN_D_R1'
 '@S9S_MB_2U_LIB.S9S_MB_2U(SCH_1):VR_P5V_EN_D_R1':
 C_SIGNAL='@s9s_mb_2u_lib.s9s_mb_2u(sch_1):vr_p5v_en_d_r1';
NODE_NAME     R1654 2
 '@S9S_MB_2U_LIB.S9S_MB_2U(SCH_1):PAGE246_I27@PURE_QUANTA.Q_RES(CHIPS)':
 'B': CDS_PINID='B';
NODE_NAME     Q37 3
 '@S9S_MB_2U_LIB.S9S_MB_2U(SCH_1):PAGE246_I76@PURE_QUANTA.MOSFET_NCH_DUAL(CHIPS)':
 'D2': CDS_PINID='D2';
NET_NAME
'VR_P5V_EN_N'
 '@S9S_MB_2U_LIB.S9S_MB_2U(SCH_1):VR_P5V_EN_N':
 C_SIGNAL='@s9s_mb_2u_lib.s9s_mb_2u(sch_1):vr_p5v_en_n';
NODE_NAME     R1643 2
 '@S9S_MB_2U_LIB.S9S_MB_2U(SCH_1):PAGE246_I17@PURE_QUANTA.Q_RES(CHIPS)':
 'B': CDS_PINID='B';
NODE_NAME     U324 G
 '@S9S_MB_2U_LIB.S9S_MB_2U(SCH_1):PAGE246_I67@PURE_QUANTA.MOSFET_NCH_GDS_ESD_PROTECTED(CHIPS)':
 'G': CDS_PINID='G';
NODE_NAME     Q37 6
 '@S9S_MB_2U_LIB.S9S_MB_2U(SCH_1):PAGE246_I69@PURE_QUANTA.MOSFET_NCH_DUAL(CHIPS)':
 'D1': CDS_PINID='D1';
NODE_NAME     Q37 5
 '@S9S_MB_2U_LIB.S9S_MB_2U(SCH_1):PAGE246_I76@PURE_QUANTA.MOSFET_NCH_DUAL(CHIPS)':
 'G2': CDS_PINID='G2';
NET_NAME
'VSENSE_P12V_INA230_3_INN'
 '@S9S_MB_2U_LIB.S9S_MB_2U(SCH_1):VSENSE_P12V_INA230_3_INN':
 C_SIGNAL='@s9s_mb_2u_lib.s9s_mb_2u(sch_1):vsense_p12v_ina230_3_inn';
NODE_NAME     U263 12
 '@S9S_MB_2U_LIB.S9S_MB_2U(SCH_1):PAGE163_I94@PURE_QUANTA.INA230AIRGTR(CHIPS)':
 'IN-': CDS_PINID='\in-\';
NODE_NAME     C2020 2
 '@S9S_MB_2U_LIB.S9S_MB_2U(SCH_1):PAGE163_I108@PURE_QUANTA.Q_CAP(CHIPS)':
 'B': CDS_PINID='B';
NODE_NAME     R3571 2
 '@S9S_MB_2U_LIB.S9S_MB_2U(SCH_1):PAGE163_I110@PURE_QUANTA.Q_RES(CHIPS)':
 'B': CDS_PINID='B';
NET_NAME
'VSENSE_P12V_INA230_3_INP'
 '@S9S_MB_2U_LIB.S9S_MB_2U(SCH_1):VSENSE_P12V_INA230_3_INP':
 C_SIGNAL='@s9s_mb_2u_lib.s9s_mb_2u(sch_1):vsense_p12v_ina230_3_inp';
NODE_NAME     U263 13
 '@S9S_MB_2U_LIB.S9S_MB_2U(SCH_1):PAGE163_I94@PURE_QUANTA.INA230AIRGTR(CHIPS)':
 'IN+': CDS_PINID='\in+\';
NODE_NAME     C2020 1
 '@S9S_MB_2U_LIB.S9S_MB_2U(SCH_1):PAGE163_I108@PURE_QUANTA.Q_CAP(CHIPS)':
 'A': CDS_PINID='A';
NODE_NAME     R3570 2
 '@S9S_MB_2U_LIB.S9S_MB_2U(SCH_1):PAGE163_I109@PURE_QUANTA.Q_RES(CHIPS)':
 'B': CDS_PINID='B';
NET_NAME
'VSENSE_P12V_INA230_4_INN'
 '@S9S_MB_2U_LIB.S9S_MB_2U(SCH_1):VSENSE_P12V_INA230_4_INN':
 C_SIGNAL='@s9s_mb_2u_lib.s9s_mb_2u(sch_1):vsense_p12v_ina230_4_inn';
NODE_NAME     R3575 2
 '@S9S_MB_2U_LIB.S9S_MB_2U(SCH_1):PAGE163_I33@PURE_QUANTA.Q_RES(CHIPS)':
 'B': CDS_PINID='B';
NODE_NAME     U264 12
 '@S9S_MB_2U_LIB.S9S_MB_2U(SCH_1):PAGE163_I46@PURE_QUANTA.INA230AIRGTR(CHIPS)':
 'IN-': CDS_PINID='\in-\';
NODE_NAME     C2021 2
 '@S9S_MB_2U_LIB.S9S_MB_2U(SCH_1):PAGE163_I71@PURE_QUANTA.Q_CAP(CHIPS)':
 'B': CDS_PINID='B';
NET_NAME
'VSENSE_P12V_INA230_4_INP'
 '@S9S_MB_2U_LIB.S9S_MB_2U(SCH_1):VSENSE_P12V_INA230_4_INP':
 C_SIGNAL='@s9s_mb_2u_lib.s9s_mb_2u(sch_1):vsense_p12v_ina230_4_inp';
NODE_NAME     R3574 2
 '@S9S_MB_2U_LIB.S9S_MB_2U(SCH_1):PAGE163_I35@PURE_QUANTA.Q_RES(CHIPS)':
 'B': CDS_PINID='B';
NODE_NAME     U264 13
 '@S9S_MB_2U_LIB.S9S_MB_2U(SCH_1):PAGE163_I46@PURE_QUANTA.INA230AIRGTR(CHIPS)':
 'IN+': CDS_PINID='\in+\';
NODE_NAME     C2021 1
 '@S9S_MB_2U_LIB.S9S_MB_2U(SCH_1):PAGE163_I71@PURE_QUANTA.Q_CAP(CHIPS)':
 'A': CDS_PINID='A';
NET_NAME
'VSENSE_P12V_INA230_5_INN'
 '@S9S_MB_2U_LIB.S9S_MB_2U(SCH_1):VSENSE_P12V_INA230_5_INN':
 C_SIGNAL='@s9s_mb_2u_lib.s9s_mb_2u(sch_1):vsense_p12v_ina230_5_inn';
NODE_NAME     R3579 2
 '@S9S_MB_2U_LIB.S9S_MB_2U(SCH_1):PAGE163_I56@PURE_QUANTA.Q_RES(CHIPS)':
 'B': CDS_PINID='B';
NODE_NAME     U265 12
 '@S9S_MB_2U_LIB.S9S_MB_2U(SCH_1):PAGE163_I69@PURE_QUANTA.INA230AIRGTR(CHIPS)':
 'IN-': CDS_PINID='\in-\';
NODE_NAME     C2022 2
 '@S9S_MB_2U_LIB.S9S_MB_2U(SCH_1):PAGE163_I72@PURE_QUANTA.Q_CAP(CHIPS)':
 'B': CDS_PINID='B';
NET_NAME
'VSENSE_P12V_INA230_5_INP'
 '@S9S_MB_2U_LIB.S9S_MB_2U(SCH_1):VSENSE_P12V_INA230_5_INP':
 C_SIGNAL='@s9s_mb_2u_lib.s9s_mb_2u(sch_1):vsense_p12v_ina230_5_inp';
NODE_NAME     R3578 2
 '@S9S_MB_2U_LIB.S9S_MB_2U(SCH_1):PAGE163_I58@PURE_QUANTA.Q_RES(CHIPS)':
 'B': CDS_PINID='B';
NODE_NAME     U265 13
 '@S9S_MB_2U_LIB.S9S_MB_2U(SCH_1):PAGE163_I69@PURE_QUANTA.INA230AIRGTR(CHIPS)':
 'IN+': CDS_PINID='\in+\';
NODE_NAME     C2022 1
 '@S9S_MB_2U_LIB.S9S_MB_2U(SCH_1):PAGE163_I72@PURE_QUANTA.Q_CAP(CHIPS)':
 'A': CDS_PINID='A';
NET_NAME
'VSENSE_P3V3_INA230_1_INN'
 '@S9S_MB_2U_LIB.S9S_MB_2U(SCH_1):VSENSE_P3V3_INA230_1_INN':
 C_SIGNAL='@s9s_mb_2u_lib.s9s_mb_2u(sch_1):vsense_p3v3_ina230_1_inn';
NODE_NAME     U266 12
 '@S9S_MB_2U_LIB.S9S_MB_2U(SCH_1):PAGE295_I30@PURE_QUANTA.INA230AIRGTR(CHIPS)':
 'IN-': CDS_PINID='\in-\';
NODE_NAME     R3603 2
 '@S9S_MB_2U_LIB.S9S_MB_2U(SCH_1):PAGE295_I43@PURE_QUANTA.Q_RES(CHIPS)':
 'B': CDS_PINID='B';
NODE_NAME     C2027 2
 '@S9S_MB_2U_LIB.S9S_MB_2U(SCH_1):PAGE295_I77@PURE_QUANTA.Q_CAP(CHIPS)':
 'B': CDS_PINID='B';
NET_NAME
'VSENSE_P3V3_INA230_1_INP'
 '@S9S_MB_2U_LIB.S9S_MB_2U(SCH_1):VSENSE_P3V3_INA230_1_INP':
 C_SIGNAL='@s9s_mb_2u_lib.s9s_mb_2u(sch_1):vsense_p3v3_ina230_1_inp';
NODE_NAME     U266 13
 '@S9S_MB_2U_LIB.S9S_MB_2U(SCH_1):PAGE295_I30@PURE_QUANTA.INA230AIRGTR(CHIPS)':
 'IN+': CDS_PINID='\in+\';
NODE_NAME     R3602 2
 '@S9S_MB_2U_LIB.S9S_MB_2U(SCH_1):PAGE295_I41@PURE_QUANTA.Q_RES(CHIPS)':
 'B': CDS_PINID='B';
NODE_NAME     C2027 1
 '@S9S_MB_2U_LIB.S9S_MB_2U(SCH_1):PAGE295_I77@PURE_QUANTA.Q_CAP(CHIPS)':
 'A': CDS_PINID='A';
NET_NAME
'VSENSE_P3V3_INA230_2_INN'
 '@S9S_MB_2U_LIB.S9S_MB_2U(SCH_1):VSENSE_P3V3_INA230_2_INN':
 C_SIGNAL='@s9s_mb_2u_lib.s9s_mb_2u(sch_1):vsense_p3v3_ina230_2_inn';
NODE_NAME     U276 12
 '@S9S_MB_2U_LIB.S9S_MB_2U(SCH_1):PAGE295_I129@PURE_QUANTA.INA230AIRGTR(CHIPS)':
 'IN-': CDS_PINID='\in-\';
NODE_NAME     C2071 2
 '@S9S_MB_2U_LIB.S9S_MB_2U(SCH_1):PAGE295_I133@PURE_QUANTA.Q_CAP(CHIPS)':
 'B': CDS_PINID='B';
NODE_NAME     R3760 2
 '@S9S_MB_2U_LIB.S9S_MB_2U(SCH_1):PAGE295_I134@PURE_QUANTA.Q_RES(CHIPS)':
 'B': CDS_PINID='B';
NET_NAME
'VSENSE_P3V3_INA230_2_INP'
 '@S9S_MB_2U_LIB.S9S_MB_2U(SCH_1):VSENSE_P3V3_INA230_2_INP':
 C_SIGNAL='@s9s_mb_2u_lib.s9s_mb_2u(sch_1):vsense_p3v3_ina230_2_inp';
NODE_NAME     U276 13
 '@S9S_MB_2U_LIB.S9S_MB_2U(SCH_1):PAGE295_I129@PURE_QUANTA.INA230AIRGTR(CHIPS)':
 'IN+': CDS_PINID='\in+\';
NODE_NAME     R3758 2
 '@S9S_MB_2U_LIB.S9S_MB_2U(SCH_1):PAGE295_I132@PURE_QUANTA.Q_RES(CHIPS)':
 'B': CDS_PINID='B';
NODE_NAME     C2071 1
 '@S9S_MB_2U_LIB.S9S_MB_2U(SCH_1):PAGE295_I133@PURE_QUANTA.Q_CAP(CHIPS)':
 'A': CDS_PINID='A';
NET_NAME
'VSENSE_PVCCD_HV_CPU0_DN'
 '@S9S_MB_2U_LIB.S9S_MB_2U(SCH_1):VSENSE_PVCCD_HV_CPU0_DN':
 C_SIGNAL='@s9s_mb_2u_lib.s9s_mb_2u(sch_1):vsense_pvccd_hv_cpu0_dn';
NODE_NAME     U2 BN11
 '@S9S_MB_2U_LIB.S9S_MB_2U(SCH_1):PAGE16_I1@PURE_QUANTA.SOCKET4677_AZIF0045P001C01CS(CHIPS)':
 'VSS_VCCD_HV_SENSE': CDS_PINID='VSS_VCCD_HV_SENSE';
NODE_NAME     PU35 22
 '@S9S_MB_2U_LIB.S9S_MB_2U(SCH_1):PAGE264_I53@PURE_QUANTA.ISL69260IRAZT(CHIPS)':
 'RGND0': CDS_PINID='RGND0';
NODE_NAME     PR591 1
 '@S9S_MB_2U_LIB.S9S_MB_2U(SCH_1):PAGE264_I30@PURE_QUANTA.Q_RES(CHIPS)':
 'A': CDS_PINID='A';
NODE_NAME     PC627 2
 '@S9S_MB_2U_LIB.S9S_MB_2U(SCH_1):PAGE264_I37@PURE_QUANTA.Q_CAP(CHIPS)':
 'B': CDS_PINID='B';
NET_NAME
'VSENSE_PVCCD_HV_CPU0_DP'
 '@S9S_MB_2U_LIB.S9S_MB_2U(SCH_1):VSENSE_PVCCD_HV_CPU0_DP':
 C_SIGNAL='@s9s_mb_2u_lib.s9s_mb_2u(sch_1):vsense_pvccd_hv_cpu0_dp';
NODE_NAME     U2 BU11
 '@S9S_MB_2U_LIB.S9S_MB_2U(SCH_1):PAGE16_I1@PURE_QUANTA.SOCKET4677_AZIF0045P001C01CS(CHIPS)':
 'VCCD_HV_SENSE': CDS_PINID='VCCD_HV_SENSE';
NODE_NAME     PJ54 1
 '@S9S_MB_2U_LIB.S9S_MB_2U(SCH_1):PAGE264_I32@PURE_QUANTA.Q_SHORT(CHIPS)':
 '1': CDS_PINID='\1\';
NODE_NAME     PR592 1
 '@S9S_MB_2U_LIB.S9S_MB_2U(SCH_1):PAGE264_I31@PURE_QUANTA.Q_RES(CHIPS)':
 'A': CDS_PINID='A';
NET_NAME
'VSENSE_PVCCD_HV_CPU1_DN'
 '@S9S_MB_2U_LIB.S9S_MB_2U(SCH_1):VSENSE_PVCCD_HV_CPU1_DN':
 C_SIGNAL='@s9s_mb_2u_lib.s9s_mb_2u(sch_1):vsense_pvccd_hv_cpu1_dn';
NODE_NAME     U1 BN11
 '@S9S_MB_2U_LIB.S9S_MB_2U(SCH_1):PAGE47_I16@PURE_QUANTA.SOCKET4677_AZIF0045P001C01CS(CHIPS)':
 'VSS_VCCD_HV_SENSE': CDS_PINID='VSS_VCCD_HV_SENSE';
NODE_NAME     PU18 22
 '@S9S_MB_2U_LIB.S9S_MB_2U(SCH_1):PAGE282_I53@PURE_QUANTA.ISL69260IRAZT(CHIPS)':
 'RGND0': CDS_PINID='RGND0';
NODE_NAME     PR558 1
 '@S9S_MB_2U_LIB.S9S_MB_2U(SCH_1):PAGE282_I15@PURE_QUANTA.Q_RES(CHIPS)':
 'A': CDS_PINID='A';
NODE_NAME     PC389 2
 '@S9S_MB_2U_LIB.S9S_MB_2U(SCH_1):PAGE282_I22@PURE_QUANTA.Q_CAP(CHIPS)':
 'B': CDS_PINID='B';
NET_NAME
'VSENSE_PVCCD_HV_CPU1_DP'
 '@S9S_MB_2U_LIB.S9S_MB_2U(SCH_1):VSENSE_PVCCD_HV_CPU1_DP':
 C_SIGNAL='@s9s_mb_2u_lib.s9s_mb_2u(sch_1):vsense_pvccd_hv_cpu1_dp';
NODE_NAME     U1 BU11
 '@S9S_MB_2U_LIB.S9S_MB_2U(SCH_1):PAGE47_I16@PURE_QUANTA.SOCKET4677_AZIF0045P001C01CS(CHIPS)':
 'VCCD_HV_SENSE': CDS_PINID='VCCD_HV_SENSE';
NODE_NAME     PR559 1
 '@S9S_MB_2U_LIB.S9S_MB_2U(SCH_1):PAGE282_I36@PURE_QUANTA.Q_RES(CHIPS)':
 'A': CDS_PINID='A';
NODE_NAME     PJ48 1
 '@S9S_MB_2U_LIB.S9S_MB_2U(SCH_1):PAGE282_I16@PURE_QUANTA.Q_SHORT(CHIPS)':
 '1': CDS_PINID='\1\';
NET_NAME
'VSENSE_PVCCFA_EHV_CPU0_DN'
 '@S9S_MB_2U_LIB.S9S_MB_2U(SCH_1):VSENSE_PVCCFA_EHV_CPU0_DN':
 C_SIGNAL='@s9s_mb_2u_lib.s9s_mb_2u(sch_1):vsense_pvccfa_ehv_cpu0_dn';
NODE_NAME     U2 BA11
 '@S9S_MB_2U_LIB.S9S_MB_2U(SCH_1):PAGE16_I1@PURE_QUANTA.SOCKET4677_AZIF0045P001C01CS(CHIPS)':
 'VSS_VCCFA_EHV_SENSE': CDS_PINID='VSS_VCCFA_EHV_SENSE';
NODE_NAME     PU5 31
 '@S9S_MB_2U_LIB.S9S_MB_2U(SCH_1):PAGE260_I65@PURE_QUANTA.ISL69260IRAZT(CHIPS)':
 'RGND1': CDS_PINID='RGND1';
NODE_NAME     PC216 2
 '@S9S_MB_2U_LIB.S9S_MB_2U(SCH_1):PAGE260_I48@PURE_QUANTA.Q_CAP(CHIPS)':
 'B': CDS_PINID='B';
NODE_NAME     PR520 1
 '@S9S_MB_2U_LIB.S9S_MB_2U(SCH_1):PAGE260_I38@PURE_QUANTA.Q_RES(CHIPS)':
 'A': CDS_PINID='A';
NET_NAME
'VSENSE_PVCCFA_EHV_CPU0_DP'
 '@S9S_MB_2U_LIB.S9S_MB_2U(SCH_1):VSENSE_PVCCFA_EHV_CPU0_DP':
 C_SIGNAL='@s9s_mb_2u_lib.s9s_mb_2u(sch_1):vsense_pvccfa_ehv_cpu0_dp';
NODE_NAME     U2 AU11
 '@S9S_MB_2U_LIB.S9S_MB_2U(SCH_1):PAGE16_I1@PURE_QUANTA.SOCKET4677_AZIF0045P001C01CS(CHIPS)':
 'VCCFA_EHV_SENSE': CDS_PINID='VCCFA_EHV_SENSE';
NODE_NAME     PR522 1
 '@S9S_MB_2U_LIB.S9S_MB_2U(SCH_1):PAGE260_I40@PURE_QUANTA.Q_RES(CHIPS)':
 'A': CDS_PINID='A';
NODE_NAME     PJ46 1
 '@S9S_MB_2U_LIB.S9S_MB_2U(SCH_1):PAGE260_I39@PURE_QUANTA.Q_SHORT(CHIPS)':
 '1': CDS_PINID='\1\';
NET_NAME
'VSENSE_PVCCFA_EHV_CPU1_DN'
 '@S9S_MB_2U_LIB.S9S_MB_2U(SCH_1):VSENSE_PVCCFA_EHV_CPU1_DN':
 C_SIGNAL='@s9s_mb_2u_lib.s9s_mb_2u(sch_1):vsense_pvccfa_ehv_cpu1_dn';
NODE_NAME     U1 BA11
 '@S9S_MB_2U_LIB.S9S_MB_2U(SCH_1):PAGE47_I16@PURE_QUANTA.SOCKET4677_AZIF0045P001C01CS(CHIPS)':
 'VSS_VCCFA_EHV_SENSE': CDS_PINID='VSS_VCCFA_EHV_SENSE';
NODE_NAME     PC469 2
 '@S9S_MB_2U_LIB.S9S_MB_2U(SCH_1):PAGE278_I51@PURE_QUANTA.Q_CAP(CHIPS)':
 'B': CDS_PINID='B';
NODE_NAME     PU22 31
 '@S9S_MB_2U_LIB.S9S_MB_2U(SCH_1):PAGE278_I38@PURE_QUANTA.ISL69260IRAZT(CHIPS)':
 'RGND1': CDS_PINID='RGND1';
NODE_NAME     PR567 1
 '@S9S_MB_2U_LIB.S9S_MB_2U(SCH_1):PAGE278_I41@PURE_QUANTA.Q_RES(CHIPS)':
 'A': CDS_PINID='A';
NET_NAME
'VSENSE_PVCCFA_EHV_CPU1_DP'
 '@S9S_MB_2U_LIB.S9S_MB_2U(SCH_1):VSENSE_PVCCFA_EHV_CPU1_DP':
 C_SIGNAL='@s9s_mb_2u_lib.s9s_mb_2u(sch_1):vsense_pvccfa_ehv_cpu1_dp';
NODE_NAME     U1 AU11
 '@S9S_MB_2U_LIB.S9S_MB_2U(SCH_1):PAGE47_I16@PURE_QUANTA.SOCKET4677_AZIF0045P001C01CS(CHIPS)':
 'VCCFA_EHV_SENSE': CDS_PINID='VCCFA_EHV_SENSE';
NODE_NAME     PJ51 1
 '@S9S_MB_2U_LIB.S9S_MB_2U(SCH_1):PAGE278_I44@PURE_QUANTA.Q_SHORT(CHIPS)':
 '1': CDS_PINID='\1\';
NODE_NAME     PR569 1
 '@S9S_MB_2U_LIB.S9S_MB_2U(SCH_1):PAGE278_I45@PURE_QUANTA.Q_RES(CHIPS)':
 'A': CDS_PINID='A';
NET_NAME
'VSENSE_PVCCFA_EHV_FIVRA_CPU0_DN'
 '@S9S_MB_2U_LIB.S9S_MB_2U(SCH_1):VSENSE_PVCCFA_EHV_FIVRA_CPU0_DN':
 C_SIGNAL='@s9s_mb_2u_lib.s9s_mb_2u(sch_1):vsense_pvccfa_ehv_fivra_cpu0_dn';
NODE_NAME     U2 AT85
 '@S9S_MB_2U_LIB.S9S_MB_2U(SCH_1):PAGE16_I1@PURE_QUANTA.SOCKET4677_AZIF0045P001C01CS(CHIPS)':
 'VSS_VCCFA_EHV_FIVRA_SENSE': CDS_PINID='VSS_VCCFA_EHV_FIVRA_SENSE';
NODE_NAME     PR586 1
 '@S9S_MB_2U_LIB.S9S_MB_2U(SCH_1):PAGE252_I15@PURE_QUANTA.Q_RES(CHIPS)':
 'A': CDS_PINID='A';
NODE_NAME     PU14 39
 '@S9S_MB_2U_LIB.S9S_MB_2U(SCH_1):PAGE252_I63@PURE_QUANTA.RAA229126GNPHA0(CHIPS)':
 'RGND1': CDS_PINID='RGND1';
NODE_NAME     PC594 2
 '@S9S_MB_2U_LIB.S9S_MB_2U(SCH_1):PAGE252_I67@PURE_QUANTA.Q_CAP(CHIPS)':
 'B': CDS_PINID='B';
NET_NAME
'VSENSE_PVCCFA_EHV_FIVRA_CPU0_DP'
 '@S9S_MB_2U_LIB.S9S_MB_2U(SCH_1):VSENSE_PVCCFA_EHV_FIVRA_CPU0_DP':
 C_SIGNAL='@s9s_mb_2u_lib.s9s_mb_2u(sch_1):vsense_pvccfa_ehv_fivra_cpu0_dp';
NODE_NAME     U2 AY85
 '@S9S_MB_2U_LIB.S9S_MB_2U(SCH_1):PAGE16_I1@PURE_QUANTA.SOCKET4677_AZIF0045P001C01CS(CHIPS)':
 'VCCFA_EHV_FIVRA_SENSE': CDS_PINID='VCCFA_EHV_FIVRA_SENSE';
NODE_NAME     PJ53 1
 '@S9S_MB_2U_LIB.S9S_MB_2U(SCH_1):PAGE252_I24@PURE_QUANTA.Q_SHORT(CHIPS)':
 '1': CDS_PINID='\1\';
NODE_NAME     PR587 1
 '@S9S_MB_2U_LIB.S9S_MB_2U(SCH_1):PAGE252_I25@PURE_QUANTA.Q_RES(CHIPS)':
 'A': CDS_PINID='A';
NET_NAME
'VSENSE_PVCCFA_EHV_FIVRA_CPU1_DN'
 '@S9S_MB_2U_LIB.S9S_MB_2U(SCH_1):VSENSE_PVCCFA_EHV_FIVRA_CPU1_DN':
 C_SIGNAL='@s9s_mb_2u_lib.s9s_mb_2u(sch_1):vsense_pvccfa_ehv_fivra_cpu1_dn';
NODE_NAME     U1 AT85
 '@S9S_MB_2U_LIB.S9S_MB_2U(SCH_1):PAGE47_I16@PURE_QUANTA.SOCKET4677_AZIF0045P001C01CS(CHIPS)':
 'VSS_VCCFA_EHV_FIVRA_SENSE': CDS_PINID='VSS_VCCFA_EHV_FIVRA_SENSE';
NODE_NAME     PR560 1
 '@S9S_MB_2U_LIB.S9S_MB_2U(SCH_1):PAGE270_I12@PURE_QUANTA.Q_RES(CHIPS)':
 'A': CDS_PINID='A';
NODE_NAME     PC422 2
 '@S9S_MB_2U_LIB.S9S_MB_2U(SCH_1):PAGE270_I38@PURE_QUANTA.Q_CAP(CHIPS)':
 'B': CDS_PINID='B';
NODE_NAME     PU29 39
 '@S9S_MB_2U_LIB.S9S_MB_2U(SCH_1):PAGE270_I33@PURE_QUANTA.RAA229126GNPHA0(CHIPS)':
 'RGND1': CDS_PINID='RGND1';
NET_NAME
'VSENSE_PVCCFA_EHV_FIVRA_CPU1_DP'
 '@S9S_MB_2U_LIB.S9S_MB_2U(SCH_1):VSENSE_PVCCFA_EHV_FIVRA_CPU1_DP':
 C_SIGNAL='@s9s_mb_2u_lib.s9s_mb_2u(sch_1):vsense_pvccfa_ehv_fivra_cpu1_dp';
NODE_NAME     U1 AY85
 '@S9S_MB_2U_LIB.S9S_MB_2U(SCH_1):PAGE47_I16@PURE_QUANTA.SOCKET4677_AZIF0045P001C01CS(CHIPS)':
 'VCCFA_EHV_FIVRA_SENSE': CDS_PINID='VCCFA_EHV_FIVRA_SENSE';
NODE_NAME     PJ49 1
 '@S9S_MB_2U_LIB.S9S_MB_2U(SCH_1):PAGE270_I22@PURE_QUANTA.Q_SHORT(CHIPS)':
 '1': CDS_PINID='\1\';
NODE_NAME     PR561 1
 '@S9S_MB_2U_LIB.S9S_MB_2U(SCH_1):PAGE270_I23@PURE_QUANTA.Q_RES(CHIPS)':
 'A': CDS_PINID='A';
NET_NAME
'VSENSE_PVCCINFAON_CPU0_DN'
 '@S9S_MB_2U_LIB.S9S_MB_2U(SCH_1):VSENSE_PVCCINFAON_CPU0_DN':
 C_SIGNAL='@s9s_mb_2u_lib.s9s_mb_2u(sch_1):vsense_pvccinfaon_cpu0_dn';
NODE_NAME     U2 CE11
 '@S9S_MB_2U_LIB.S9S_MB_2U(SCH_1):PAGE16_I1@PURE_QUANTA.SOCKET4677_AZIF0045P001C01CS(CHIPS)':
 'VSS_VCCINFAON_SENSE': CDS_PINID='VSS_VCCINFAON_SENSE';
NODE_NAME     PU5 22
 '@S9S_MB_2U_LIB.S9S_MB_2U(SCH_1):PAGE260_I65@PURE_QUANTA.ISL69260IRAZT(CHIPS)':
 'RGND0': CDS_PINID='RGND0';
NODE_NAME     PC215 2
 '@S9S_MB_2U_LIB.S9S_MB_2U(SCH_1):PAGE260_I50@PURE_QUANTA.Q_CAP(CHIPS)':
 'B': CDS_PINID='B';
NODE_NAME     PR519 1
 '@S9S_MB_2U_LIB.S9S_MB_2U(SCH_1):PAGE260_I42@PURE_QUANTA.Q_RES(CHIPS)':
 'A': CDS_PINID='A';
NET_NAME
'VSENSE_PVCCINFAON_CPU0_DP'
 '@S9S_MB_2U_LIB.S9S_MB_2U(SCH_1):VSENSE_PVCCINFAON_CPU0_DP':
 C_SIGNAL='@s9s_mb_2u_lib.s9s_mb_2u(sch_1):vsense_pvccinfaon_cpu0_dp';
NODE_NAME     U2 CA11
 '@S9S_MB_2U_LIB.S9S_MB_2U(SCH_1):PAGE16_I1@PURE_QUANTA.SOCKET4677_AZIF0045P001C01CS(CHIPS)':
 'VCCINFAON_SENSE': CDS_PINID='VCCINFAON_SENSE';
NODE_NAME     PR521 1
 '@S9S_MB_2U_LIB.S9S_MB_2U(SCH_1):PAGE260_I44@PURE_QUANTA.Q_RES(CHIPS)':
 'A': CDS_PINID='A';
NODE_NAME     PJ45 1
 '@S9S_MB_2U_LIB.S9S_MB_2U(SCH_1):PAGE260_I43@PURE_QUANTA.Q_SHORT(CHIPS)':
 '1': CDS_PINID='\1\';
NET_NAME
'VSENSE_PVCCINFAON_CPU1_DN'
 '@S9S_MB_2U_LIB.S9S_MB_2U(SCH_1):VSENSE_PVCCINFAON_CPU1_DN':
 C_SIGNAL='@s9s_mb_2u_lib.s9s_mb_2u(sch_1):vsense_pvccinfaon_cpu1_dn';
NODE_NAME     U1 CE11
 '@S9S_MB_2U_LIB.S9S_MB_2U(SCH_1):PAGE47_I16@PURE_QUANTA.SOCKET4677_AZIF0045P001C01CS(CHIPS)':
 'VSS_VCCINFAON_SENSE': CDS_PINID='VSS_VCCINFAON_SENSE';
NODE_NAME     PC468 2
 '@S9S_MB_2U_LIB.S9S_MB_2U(SCH_1):PAGE278_I53@PURE_QUANTA.Q_CAP(CHIPS)':
 'B': CDS_PINID='B';
NODE_NAME     PU22 22
 '@S9S_MB_2U_LIB.S9S_MB_2U(SCH_1):PAGE278_I38@PURE_QUANTA.ISL69260IRAZT(CHIPS)':
 'RGND0': CDS_PINID='RGND0';
NODE_NAME     PR566 1
 '@S9S_MB_2U_LIB.S9S_MB_2U(SCH_1):PAGE278_I46@PURE_QUANTA.Q_RES(CHIPS)':
 'A': CDS_PINID='A';
NET_NAME
'VSENSE_PVCCINFAON_CPU1_DP'
 '@S9S_MB_2U_LIB.S9S_MB_2U(SCH_1):VSENSE_PVCCINFAON_CPU1_DP':
 C_SIGNAL='@s9s_mb_2u_lib.s9s_mb_2u(sch_1):vsense_pvccinfaon_cpu1_dp';
NODE_NAME     U1 CA11
 '@S9S_MB_2U_LIB.S9S_MB_2U(SCH_1):PAGE47_I16@PURE_QUANTA.SOCKET4677_AZIF0045P001C01CS(CHIPS)':
 'VCCINFAON_SENSE': CDS_PINID='VCCINFAON_SENSE';
NODE_NAME     PJ50 1
 '@S9S_MB_2U_LIB.S9S_MB_2U(SCH_1):PAGE278_I54@PURE_QUANTA.Q_SHORT(CHIPS)':
 '1': CDS_PINID='\1\';
NODE_NAME     PR568 1
 '@S9S_MB_2U_LIB.S9S_MB_2U(SCH_1):PAGE278_I55@PURE_QUANTA.Q_RES(CHIPS)':
 'A': CDS_PINID='A';
NET_NAME
'VSENSE_PVCCIN_CPU0_DN'
 '@S9S_MB_2U_LIB.S9S_MB_2U(SCH_1):VSENSE_PVCCIN_CPU0_DN':
 C_SIGNAL='@s9s_mb_2u_lib.s9s_mb_2u(sch_1):vsense_pvccin_cpu0_dn';
NODE_NAME     U2 BC90
 '@S9S_MB_2U_LIB.S9S_MB_2U(SCH_1):PAGE16_I1@PURE_QUANTA.SOCKET4677_AZIF0045P001C01CS(CHIPS)':
 'VSS_VCCIN_SENSE': CDS_PINID='VSS_VCCIN_SENSE';
NODE_NAME     PU14 26
 '@S9S_MB_2U_LIB.S9S_MB_2U(SCH_1):PAGE252_I63@PURE_QUANTA.RAA229126GNPHA0(CHIPS)':
 'RGND0': CDS_PINID='RGND0';
NODE_NAME     PC331 2
 '@S9S_MB_2U_LIB.S9S_MB_2U(SCH_1):PAGE252_I79@PURE_QUANTA.Q_CAP(CHIPS)':
 'B': CDS_PINID='B';
NODE_NAME     PR527 1
 '@S9S_MB_2U_LIB.S9S_MB_2U(SCH_1):PAGE252_I26@PURE_QUANTA.Q_RES(CHIPS)':
 'A': CDS_PINID='A';
NET_NAME
'VSENSE_PVCCIN_CPU0_DP'
 '@S9S_MB_2U_LIB.S9S_MB_2U(SCH_1):VSENSE_PVCCIN_CPU0_DP':
 C_SIGNAL='@s9s_mb_2u_lib.s9s_mb_2u(sch_1):vsense_pvccin_cpu0_dp';
NODE_NAME     U2 BD87
 '@S9S_MB_2U_LIB.S9S_MB_2U(SCH_1):PAGE16_I1@PURE_QUANTA.SOCKET4677_AZIF0045P001C01CS(CHIPS)':
 'VCCIN_SENSE': CDS_PINID='VCCIN_SENSE';
NODE_NAME     PR531 1
 '@S9S_MB_2U_LIB.S9S_MB_2U(SCH_1):PAGE252_I38@PURE_QUANTA.Q_RES(CHIPS)':
 'A': CDS_PINID='A';
NODE_NAME     PJ47 1
 '@S9S_MB_2U_LIB.S9S_MB_2U(SCH_1):PAGE252_I37@PURE_QUANTA.Q_SHORT(CHIPS)':
 '1': CDS_PINID='\1\';
NET_NAME
'VSENSE_PVCCIN_CPU1_DN'
 '@S9S_MB_2U_LIB.S9S_MB_2U(SCH_1):VSENSE_PVCCIN_CPU1_DN':
 C_SIGNAL='@s9s_mb_2u_lib.s9s_mb_2u(sch_1):vsense_pvccin_cpu1_dn';
NODE_NAME     U1 BC90
 '@S9S_MB_2U_LIB.S9S_MB_2U(SCH_1):PAGE47_I16@PURE_QUANTA.SOCKET4677_AZIF0045P001C01CS(CHIPS)':
 'VSS_VCCIN_SENSE': CDS_PINID='VSS_VCCIN_SENSE';
NODE_NAME     PC549 2
 '@S9S_MB_2U_LIB.S9S_MB_2U(SCH_1):PAGE270_I64@PURE_QUANTA.Q_CAP(CHIPS)':
 'B': CDS_PINID='B';
NODE_NAME     PU29 26
 '@S9S_MB_2U_LIB.S9S_MB_2U(SCH_1):PAGE270_I33@PURE_QUANTA.RAA229126GNPHA0(CHIPS)':
 'RGND0': CDS_PINID='RGND0';
NODE_NAME     PR574 1
 '@S9S_MB_2U_LIB.S9S_MB_2U(SCH_1):PAGE270_I45@PURE_QUANTA.Q_RES(CHIPS)':
 'A': CDS_PINID='A';
NET_NAME
'VSENSE_PVCCIN_CPU1_DP'
 '@S9S_MB_2U_LIB.S9S_MB_2U(SCH_1):VSENSE_PVCCIN_CPU1_DP':
 C_SIGNAL='@s9s_mb_2u_lib.s9s_mb_2u(sch_1):vsense_pvccin_cpu1_dp';
NODE_NAME     U1 BD87
 '@S9S_MB_2U_LIB.S9S_MB_2U(SCH_1):PAGE47_I16@PURE_QUANTA.SOCKET4677_AZIF0045P001C01CS(CHIPS)':
 'VCCIN_SENSE': CDS_PINID='VCCIN_SENSE';
NODE_NAME     PR578 1
 '@S9S_MB_2U_LIB.S9S_MB_2U(SCH_1):PAGE270_I49@PURE_QUANTA.Q_RES(CHIPS)':
 'A': CDS_PINID='A';
NODE_NAME     PJ52 1
 '@S9S_MB_2U_LIB.S9S_MB_2U(SCH_1):PAGE270_I46@PURE_QUANTA.Q_SHORT(CHIPS)':
 '1': CDS_PINID='\1\';
NET_NAME
'XTAL_CLK_GEN1_25M_X1'
 '@S9S_MB_2U_LIB.S9S_MB_2U(SCH_1):XTAL_CLK_GEN1_25M_X1':
 C_SIGNAL='@s9s_mb_2u_lib.s9s_mb_2u(sch_1):xtal_clk_gen1_25m_x1';
NODE_NAME     U13 A13
 '@S9S_MB_2U_LIB.S9S_MB_2U(SCH_1):PAGE197_I180@PURE_QUANTA.9SQ440NQQI8(CHIPS)':
 'XIN_CLKIN': CDS_PINID='XIN_CLKIN';
NODE_NAME     R1724 2
 '@S9S_MB_2U_LIB.S9S_MB_2U(SCH_1):PAGE197_I392@PURE_QUANTA.Q_RES(CHIPS)':
 'B': CDS_PINID='B';
NET_NAME
'XTAL_CLK_GEN1_25M_X1_R'
 '@S9S_MB_2U_LIB.S9S_MB_2U(SCH_1):XTAL_CLK_GEN1_25M_X1_R':
 C_SIGNAL='@s9s_mb_2u_lib.s9s_mb_2u(sch_1):xtal_clk_gen1_25m_x1_r';
NODE_NAME     Y2 1
 '@S9S_MB_2U_LIB.S9S_MB_2U(SCH_1):PAGE197_I391@PURE_QUANTA.Q_XTAL_4P_13BI_24GND(CHIPS)':
 'X1': CDS_PINID='X1';
NODE_NAME     R1724 1
 '@S9S_MB_2U_LIB.S9S_MB_2U(SCH_1):PAGE197_I392@PURE_QUANTA.Q_RES(CHIPS)':
 'A': CDS_PINID='A';
NODE_NAME     C2036 1
 '@S9S_MB_2U_LIB.S9S_MB_2U(SCH_1):PAGE197_I393@PURE_QUANTA.Q_CAP(CHIPS)':
 'A': CDS_PINID='A';
NET_NAME
'XTAL_CLK_GEN1_25M_X2'
 '@S9S_MB_2U_LIB.S9S_MB_2U(SCH_1):XTAL_CLK_GEN1_25M_X2':
 C_SIGNAL='@s9s_mb_2u_lib.s9s_mb_2u(sch_1):xtal_clk_gen1_25m_x2';
NODE_NAME     U13 B11
 '@S9S_MB_2U_LIB.S9S_MB_2U(SCH_1):PAGE197_I180@PURE_QUANTA.9SQ440NQQI8(CHIPS)':
 'XOUT': CDS_PINID='XOUT';
NODE_NAME     Y2 3
 '@S9S_MB_2U_LIB.S9S_MB_2U(SCH_1):PAGE197_I391@PURE_QUANTA.Q_XTAL_4P_13BI_24GND(CHIPS)':
 'X2': CDS_PINID='X2';
NODE_NAME     C2037 1
 '@S9S_MB_2U_LIB.S9S_MB_2U(SCH_1):PAGE197_I394@PURE_QUANTA.Q_CAP(CHIPS)':
 'A': CDS_PINID='A';
NET_NAME
'XTAL_PCH_25M_IN'
 '@S9S_MB_2U_LIB.S9S_MB_2U(SCH_1):XTAL_PCH_25M_IN':
 C_SIGNAL='@s9s_mb_2u_lib.s9s_mb_2u(sch_1):xtal_pch_25m_in';
NODE_NAME     U4 B23
 '@S9S_MB_2U_LIB.S9S_MB_2U(SCH_1):PAGE171_I78@PURE_QUANTA.EMMITSBURG_REV0P9(CHIPS)':
 'XTAL_IN': CDS_PINID='XTAL_IN';
NODE_NAME     R1720 2
 '@S9S_MB_2U_LIB.S9S_MB_2U(SCH_1):PAGE171_I103@PURE_QUANTA.Q_RES(CHIPS)':
 'B': CDS_PINID='B';
NET_NAME
'XTAL_PCH_25M_IN_R'
 '@S9S_MB_2U_LIB.S9S_MB_2U(SCH_1):XTAL_PCH_25M_IN_R':
 C_SIGNAL='@s9s_mb_2u_lib.s9s_mb_2u(sch_1):xtal_pch_25m_in_r';
NODE_NAME     Y7 1
 '@S9S_MB_2U_LIB.S9S_MB_2U(SCH_1):PAGE171_I75@PURE_QUANTA.Q_XTAL_4P_13BI_24GND(CHIPS)':
 'X1': CDS_PINID='X1';
NODE_NAME     C103 1
 '@S9S_MB_2U_LIB.S9S_MB_2U(SCH_1):PAGE171_I77@PURE_QUANTA.Q_CAP(CHIPS)':
 'A': CDS_PINID='A';
NODE_NAME     R1316 1
 '@S9S_MB_2U_LIB.S9S_MB_2U(SCH_1):PAGE171_I92@PURE_QUANTA.Q_RES(CHIPS)':
 'A': CDS_PINID='A';
NODE_NAME     R1720 1
 '@S9S_MB_2U_LIB.S9S_MB_2U(SCH_1):PAGE171_I103@PURE_QUANTA.Q_RES(CHIPS)':
 'A': CDS_PINID='A';
NET_NAME
'XTAL_PCH_25M_OUT'
 '@S9S_MB_2U_LIB.S9S_MB_2U(SCH_1):XTAL_PCH_25M_OUT':
 C_SIGNAL='@s9s_mb_2u_lib.s9s_mb_2u(sch_1):xtal_pch_25m_out';
NODE_NAME     Y7 3
 '@S9S_MB_2U_LIB.S9S_MB_2U(SCH_1):PAGE171_I75@PURE_QUANTA.Q_XTAL_4P_13BI_24GND(CHIPS)':
 'X2': CDS_PINID='X2';
NODE_NAME     C104 1
 '@S9S_MB_2U_LIB.S9S_MB_2U(SCH_1):PAGE171_I76@PURE_QUANTA.Q_CAP(CHIPS)':
 'A': CDS_PINID='A';
NODE_NAME     U4 D23
 '@S9S_MB_2U_LIB.S9S_MB_2U(SCH_1):PAGE171_I78@PURE_QUANTA.EMMITSBURG_REV0P9(CHIPS)':
 'XTAL_OUT': CDS_PINID='XTAL_OUT';
NODE_NAME     R1316 2
 '@S9S_MB_2U_LIB.S9S_MB_2U(SCH_1):PAGE171_I92@PURE_QUANTA.Q_RES(CHIPS)':
 'B': CDS_PINID='B';
NET_NAME
'XTAL_PCH_RTC1'
 '@S9S_MB_2U_LIB.S9S_MB_2U(SCH_1):XTAL_PCH_RTC1':
 C_SIGNAL='@s9s_mb_2u_lib.s9s_mb_2u(sch_1):xtal_pch_rtc1';
NODE_NAME     Y1 2
 '@S9S_MB_2U_LIB.S9S_MB_2U(SCH_1):PAGE171_I11@PURE_QUANTA.Q_CRYSTAL(CHIPS)':
 '2': CDS_PINID='\2\';
NODE_NAME     C1508 1
 '@S9S_MB_2U_LIB.S9S_MB_2U(SCH_1):PAGE171_I17@PURE_QUANTA.Q_CAP(CHIPS)':
 'A': CDS_PINID='A';
NODE_NAME     R120 2
 '@S9S_MB_2U_LIB.S9S_MB_2U(SCH_1):PAGE171_I74@PURE_QUANTA.Q_RES(CHIPS)':
 'B': CDS_PINID='B';
NODE_NAME     U4 BE6
 '@S9S_MB_2U_LIB.S9S_MB_2U(SCH_1):PAGE171_I78@PURE_QUANTA.EMMITSBURG_REV0P9(CHIPS)':
 'RTCX1': CDS_PINID='RTCX1';
NET_NAME
'XTAL_PCH_RTC2'
 '@S9S_MB_2U_LIB.S9S_MB_2U(SCH_1):XTAL_PCH_RTC2':
 C_SIGNAL='@s9s_mb_2u_lib.s9s_mb_2u(sch_1):xtal_pch_rtc2';
NODE_NAME     U4 BF7
 '@S9S_MB_2U_LIB.S9S_MB_2U(SCH_1):PAGE171_I78@PURE_QUANTA.EMMITSBURG_REV0P9(CHIPS)':
 'RTCX2': CDS_PINID='RTCX2';
NODE_NAME     R1721 2
 '@S9S_MB_2U_LIB.S9S_MB_2U(SCH_1):PAGE171_I104@PURE_QUANTA.Q_RES(CHIPS)':
 'B': CDS_PINID='B';
NET_NAME
'XTAL_PCH_RTC2_R'
 '@S9S_MB_2U_LIB.S9S_MB_2U(SCH_1):XTAL_PCH_RTC2_R':
 C_SIGNAL='@s9s_mb_2u_lib.s9s_mb_2u(sch_1):xtal_pch_rtc2_r';
NODE_NAME     C1507 1
 '@S9S_MB_2U_LIB.S9S_MB_2U(SCH_1):PAGE171_I10@PURE_QUANTA.Q_CAP(CHIPS)':
 'A': CDS_PINID='A';
NODE_NAME     Y1 1
 '@S9S_MB_2U_LIB.S9S_MB_2U(SCH_1):PAGE171_I11@PURE_QUANTA.Q_CRYSTAL(CHIPS)':
 '1': CDS_PINID='\1\';
NODE_NAME     R120 1
 '@S9S_MB_2U_LIB.S9S_MB_2U(SCH_1):PAGE171_I74@PURE_QUANTA.Q_RES(CHIPS)':
 'A': CDS_PINID='A';
NODE_NAME     R1721 1
 '@S9S_MB_2U_LIB.S9S_MB_2U(SCH_1):PAGE171_I104@PURE_QUANTA.Q_RES(CHIPS)':
 'A': CDS_PINID='A';
END.
